FILE_TYPE = MULTI_PHYS_TABLE;

PART 'Q_CAP'

{========================================================================================}
:VALUE      | VOLTAGE | TOLERANCE | PACK_TYPE   | MATERIAL  | PART_NUMBER        = STANDARD        | LIFECYCLE          | ASS_PART | PART_NUMBER      | JEDEC_TYPE                | ALT_SYMBOLS                                                          | VALUE      | RATED_VOLTAGE | TOL      | CLASS      | DESCRIPTION                                                    | COMPONENT_TYPE | LEAD_LENGTH | LPID | DATE       ;
{========================================================================================}
 '1UF'      | '25V'   | '10%'     | '0603'      | 'COG'     | 'TMP_QCH5104K9906'(!) = 'End of Design' | 'Comp-Release Qty' | ''       | 'CH5104K9906'    |'C0603'| '(SMC0603AW)'                                                        | '1UF'      | '25V'         | '10%'    | 'DISCRETE' | 'CHIP0603'                                                     | 'CHIP0603'     | ''          | ''   | ''        
 '1UF'      | '25V'   | '10%'     | '0603'      | 'EMPTY'   | 'TMP_QCH5104K9906'(!) = 'End of Design' | 'Comp-Release Qty' | ''       | 'CH5104K9906'    |'C0603'| '(SMC0603AW)'                                                        | 'NA'       | '25V'         | '10%'    | 'IO'       | 'CHIP0603'                                                     | 'CHIP0603'     | ''          | ''   | ''        
 '0.1UF'    | '25V'   | '10%'     | '0603'      | 'X7R'     | 'TMP_QCH41004K910'(!) = 'End of Design' | 'Comp-Approve'     | ''       | 'CH41004K910'    |'C0603'| '(SMC0603AW)'                                                        | '0.1UF'    | '25V'         | '10%'    | 'DISCRETE' | 'CHIP0603'                                                     | 'CHIP0603'     | ''          | ''   | ''        
 '0.1UF'    | '25V'   | '10%'     | '0603'      | 'EMPTY'   | 'TMP_QCH41004K910'(!) = 'End of Design' | 'Comp-Approve'     | ''       | 'CH41004K910'    |'C0603'| '(SMC0603AW)'                                                        | 'NA'       | '25V'         | '10%'    | 'IO'       | 'CHIP0603'                                                     | 'CHIP0603'     | ''          | ''   | ''        
 '15PF'     | '50V'   | '5%'      | '0603'      | 'X7R'     | 'TMP_QCH0156J0910'(!) = 'End of Design' | 'Comp-Approve'     | ''       | 'CH0156J0910'    |'C0603'| '(SMC0603AW)'                                                        | '15PF'     | '50V'         | '5%'     | 'DISCRETE' | 'CHIP0603'                                                     | 'CHIP0603'     | ''          | ''   | ''        
 '15PF'     | '50V'   | '5%'      | '0603'      | 'EMPTY'   | 'TMP_QCH0156J0910'(!) = 'End of Design' | 'Comp-Approve'     | ''       | 'CH0156J0910'    |'C0603'| '(SMC0603AW)'                                                        | 'NA'       | '50V'         | '5%'     | 'IO'       | 'CHIP0603'                                                     | 'CHIP0603'     | ''          | ''   | ''        
 '3300PF'   | '50V'   | '10%'     | '0402'      | 'X7R'     | 'TMP_QCH2336K1B12'(!) = ''              | ''                 | ''       | 'CH2336K1B12'    |'C0402'| '(C0402-0201)'                                                       | '3300PF'   | '50V'         | '10%'    | 'DISCRETE' | 'CHIP0402'                                                     | 'CHIP0402'     | ''          | ''   | ''        
 '3300PF'   | '50V'   | '10%'     | '0402'      | 'EMPTY'   | 'TMP_QCH2336K1B12'(!) = ''              | ''                 | ''       | 'CH2336K1B12'    |'C0402'| '(C0402-0201)'                                                       | 'NA'       | '50V'         | '10%'    | 'IO'       | 'CHIP0402'                                                     | 'CHIP0402'     | ''          | ''   | ''        
 '10UF'     | '25V'   | '20%'     | '1206'      | 'X6S'     | 'TMP_QCH61004M2E8'(!) = 'End of Design' | 'Comp-Approve'     | ''       | 'CH61004M2E8'    |'C1206_H76'| '(SMC1206AW)'                                                        | '10UF'     | '25V'         | '20%'    | 'DISCRETE' | 'CHIP1206'                                                     | 'CHIP1206'     | ''          | ''   | ''        
 '10UF'     | '25V'   | '20%'     | '1206'      | 'EMPTY'   | 'TMP_QCH61004M2E8'(!) = 'End of Design' | 'Comp-Approve'     | ''       | 'CH61004M2E8'    |'C1206_H76'| '(SMC1206AW)'                                                        | 'NA'       | '25V'         | '20%'    | 'IO'       | 'CHIP1206'                                                     | 'CHIP1206'     | ''          | ''   | ''        
 '1UF'      | '16V'   | '10%'     | '0402'      | 'X5R'     | 'TMP_QCH5103K9B00'(!) = 'End of Design' | 'Comp-Approve'     | ''       | 'CH5103K9B00'    |'C0402'| '(C0402-0201)'                                                       | '1UF'      | '16V'         | '10%'    | 'DISCRETE' | 'CHIP0402'                                                     | 'CHIP0402'     | ''          | ''   | ''        
 '1UF'      | '16V'   | '10%'     | '0402'      | 'EMPTY'   | 'TMP_QCH5103K9B00'(!) = 'End of Design' | 'Comp-Approve'     | ''       | 'CH5103K9B00'    |'C0402'| '(C0402-0201)'                                                       | 'NA'       | '16V'         | '10%'    | 'IO'       | 'CHIP0402'                                                     | 'CHIP0402'     | ''          | ''   | ''        
 '1UF'      | '25V'   | '10%'     | '0805'      | 'X7R'     | 'TMP_QCH51004KE12'(!) = 'End of Design' | 'Comp-Approve'     | ''       | 'CH51004KE12'    |'C0805_H61'| '(SMC0805AW)'                                                        | '1UF'      | '25V'         | '10%'    | 'DISCRETE' | 'CHIP0805'                                                     | 'CHIP0805'     | ''          | ''   | ''        
 '1UF'      | '25V'   | '10%'     | '0805'      | 'EMPTY'   | 'TMP_QCH51004KE12'(!) = 'End of Design' | 'Comp-Approve'     | ''       | 'CH51004KE12'    |'C0805_H61'| '(SMC0805AW)'                                                        | 'NA'       | '25V'         | '10%'    | 'IO'       | 'CHIP0805'                                                     | 'CHIP0805'     | ''          | ''   | ''        
 '1UF'      | '50V'   | '10%'     | '1206'      | 'X7R'     | 'TMP_QCH5106K1200'(!) = 'End of Design' | 'Comp-Approve'     | ''       | 'CH5106K1200'    |'C1206_H56'| '(SMC1206AW)'                                                        | '1UF'      | '50V'         | '10%'    | 'DISCRETE' | 'CHIP1206'                                                     | 'CHIP1206'     | ''          | ''   | ''        
 '1UF'      | '50V'   | '10%'     | '1206'      | 'EMPTY'   | 'TMP_QCH5106K1200'(!) = 'End of Design' | 'Comp-Approve'     | ''       | 'CH5106K1200'    |'C1206_H56'| '(SMC1206AW)'                                                        | 'NA'       | '50V'         | '10%'    | 'IO'       | 'CHIP1206'                                                     | 'CHIP1206'     | ''          | ''   | ''        
 '0.47UF'   | '25V'   | '10%'     | '0805'      | 'X7R'     | 'TMP_QCH44704KE14'(!) = ''              | ''                 | ''       | 'CH44704KE14'    |'C0805_H61'| '(SMC0805AW)'                                                        | '0.47UF'   | '25V'         | '10%'    | 'DISCRETE' | 'CHIP0805'                                                     | 'CHIP0805'     | ''          | ''   | ''        
 '0.47UF'   | '25V'   | '10%'     | '0805'      | 'EMPTY'   | 'TMP_QCH44704KE14'(!) = ''              | ''                 | ''       | 'CH44704KE14'    |'C0805_H61'| '(SMC0805AW)'                                                        | 'NA'       | '25V'         | '10%'    | 'IO'       | 'CHIP0805'                                                     | 'CHIP0805'     | ''          | ''   | ''        
 '0.22UF'   | '25V'   | '20%'     | '0805'      | 'X7R'     | 'TMP_QCH42204ME13'(!) = 'End of Design' | 'Comp-Approve'     | ''       | 'CH5106K1200'    |'C0805_H43'| '(SMC0805AW)'                                                        | '0.22UF'   | '25V'         | '20%'    | 'DISCRETE' | 'CHIP0805'                                                     | 'CHIP0805'     | ''          | ''   | ''        
 '0.22UF'   | '25V'   | '20%'     | '0805'      | 'EMPTY'   | 'TMP_QCH42204ME13'(!) = 'End of Design' | 'Comp-Approve'     | ''       | 'CH5106K1200'    |'C0805_H43'| '(SMC0805AW)'                                                        | 'NA'       | '25V'         | '20%'    | 'IO'       | 'CHIP0805'                                                     | 'CHIP0805'     | ''          | ''   | ''        
 '100PF'    | '50V'   | '10%'     | '0402'      | 'X7R'     | 'TMP_QCH1106K1B00'(!) = 'End of Design' | 'Comp-Approve'     | ''       | 'CH1106K1B00'    |'C0402'| '(C0402-0201)'                                                       | '100PF'    | '50V'         | '10%'    | 'DISCRETE' | 'CHIP0402'                                                     | 'CHIP0402'     | ''          | ''   | ''        
 '100PF'    | '50V'   | '10%'     | '0402'      | 'EMPTY'   | 'TMP_QCH1106K1B00'(!) = 'End of Design' | 'Comp-Approve'     | ''       | 'CH1106K1B00'    |'C0402'| '(C0402-0201)'                                                       | 'NA'       | '50V'         | '10%'    | 'IO'       | 'CHIP0402'                                                     | 'CHIP0402'     | ''          | ''   | ''        
 '150PF'    | '50V'   | '5%'      | '0402'      | 'NPO'     | 'TMP_QCH11506JB08'(!) = ''              | ''                 | ''       | 'CH11506JB08'    |'C0402'| '(C0402-0201)'                                                       | '150PF'    | '50V'         | '5%'     | 'DISCRETE' | 'CHIP0402'                                                     | 'CHIP0402'     | ''          | ''   | ''        
 '150PF'    | '50V'   | '5%'      | '0402'      | 'EMPTY'   | 'TMP_QCH11506JB08'(!) = ''              | ''                 | ''       | 'CH11506JB08'    |'C0402'| '(C0402-0201)'                                                       | 'NA'       | '50V'         | '5%'     | 'IO'       | 'CHIP0402'                                                     | 'CHIP0402'     | ''          | ''   | ''        
 '100PF'    | '50V'   | '5%'      | '0603'      | 'NPO'     | 'TMP_QCH11006J901'(!) = 'End of Design' | 'Comp-Approve'     | ''       | 'CH11006J901'    |'C0603'| '(SMC0603AW)'                                                        | '100PF'    | '50V'         | '5%'     | 'DISCRETE' | 'CHIP0603'                                                     | 'CHIP0603'     | ''          | ''   | ''        
 '100PF'    | '50V'   | '5%'      | '0603'      | 'EMPTY'   | 'TMP_QCH11006J901'(!) = 'End of Design' | 'Comp-Approve'     | ''       | 'CH11006J901'    |'C0603'| '(SMC0603AW)'                                                        | 'NA'       | '50V'         | '5%'     | 'IO'       | 'CHIP0603'                                                     | 'CHIP0603'     | ''          | ''   | ''        
 '220PF'    | '50V'   | '5%'      | '0603'      | 'NPO'     | 'TMP_QCH12206J901'(!) = 'End of Design' | 'Comp-Approve'     | ''       | 'CH12206J901'    |'C0603'| '(SMC0603AW)'                                                        | '220PF'    | '50V'         | '5%'     | 'DISCRETE' | 'CHIP0603'                                                     | 'CHIP0603'     | ''          | ''   | ''        
 '220PF'    | '50V'   | '5%'      | '0603'      | 'EMPTY'   | 'TMP_QCH12206J901'(!) = 'End of Design' | 'Comp-Approve'     | ''       | 'CH12206J901'    |'C0603'| '(SMC0603AW)'                                                        | 'NA'       | '50V'         | '5%'     | 'IO'       | 'CHIP0603'                                                     | 'CHIP0603'     | ''          | ''   | ''        
 '470PF'    | '50V'   | '5%'      | '0603'      | 'NPO'     | 'TMP_QCH14706J904'(!) = 'End of Design' | 'Comp-Release Qty' | ''       | 'CH14706J904'    |'C0603'| '(SMC0603AW)'                                                        | '470PF'    | '50V'         | '5%'     | 'DISCRETE' | 'CHIP0603'                                                     | 'CHIP0603'     | ''          | ''   | ''        
 '470PF'    | '50V'   | '5%'      | '0603'      | 'EMPTY'   | 'TMP_QCH14706J904'(!) = 'End of Design' | 'Comp-Release Qty' | ''       | 'CH14706J904'    |'C0603'| '(SMC0603AW)'                                                        | 'NA'       | '50V'         | '5%'     | 'IO'       | 'CHIP0603'                                                     | 'CHIP0603'     | ''          | ''   | ''        
 '680PF'    | '50V'   | '10%'     | '0603'      | 'X7R'     | 'TMP_QCH16806K918'(!) = ''              | ''                 | ''       | 'CH16806K918'    |'C0603'| '(SMC0603AW)'                                                        | '680PF'    | '50V'         | '10%'    | 'DISCRETE' | 'CHIP0603'                                                     | 'CHIP0603'     | ''          | ''   | ''        
 '680PF'    | '50V'   | '10%'     | '0603'      | 'EMPTY'   | 'TMP_QCH16806K918'(!) = ''              | ''                 | ''       | 'CH16806K918'    |'C0603'| '(SMC0603AW)'                                                        | 'NA'       | '50V'         | '10%'    | 'IO'       | 'CHIP0603'                                                     | 'CHIP0603'     | ''          | ''   | ''        
 '0.022UF'  | '25V'   | '10%'     | '0603'      | 'X7R'     | 'TMP_QCH32204K918'(!) = 'End of Design' | 'Comp-Approve'     | ''       | 'CH32204K918'    |'C0603'| '(SMC0603AW)'                                                        | '0.022UF'  | '25V'         | '10%'    | 'DISCRETE' | 'CHIP0603'                                                     | 'CHIP0603'     | ''          | ''   | ''        
 '0.022UF'  | '25V'   | '10%'     | '0603'      | 'EMPTY'   | 'TMP_QCH32204K918'(!) = 'End of Design' | 'Comp-Approve'     | ''       | 'CH32204K918'    |'C0603'| '(SMC0603AW)'                                                        | 'NA'       | '25V'         | '10%'    | 'IO'       | 'CHIP0603'                                                     | 'CHIP0603'     | ''          | ''   | ''        
 '0.22UF'   | '25V'   | '10%'     | '0603'      | 'X7R'     | 'TMP_QCH4224K1900'(!) = 'End of Design' | 'Comp-Release Qty' | ''       | 'CH4224K1900'    |'C0603'| '(SMC0603AW)'                                                        | '0.22UF'   | '25V'         | '10%'    | 'DISCRETE' | 'CHIP0603'                                                     | 'CHIP0603'     | ''          | ''   | ''        
 '0.22UF'   | '25V'   | '10%'     | '0603'      | 'EMPTY'   | 'TMP_QCH4224K1900'(!) = 'End of Design' | 'Comp-Release Qty' | ''       | 'CH4224K1900'    |'C0603'| '(SMC0603AW)'                                                        | 'NA'       | '25V'         | '10%'    | 'IO'       | 'CHIP0603'                                                     | 'CHIP0603'     | ''          | ''   | ''        
 '10UF'     | '10V'   | '10%'     | '0805'      | 'X7R'     | 'TMP_QCH6102K1A00'(!) = ''              | ''                 | ''       | 'CH6102K1A00'    |'C0805_H61'| '(SMC0805AW)'                                                        | '10UFF'    | '10V'         | '10%'    | 'DISCRETE' | 'CHIP0805'                                                     | 'CHIP0805'     | ''          | ''   | ''        
 '10UF'     | '10V'   | '10%'     | '0805'      | 'EMPTY'   | 'TMP_QCH6102K1A00'(!) = ''              | ''                 | ''       | 'CH6102K1A00'    |'C0805_H61'| '(SMC0805AW)'                                                        | 'NA'       | '10V'         | '10%'    | 'IO'       | 'CHIP0805'                                                     | 'CHIP0805'     | ''          | ''   | ''        
 '10UF'     | '10V'   | '10%'     | '1206'      | 'X5R'     | 'TMP_QCH61002K297'(!) = 'End of Design' | 'Comp-Approve'     | ''       | 'CH61002K297'    |'C1206_H76'| '(SMC1206AW)'                                                        | '10UF'     | '10V'         | '10%'    | 'DISCRETE' | 'CHIP1206'                                                     | 'CHIP1206'     | ''          | ''   | ''        
 '10UF'     | '10V'   | '10%'     | '1206'      | 'EMPTY'   | 'TMP_QCH61002K297'(!) = 'End of Design' | 'Comp-Approve'     | ''       | 'CH61002K297'    |'C1206_H76'| '(SMC1206AW)'                                                        | 'NA'       | '10V'         | '10%'    | 'IO'       | 'CHIP1206'                                                     | 'CHIP1206'     | ''          | ''   | ''        
 '1UF'      | '10V'   | '10%'     | '0603'      | 'X7R'     | 'TMP_QCH5102K1906'(!) = 'End of Design' | 'Comp-Approve'     | ''       | 'CH5102K1906'    |'C0603'| '(SMC0603AW)'                                                        | '1UF'      | '10V'         | '10%'    | 'DISCRETE' | 'CHIP0603'                                                     | 'CHIP0603'     | ''          | ''   | ''        
 '1UF'      | '10V'   | '10%'     | '0603'      | 'EMPTY'   | 'TMP_QCH5102K1906'(!) = 'End of Design' | 'Comp-Approve'     | ''       | 'CH5102K1906'    |'C0603'| '(SMC0603AW)'                                                        | 'NA'       | '10V'         | '10%'    | 'IO'       | 'CHIP0603'                                                     | 'CHIP0603'     | ''          | ''   | ''        
 '47UF'     | '4V'    | '20%'     | '1206'      | 'X6S'     | 'TMP_QCH647KME200'(!) = 'End of Design' | 'Comp-Approve'     | ''       | 'CH647KME200'    |'C1206_H66'| '(SMC1206AW)'                                                        | '47UF'     | '4V'          | '20%'    | 'DISCRETE' | 'CHIP1206'                                                     | 'CHIP1206'     | ''          | ''   | ''        
 '47UF'     | '4V'    | '20%'     | '1206'      | 'EMPTY'   | 'TMP_QCH647KME200'(!) = 'End of Design' | 'Comp-Approve'     | ''       | 'CH647KME200'    |'C1206_H66'| '(SMC1206AW)'                                                        | 'NA'       | '4V'          | '20%'    | 'IO'       | 'CHIP1206'                                                     | 'CHIP1206'     | ''          | ''   | ''        
 '22UF'     | '6.3V'  | '20%'     | '0805'      | 'X5R'     | 'TMP_QCH6221M9A02'(!) = 'End of Design' | 'End of Life'      | ''       | 'CH6221M9A02'    |'C0805_H61_EOL'| '(SMC0805AW)'                                                        | '22UF'     | '6.3V'        | '20%'    | 'DISCRETE' | 'CHIP0805'                                                     | 'CHIP0805'     | ''          | ''   | ''        
 '22UF'     | '6.3V'  | '20%'     | '0805'      | 'EMPTY'   | 'TMP_QCH6221M9A02'(!) = 'End of Design' | 'End of Life'      | ''       | 'CH6221M9A02'    |'C0805_H61_EOL'| '(SMC0805AW)'                                                        | 'NA'       | '6.3V'        | '20%'    | 'IO'       | 'CHIP0805'                                                     | 'CHIP0805'     | ''          | ''   | ''        
 '22UF'     | '6.3V'  | '20%'     | '1206'      | 'X7R'     | 'TMP_QCH6221M1203'(!) = 'End of Design' | 'Comp-Approve'     | ''       | 'CH6221M1203'    |'C1206_H76'| '(SMC1206AW)'                                                        | '22UF'     | '6.3V'        | '20%'    | 'DISCRETE' | 'CHIP1206'                                                     | 'CHIP1206'     | ''          | ''   | ''        
 '22UF'     | '6.3V'  | '20%'     | '1206'      | 'EMPTY'   | 'TMP_QCH6221M1203'(!) = 'End of Design' | 'Comp-Approve'     | ''       | 'CH6221M1203'    |'C1206_H76'| '(SMC1206AW)'                                                        | 'NA'       | '6.3V'        | '20%'    | 'IO'       | 'CHIP1206'                                                     | 'CHIP1206'     | ''          | ''   | ''        
 '22UF'     | '4V'    | '20%'     | '0805'      | 'X6S'     | 'TMP_QCH622KMEA01'(!) = 'End of Design' | 'Comp-Approve'     | ''       | 'CH622KMEA01'    |'C0805_H61'| '(SMC0805AW)'                                                        | '22UF'     | '4V'          | '20%'    | 'DISCRETE' | 'CHIP0805'                                                     | 'CHIP0805'     | ''          | ''   | ''        
 '22UF'     | '4V'    | '20%'     | '0805'      | 'EMPTY'   | 'TMP_QCH622KMEA01'(!) = 'End of Design' | 'Comp-Approve'     | ''       | 'CH622KMEA01'    |'C0805_H61'| '(SMC0805AW)'                                                        | 'NA'       | '4V'          | '20%'    | 'IO'       | 'CHIP0805'                                                     | 'CHIP0805'     | ''          | ''   | ''        
 '0.22UF'   | '16V'   | '10%'     | '0603'      | 'X7R'     | 'TMP_QCH4223K1909'(!) = 'End of Design' | 'Comp-Approve'     | ''       | 'CH4223K1909'    |'C0603'| '(SMC0603AW)'                                                        | '0.22UF'   | '16V'         | '10%'    | 'DISCRETE' | 'CHIP0603'                                                     | 'CHIP0603'     | ''          | ''   | ''        
 '0.22UF'   | '16V'   | '10%'     | '0603'      | 'EMPTY'   | 'TMP_QCH4223K1909'(!) = 'End of Design' | 'Comp-Approve'     | ''       | 'CH4223K1909'    |'C0603'| '(SMC0603AW)'                                                        | 'NA'       | '16V'         | '10%'    | 'IO'       | 'CHIP0603'                                                     | 'CHIP0603'     | ''          | ''   | ''        
 '0.47UF'   | '16V'   | '10%'     | '0603'      | 'X7R'     | 'TMP_QCH4473K1902'(!) = 'End of Design' | 'Comp-Approve'     | ''       | 'CH4473K1902'    |'C0603'| '(SMC0603AW)'                                                        | '0.47UF'   | '16V'         | '10%'    | 'DISCRETE' | 'CHIP0603'                                                     | 'CHIP0603'     | ''          | ''   | ''        
 '0.47UF'   | '16V'   | '10%'     | '0603'      | 'EMPTY'   | 'TMP_QCH4473K1902'(!) = 'End of Design' | 'Comp-Approve'     | ''       | 'CH4473K1902'    |'C0603'| '(SMC0603AW)'                                                        | 'NA'       | '16V'         | '10%'    | 'IO'       | 'CHIP0603'                                                     | 'CHIP0603'     | ''          | ''   | ''        
 '10UF'     | '16V'   | '10%'     | '1206'      | 'X7R'     | 'TMP_QCH6103K1201'(!) = 'End of Design' | 'Comp-Approve'     | ''       | 'CH6103K1201'    |'C1206_H66'| '(SMC1206AW)'                                                        | '10UF'     | '16V'         | '10%'    | 'DISCRETE' | 'CHIP1206'                                                     | 'CHIP1206'     | ''          | ''   | ''        
 '10UF'     | '16V'   | '10%'     | '1206'      | 'EMPTY'   | 'TMP_QCH6103K1201'(!) = 'End of Design' | 'Comp-Approve'     | ''       | 'CH6103K1201'    |'C1206_H66'| '(SMC1206AW)'                                                        | 'NA'       | '16V'         | '10%'    | 'IO'       | 'CHIP1206'                                                     | 'CHIP1206'     | ''          | ''   | ''        
 '2.2UF'    | '16V'   | '10%'     | '0603'      | 'X5R'     | 'TMP_QCH5223K9901'(!) = 'End of Design' | 'Comp-Release Qty' | ''       | 'CH5223K9901'    |'C0603'| '(SMC0603AW)'                                                        | '2.2UF'    | '16V'         | '10%'    | 'DISCRETE' | 'CHIP0603'                                                     | 'CHIP0603'     | ''          | ''   | ''        
 '2.2UF'    | '16V'   | '10%'     | '0603'      | 'EMPTY'   | 'TMP_QCH5223K9901'(!) = 'End of Design' | 'Comp-Release Qty' | ''       | 'CH5223K9901'    |'C0603'| '(SMC0603AW)'                                                        | 'NA'       | '16V'         | '10%'    | 'IO'       | 'CHIP0603'                                                     | 'CHIP0603'     | ''          | ''   | ''        
 '0.22UF'   | '10V'   | '10%'     | '0402'      | 'X5R'     | 'TMP_QCH4222K9B04'(!) = 'End of Design' | 'Comp-Release Qty' | ''       | 'CH4222K9B04'    |'C0402'| '(C0402-0201)'                                                       | '0.22UF'   | '10V'         | '10%'    | 'DISCRETE' | 'CHIP0402'                                                     | 'CHIP0402'     | ''          | ''   | ''        
 '0.22UF'   | '10V'   | '10%'     | '0402'      | 'EMPTY'   | 'TMP_QCH4222K9B04'(!) = 'End of Design' | 'Comp-Release Qty' | ''       | 'CH4222K9B04'    |'C0402'| '(C0402-0201)'                                                       | 'NA'       | '10V'         | '10%'    | 'IO'       | 'CHIP0402'                                                     | 'CHIP0402'     | ''          | ''   | ''        
 '1800PF'   | '50V'   | '10%'     | '0603'      | 'X7R'     | 'TMP_QCH21806K916'(!) = 'End of Design' | 'Comp-Approve'     | ''       | 'CH21806K916'    |'C0603'| '(SMC0603AW)'                                                        | '1800PF'   | '50V'         | '10%'    | 'DISCRETE' | 'CHIP0603'                                                     | 'CHIP0603'     | ''          | ''   | ''        
 '1800PF'   | '50V'   | '10%'     | '0603'      | 'EMPTY'   | 'TMP_QCH21806K916'(!) = 'End of Design' | 'Comp-Approve'     | ''       | 'CH21806K916'    |'C0603'| '(SMC0603AW)'                                                        | 'NA'       | '50V'         | '10%'    | 'IO'       | 'CHIP0603'                                                     | 'CHIP0603'     | ''          | ''   | ''        
 '10PF'     | '50V'   | '1%'      | '0402'      | 'NPO'     | 'TMP_QCH0106F0B00'(!) = ''              | ''                 | ''       | 'CH0106F0B00'    |'C0402'| '(C0402-0201)'                                                       | '10PF'     | '50V'         | '1%'     | 'DISCRETE' | 'CHIP0402'                                                     | 'CHIP0402'     | ''          | ''   | ''        
 '10PF'     | '50V'   | '1%'      | '0402'      | 'EMPTY'   | 'TMP_QCH0106F0B00'(!) = ''              | ''                 | ''       | 'CH0106F0B00'    |'C0402'| '(C0402-0201)'                                                       | 'NA'       | '50V'         | '1%'     | 'IO'       | 'CHIP0402'                                                     | 'CHIP0402'     | ''          | ''   | ''        
 '1000PF'   | '16V'   | '10%'     | '0402'      | 'X7R'     | 'TMP_QCH2103K1B04'(!) = ''              | ''                 | ''       | 'CH2103K1B04'    |'C0402'| '(C0402-0201,C0402_OCTAGONXA)'                                       | '1000PF'   | '16V'         | '10%'    | 'DISCRETE' | 'CHIP0402'                                                     | 'CHIP0402'     | ''          | ''   | ''        
 '1000PF'   | '16V'   | '10%'     | '0402'      | 'EMPTY'   | 'TMP_QCH2103K1B04'(!) = ''              | ''                 | ''       | 'CH2103K1B04'    |'C0402'| '(C0402-0201,C0402_OCTAGONXA)'                                       | 'NA'       | '16V'         | '10%'    | 'IO'       | 'CHIP0402'                                                     | 'CHIP0402'     | ''          | ''   | ''        
 '0.01UF'   | '16V'   | '10%'     | '0402'      | 'X7R'     | 'TMP_QCH31003KB11'(!) = 'End of Design' | 'Comp-Approve'     | ''       | 'CH31003KB11'    |'C0402'| '(C0402-0201)'                                                       | '0.01UF'   | '16V'         | '10%'    | 'DISCRETE' | 'CHIP0402'                                                     | 'CHIP0402'     | ''          | ''   | ''        
 '0.01UF'   | '16V'   | '10%'     | '0402'      | 'EMPTY'   | 'TMP_QCH31003KB11'(!) = 'End of Design' | 'Comp-Approve'     | ''       | 'CH31003KB11'    |'C0402'| '(C0402-0201)'                                                       | 'NA'       | '16V'         | '10%'    | 'IO'       | 'CHIP0402'                                                     | 'CHIP0402'     | ''          | ''   | ''        
 '4.7UF'    | '16V'   | '20%'     | '0805'      | 'X7R'     | 'TMP_QCH5473M1A00'(!) = 'End of Design' | 'Comp-Approve'     | ''       | 'CH5473M1A00'    |'C0805_H61'| '(SMC0805AW)'                                                        | '4.7UF'    | '16V'         | '20%'    | 'DISCRETE' | 'CHIP0805'                                                     | 'CHIP0805'     | ''          | ''   | ''        
 '4.7UF'    | '16V'   | '20%'     | '0805'      | 'EMPTY'   | 'TMP_QCH5473M1A00'(!) = 'End of Design' | 'Comp-Approve'     | ''       | 'CH5473M1A00'    |'C0805_H61'| '(SMC0805AW)'                                                        | 'NA'       | '16V'         | '20%'    | 'IO'       | 'CHIP0805'                                                     | 'CHIP0805'     | ''          | ''   | ''        
 '470PF'    | '50V'   | '10%'     | '0402'      | 'X7R'     | 'TMP_QCH14706KB18'(!) = ''              | ''                 | ''       | 'CH14706KB18'    |'C0402'| '(C0402-0201)'                                                       | '470PF'    | '50V'         | '10%'    | 'DISCRETE' | 'CHIP0402'                                                     | 'CHIP0402'     | ''          | ''   | ''        
 '470PF'    | '50V'   | '10%'     | '0402'      | 'EMPTY'   | 'TMP_QCH14706KB18'(!) = ''              | ''                 | ''       | 'CH14706KB18'    |'C0402'| '(C0402-0201)'                                                       | 'NA'       | '50V'         | '10%'    | 'IO'       | 'CHIP0402'                                                     | 'CHIP0402'     | ''          | ''   | ''        
 '1500PF'   | '50V'   | '10%'     | '0402'      | 'X7R'     | 'TMP_QCH21506KB14'(!) = ''              | ''                 | ''       | 'CH21506KB14'    |'C0402'| '(C0402-0201)'                                                       | '1500PF'   | '50V'         | '10%'    | 'DISCRETE' | 'CHIP0402'                                                     | 'CHIP0402'     | ''          | ''   | ''        
 '1500PF'   | '50V'   | '10%'     | '0402'      | 'EMPTY'   | 'TMP_QCH21506KB14'(!) = ''              | ''                 | ''       | 'CH21506KB14'    |'C0402'| '(C0402-0201)'                                                       | 'NA'       | '50V'         | '10%'    | 'IO'       | 'CHIP0402'                                                     | 'CHIP0402'     | ''          | ''   | ''        
 '22PF'     | '50V'   | '5%'      | '0402'      | 'NPO'     | 'TMP_QCH02206JB08'(!) = ''              | ''                 | ''       | 'CH02206JB08'    |'C0402'| '(C0402-0201)'                                                       | '22PF'     | '50V'         | '5%'     | 'DISCRETE' | 'CHIP0402'                                                     | 'CHIP0402'     | ''          | ''   | ''        
 '22PF'     | '50V'   | '5%'      | '0402'      | 'EMPTY'   | 'TMP_QCH02206JB08'(!) = ''              | ''                 | ''       | 'CH02206JB08'    |'C0402'| '(C0402-0201)'                                                       | 'NA'       | '50V'         | '5%'     | 'IO'       | 'CHIP0402'                                                     | 'CHIP0402'     | ''          | ''   | ''        
 '33PF'     | '50V'   | '5%'      | '0402'      | 'NPO'     | 'TMP_QCH03306JB04'(!) = ''              | ''                 | ''       | 'CH03306JB04'    |'C0402'| '(C0402-0201)'                                                       | '33PF'     | '50V'         | '15%'    | 'DISCRETE' | 'CHIP0402'                                                     | 'CHIP0402'     | ''          | ''   | ''        
 '33PF'     | '50V'   | '5%'      | '0402'      | 'EMPTY'   | 'TMP_QCH03306JB04'(!) = ''              | ''                 | ''       | 'CH03306JB04'    |'C0402'| '(C0402-0201)'                                                       | 'NA'       | '50V'         | '5%'     | 'IO'       | 'CHIP0402'                                                     | 'CHIP0402'     | ''          | ''   | ''        
 '47PF'     | '50V'   | '5%'      | '0402'      | 'NPO'     | 'TMP_QCH04706JB01'(!) = ''              | ''                 | ''       | 'CH04706JB01'    |'C0402'| '(C0402-0201)'                                                       | '47PF'     | '50V'         | '5%'     | 'DISCRETE' | 'CHIP0402'                                                     | 'CHIP0402'     | ''          | ''   | ''        
 '47PF'     | '50V'   | '5%'      | '0402'      | 'EMPTY'   | 'TMP_QCH04706JB01'(!) = ''              | ''                 | ''       | 'CH04706JB01'    |'C0402'| '(C0402-0201)'                                                       | 'NA'       | '50V'         | '5%'     | 'IO'       | 'CHIP0402'                                                     | 'CHIP0402'     | ''          | ''   | ''        
 '680PF'    | '50V'   | '10%'     | '0402'      | 'X7R'     | 'TMP_QCH16806KB17'(!) = ''              | ''                 | ''       | 'CH16806KB17'    |'C0402'| '(C0402-0201)'                                                       | '680PF'    | '50V'         | '10%'    | 'DISCRETE' | 'CAP CHIP 680P 50V(+-10%,X7R,0402)'                            | 'CHIP0402'     | ''          | ''   | ''        
 '680PF'    | '50V'   | '10%'     | '0402'      | 'EMPTY'   | 'TMP_QCH16806KB17'(!) = ''              | ''                 | ''       | 'CH16806KB17'    |'C0402'| '(C0402-0201)'                                                       | 'NA'       | '50V'         | '10%'    | 'IO'       | 'CAP CHIP 680P 50V(+-10%,X7R,0402)'                            | 'CHIP0402'     | ''          | ''   | ''        
 '1UF'      | '10V'   | '10%'     | '0603'      | 'X5R'     | 'TMP_QCH51002K996'(!) = 'End of Design' | 'Comp-Approve'     | ''       | 'CH51002K996'    |'C0603'| '(SMC0603AW)'                                                        | '1UF'      | '10V'         | '10%'    | 'DISCRETE' | 'CHIP0603'                                                     | 'CHIP0603'     | ''          | ''   | ''        
 '1UF'      | '10V'   | '10%'     | '0603'      | 'EMPTY'   | 'TMP_QCH51002K996'(!) = 'End of Design' | 'Comp-Approve'     | ''       | 'CH51002K996'    |'C0603'| '(SMC0603AW)'                                                        | 'NA'       | '10V'         | '10%'    | 'IO'       | 'CHIP0603'                                                     | 'CHIP0603'     | ''          | ''   | ''        
 '10UF'     | '6.3V'  | '10%'     | '0805'      | 'X5R'     | 'TMP_QCH61001ME96'(!) = 'End of Design' | 'Comp-Approve'     | ''       | 'CH61001ME96'    |'C0805_H64'| '(SMC0805AW)'                                                        | '10UF'     | '6.3V'        | '10%'    | 'DISCRETE' | 'CHIP0805'                                                     | 'CHIP0805'     | ''          | ''   | ''        
 '10UF'     | '6.3V'  | '10%'     | '0805'      | 'EMPTY'   | 'TMP_QCH61001ME96'(!) = 'End of Design' | 'Comp-Approve'     | ''       | 'CH61001ME96'    |'C0805_H64'| '(SMC0805AW)'                                                        | 'NA'       | '6.3V'        | '10%'    | 'IO'       | 'CHIP0805'                                                     | 'CHIP0805'     | ''          | ''   | ''        
 '10UF'     | '10V'   | '20%'     | '0805'      | 'X5R'     | 'TMP_QCH6102M9A01'(!) = 'End of Design' | 'Comp-Approve'     | ''       | 'CH6102M9A01'    |'C0805_H64'| '(SMC0805AW)'                                                        | '10UF'     | '10V'         | '20%'    | 'DISCRETE' | 'CAP CHIP 10U,10V(+-20%,X5R,0805)'                             | 'CHIP0805'     | ''          | ''   | ''        
 '10UF'     | '10V'   | '20%'     | '0805'      | 'EMPTY'   | 'TMP_QCH6102M9A01'(!) = 'End of Design' | 'Comp-Approve'     | ''       | 'CH6102M9A01'    |'C0805_H64'| '(SMC0805AW)'                                                        | 'NA'       | '10V'         | '20%'    | 'IO'       | 'CAP CHIP 10U,10V(+-20%,X5R,0805)'                             | 'CHIP0805'     | ''          | ''   | ''        
 '0.1UF'    | '10V'   | '10%'     | '0402'      | 'X5R'     | 'TMP_QCH41002KB93'(!) = 'End of Design' | 'Comp-Approve'     | ''       | 'CH41002KB93'    |'C0402'| '(C0402-0201)'                                                       | '0.1UF'    | '10V'         | '10%'    | 'DISCRETE' | 'CAP CHIP 0.1U 10V(+-10%,X5R,0402)'                            | 'CHIP0402'     | ''          | ''   | ''        
 '0.1UF'    | '10V'   | '10%'     | '0402'      | 'EMPTY'   | 'TMP_QCH41002KB93'(!) = 'End of Design' | 'Comp-Approve'     | ''       | 'CH41002KB93'    |'C0402'| '(C0402-0201)'                                                       | 'NA'       | '10V'         | '10%'    | 'IO'       | 'CAP CHIP 0.1U 10V(+-10%,X5R,0402)'                            | 'CHIP0402'     | ''          | ''   | ''        
 '4.7UF'    | '10V'   | '10%'     | '0805'      | 'X5R'     | 'TMP_QCH5472K9A02'(!) = 'End of Design' | 'Comp-Approve'     | ''       | 'CH5472K9A02'    |'C0805_H61'| '(SMC0805AW)'                                                        | '4.7UF'    | '10V'         | '10%'    | 'DISCRETE' | 'CAP CHIP 4.7U 10V(+-10%,X5R,0805)'                            | 'CHIP0805'     | ''          | ''   | ''        
 '4.7UF'    | '10V'   | '10%'     | '0805'      | 'EMPTY'   | 'TMP_QCH5472K9A02'(!) = 'End of Design' | 'Comp-Approve'     | ''       | 'CH5472K9A02'    |'C0805_H61'| '(SMC0805AW)'                                                        | 'NA'       | '10V'         | '10%'    | 'IO'       | 'CAP CHIP 4.7U 10V(+-10%,X5R,0805)'                            | 'CHIP0805'     | ''          | ''   | ''        
 '6800PF'   | '25V'   | '10%'     | '0402'      | 'X7R'     | 'TMP_QCH26804KB18'(!) = 'End of Design' | 'Comp-Approve'     | ''       | 'CH26804KB18'    |'C0402'| '(C0402-0201)'                                                       | '6800PF'   | '25V'         | '10%'    | 'DISCRETE' | 'CAP CHIP 6800P 25V(+-10% X7R 0402)'                           | 'CHIP0402'     | ''          | ''   | ''        
 '6800PF'   | '25V'   | '10%'     | '0402'      | 'EMPTY'   | 'TMP_QCH26804KB18'(!) = 'End of Design' | 'Comp-Approve'     | ''       | 'CH26804KB18'    |'C0402'| '(C0402-0201)'                                                       | 'NA'       | '25V'         | '10%'    | 'IO'       | 'CAP CHIP 6800P 25V(+-10% X7R 0402)'                           | 'CHIP0402'     | ''          | ''   | ''        
 '4.7UF'    | '4V'    | '20%'     | '0402'      | 'X5R'     | 'TMP_QCH547KM9B00'(!) = 'End of Design' | 'Comp-Approve'     | ''       | 'CH547KM9B00'    |'C0402'| '(C0402-0201)'                                                       | '4.7UF'    | '4V'          | '20%'    | 'DISCRETE' | 'CAP CHIP 4.7U 4V(+-20%,X5R,0402)HF'                           | 'CHIP0402'     | ''          | ''   | ''        
 '4.7UF'    | '4V'    | '20%'     | '0402'      | 'EMPTY'   | 'TMP_QCH547KM9B00'(!) = 'End of Design' | 'Comp-Approve'     | ''       | 'CH547KM9B00'    |'C0402'| '(C0402-0201)'                                                       | 'NA'       | '4V'          | '20%'    | 'IO'       | 'CAP CHIP 4.7U 4V(+-20%,X5R,0402)HF'                           | 'CHIP0402'     | ''          | ''   | ''        
 '2PF'      | '50V'   | '.25PF'   | '0402'      | 'COG'     | 'TMP_QCH-206C0B01'(!) = ''              | ''                 | ''       | 'CH-206C0B01'    |'C0402'| '(C0402-0201)'                                                       | '2PF'      | '50V'         | '.25PF'  | 'DISCRETE' | 'CAP CHIP 2P 50V(+-0.25PF,COG,0402)HI-Q'                       | 'CHIP0402'     | ''          | ''   | ''        
 '2PF'      | '50V'   | '.25PF'   | '0402'      | 'EMPTY'   | 'TMP_QCH-206C0B01'(!) = ''              | ''                 | ''       | 'CH-206C0B01'    |'C0402'| '(C0402-0201)'                                                       | 'NA'       | '50V'         | '.25PF'  | 'IO'       | 'CAP CHIP 2P 50V(+-0.25PF,COG,0402)HI-Q'                       | 'CHIP0402'     | ''          | ''   | ''        
 '5.0PF'    | '50V'   | '.25PF'   | '0402'      | 'COG'     | 'TMP_QCH-5006TB09'(!) = ''              | ''                 | ''       | 'CH-5006TB09'    |'C0402'| '(C0402-0201)'                                                       | '5.0PF'    | '50V'         | '.25PF'  | 'DISCRETE' | 'CAP CHIP 5.0P 50V(+-0.25P,COG,0402)EP'                        | 'CHIP0402'     | ''          | ''   | ''        
 '5.0PF'    | '50V'   | '.25PF'   | '0402'      | 'EMPTY'   | 'TMP_QCH-5006TB09'(!) = ''              | ''                 | ''       | 'CH-5006TB09'    |'C0402'| '(C0402-0201)'                                                       | 'NA'       | '50V'         | '.25PF'  | 'IO'       | 'CAP CHIP 5.0P 50V(+-0.25P,COG,0402)EP'                        | 'CHIP0402'     | ''          | ''   | ''        
 '0.022UF'  | '16V'   | '10%'     | '0402'      | 'X7R'     | 'TMP_QCH32203KB11'(!) = ''              | ''                 | ''       | 'CH32203KB11'    |'C0402'| '(C0402-0201,C0402_OCTAGONXA)'                                       | '0.022UF'  | '16V'         | '10%'    | 'DISCRETE' | 'CAP CHIP 0.022U 16V(+-10%,X7R,0402)'                          | 'CHIP0402'     | ''          | ''   | ''        
 '0.022UF'  | '16V'   | '10%'     | '0402'      | 'EMPTY'   | 'TMP_QCH32203KB11'(!) = ''              | ''                 | ''       | 'CH32203KB11'    |'C0402'| '(C0402-0201,C0402_OCTAGONXA)'                                       | 'NA'       | '16V'         | '10%'    | 'IO'       | 'CAP CHIP 0.022U 16V(+-10%,X7R,0402)'                          | 'CHIP0402'     | ''          | ''   | ''        
 '2.2UF'    | '10V'   | '20%'     | '0402'      | 'X5R'     | 'TMP_QCH5222M9B07'(!) = 'End of Design' | 'Comp-Approve'     | ''       | 'CH5222M9B07'    |'C0402'| '(C0402-0201)'                                                       | '2.2UF'    | '10V'         | '20%'    | 'DISCRETE' | 'CAP CHIP 2.2UF 10V(+-20%,X5R,0402)'                           | 'CHIP0402'     | ''          | ''   | ''        
 '2.2UF'    | '10V'   | '20%'     | '0402'      | 'EMPTY'   | 'TMP_QCH5222M9B07'(!) = 'End of Design' | 'Comp-Approve'     | ''       | 'CH5222M9B07'    |'C0402'| '(C0402-0201)'                                                       | 'NA'       | '10V'         | '20%'    | 'IO'       | 'CAP CHIP 2.2UF 10V(+-20%,X5R,0402)'                           | 'CHIP0402'     | ''          | ''   | ''        
 '10UF'     | '10V'   | '10%'     | '0805'      | 'X5R'     | 'TMP_QCH6102K9A01'(!) = 'End of Design' | 'Comp-Release Qty' | ''       | 'CH6102K9A01'    |'C0805_H61'| '(SMC0805AW)'                                                        | '10UF'     | '10V'         | '10%'    | 'DISCRETE' | 'CAP CHIP 10U 10V(+-10%,X5R,0805)'                             | 'CHIP0805'     | ''          | ''   | ''        
 '10UF'     | '10V'   | '10%'     | '0805'      | 'EMPTY'   | 'TMP_QCH6102K9A01'(!) = 'End of Design' | 'Comp-Release Qty' | ''       | 'CH6102K9A01'    |'C0805_H61'| '(SMC0805AW)'                                                        | 'NA'       | '10V'         | '10%'    | 'IO'       | 'CAP CHIP 10U 10V(+-10%,X5R,0805)'                             | 'CHIP0805'     | ''          | ''   | ''        
 '6.8PF'    | '50V'   | '0.5P'    | '0402'      | 'NPO'     | 'TMP_QCH-6806TB01'(!) = ''              | ''                 | ''       | 'CH-6806TB01'    |'C0402'| '(C0402-0201)'                                                       | '6.8PF'    | '50V'         | '0.5P'   | 'DISCRETE' | 'CAP CHIP 6.8P 50V(+-0.5P 0402 NPO)'                           | 'CHIP0402'     | ''          | ''   | ''        
 '6.8PF'    | '50V'   | '0.5P'    | '0402'      | 'EMPTY'   | 'TMP_QCH-6806TB01'(!) = ''              | ''                 | ''       | 'CH-6806TB01'    |'C0402'| '(C0402-0201)'                                                       | 'NA'       | '50V'         | '0.5P'   | 'IO'       | 'CAP CHIP 6.8P 50V(+-0.5P 0402 NPO)'                           | 'CHIP0402'     | ''          | ''   | ''        
 '4700PF'   | '50V'   | '10%'     | '0402'      | 'X7R'     | 'TMP_QCH2476K1B00'(!) = ''              | ''                 | ''       | 'CH2476K1B00'    |'C0402'| '(C0402-0201,C0402_OCTAGONXA)'                                       | '4700PF'   | '50V'         | '10%'    | 'DISCRETE' | 'CAP CHIP 4700PF 50V(10%,X7R,0402)'                            | 'CHIP0402'     | ''          | ''   | ''        
 '4700PF'   | '50V'   | '10%'     | '0402'      | 'EMPTY'   | 'TMP_QCH2476K1B00'(!) = ''              | ''                 | ''       | 'CH2476K1B00'    |'C0402'| '(C0402-0201,C0402_OCTAGONXA)'                                       | 'NA'       | '50V'         | '10%'    | 'IO'       | 'CAP CHIP 4700PF 50V(10%,X7R,0402)'                            | 'CHIP0402'     | ''          | ''   | ''        
 '1200PF'   | '50V'   | '10%'     | '0402'      | 'X7R'     | 'TMP_QCH21206KB13'(!) = 'End of Design' | 'End of Life'      | ''       | 'CH21206KB13'    |'C0402_EOL'| '(C0402-0201)'                                                       | '1200PF'   | '50V'         | '10%'    | 'DISCRETE' | 'CAP CHIP 1200P 50V(+-10%,X7R,0402)'                           | 'CHIP0402'     | ''          | ''   | ''        
 '1200PF'   | '50V'   | '10%'     | '0402'      | 'EMPTY'   | 'TMP_QCH21206KB13'(!) = 'End of Design' | 'End of Life'      | ''       | 'CH21206KB13'    |'C0402_EOL'| '(C0402-0201)'                                                       | 'NA'       | '50V'         | '10%'    | 'IO'       | 'CAP CHIP 1200P 50V(+-10%,X7R,0402)'                           | 'CHIP0402'     | ''          | ''   | ''        
 '2.2UF'    | '6.3V'  | '10%'     | '0603'      | 'X7R'     | 'TMP_QCH5221K1900'(!) = 'End of Design' | 'Comp-Approve'     | ''       | 'CH5221K1900'    |'C0603'| '(SMC0603AW)'                                                        | '2.2UF'    | '6.3V'        | '10%'    | 'DISCRETE' | 'CAP CHIP 2.2UF 6.3V(+-10%,X7R,0603)'                          | 'CHIP0603'     | ''          | ''   | ''        
 '2.2UF'    | '6.3V'  | '10%'     | '0603'      | 'EMPTY'   | 'TMP_QCH5221K1900'(!) = 'End of Design' | 'Comp-Approve'     | ''       | 'CH5221K1900'    |'C0603'| '(SMC0603AW)'                                                        | 'NA'       | '6.3V'        | '10%'    | 'IO'       | 'CAP CHIP 2.2UF 6.3V(+-10%,X7R,0603)'                          | 'CHIP0603'     | ''          | ''   | ''        
 '10UF'     | '25V'   | '10%'     | '1206'      | 'X7R'     | 'TMP_QCH6104K1206'(!) = 'End of Design' | 'Comp-Approve'     | ''       | 'CH6104K1206'    |'C1206_H76'| '(SMC1206AW)'                                                        | '10UF'     | '25V'         | '10%'    | 'DISCRETE' | 'CAP CHIP 10U,25V(+-10%,X7R,1206)H1.6'                         | 'CHIP1206'     | ''          | ''   | ''        
 '10UF'     | '25V'   | '10%'     | '1206'      | 'EMPTY'   | 'TMP_QCH6104K1206'(!) = 'End of Design' | 'Comp-Approve'     | ''       | 'CH6104K1206'    |'C1206_H76'| '(SMC1206AW)'                                                        | 'NA'       | '25V'         | '10%'    | 'IO'       | 'CAP CHIP 10U,25V(+-10%,X7R,1206)H1.6'                         | 'CHIP1206'     | ''          | ''   | ''        
 '2700PF'   | '50V'   | '10%'     | '0402'      | 'X7R'     | 'TMP_QCH22706KB14'(!) = ''              | ''                 | ''       | 'CH22706KB14'    |'C0402'| '(C0402-0201)'                                                       | '2700PF'   | '50V'         | '10%'    | 'DISCRETE' | 'CAP CHIP 2700P 50V(+-10%,X7R,0402)'                           | 'CHIP0402'     | ''          | ''   | ''        
 '2700PF'   | '50V'   | '10%'     | '0402'      | 'EMPTY'   | 'TMP_QCH22706KB14'(!) = ''              | ''                 | ''       | 'CH22706KB14'    |'C0402'| '(C0402-0201)'                                                       | 'NA'       | '50V'         | '10%'    | 'IO'       | 'CAP CHIP 2700P 50V(+-10%,X7R,0402)'                           | 'CHIP0402'     | ''          | ''   | ''        
 '4.7UF'    | '6.3V'  | '10%'     | '0603'      | 'X6S'     | 'TMP_QCH5471KE901'(!) = 'End of Design' | 'Comp-Approve'     | ''       | 'CH5471KE901'    |'C0603'| '(SMC0603AW)'                                                        | '4.7UF'    | '6.3V'        | '10%'    | 'DISCRETE' | 'CAP CHIP 4.7U 6.3V(+-10%,X6S,0603)'                           | 'CHIP0603'     | ''          | ''   | ''        
 '4.7UF'    | '6.3V'  | '10%'     | '0603'      | 'EMPTY'   | 'TMP_QCH5471KE901'(!) = 'End of Design' | 'Comp-Approve'     | ''       | 'CH5471KE901'    |'C0603'| '(SMC0603AW)'                                                        | 'NA'       | '6.3V'        | '10%'    | 'IO'       | 'CAP CHIP 4.7U 6.3V(+-10%,X6S,0603)'                           | 'CHIP0603'     | ''          | ''   | ''        
 '4.7UF'    | '6.3V'  | '10%'     | '0805'      | 'X7R'     | 'TMP_QCH5471K1A00'(!) = 'End of Design' | 'Comp-Approve'     | ''       | 'CH5471K1A00'    |'C0805_H61'| '(SMC0805AW)'                                                        | '4.7UF'    | '6.3V'        | '10%'    | 'DISCRETE' | 'CAP CHIP 4.7UF 6.3V(+-10%,X7R,0805)H1.25'                     | 'CHIP0805'     | ''          | ''   | ''        
 '4.7UF'    | '6.3V'  | '10%'     | '0805'      | 'EMPTY'   | 'TMP_QCH5471K1A00'(!) = 'End of Design' | 'Comp-Approve'     | ''       | 'CH5471K1A00'    |'C0805_H61'| '(SMC0805AW)'                                                        | 'NA'       | '6.3V'        | '10%'    | 'IO'       | 'CAP CHIP 4.7UF 6.3V(+-10%,X7R,0805)H1.25'                     | 'CHIP0805'     | ''          | ''   | ''        
 '10UF'     | '25V'   | '10%'     | '0805'      | 'X5R'     | 'TMP_QCH6104K9A00'(!) = 'End of Design' | 'Comp-Release Qty' | ''       | 'CH6104K9A00'    |'C0805_H61'| '(SMC0805AW)'                                                        | '10UF'     | '25V'         | '10%'    | 'DISCRETE' | 'CAP CHIP 10U 25V(+-10%,X5R,0805,H1.25)'                       | 'CHIP0805'     | ''          | ''   | ''        
 '10UF'     | '25V'   | '10%'     | '0805'      | 'EMPTY'   | 'TMP_QCH6104K9A00'(!) = 'End of Design' | 'Comp-Release Qty' | ''       | 'CH6104K9A00'    |'C0805_H61'| '(SMC0805AW)'                                                        | 'NA'       | '25V'         | '10%'    | 'IO'       | 'CAP CHIP 10U 25V(+-10%,X5R,0805,H1.25)'                       | 'CHIP0805'     | ''          | ''   | ''        
 '56PF'     | '50V'   | '5%'      | '0402'      | 'NPO'     | 'TMP_QCH05606JB01'(!) = ''              | ''                 | ''       | 'CH05606JB01'    |'C0402'| '(C0402-0201)'                                                       | '56PF'     | '50V'         | '5%'     | 'DISCRETE' | 'CAP CHIP 56P 50V(+-5%,NPO,0402)'                              | 'CHIP0402'     | ''          | ''   | ''        
 '56PF'     | '50V'   | '5%'      | '0402'      | 'EMPTY'   | 'TMP_QCH05606JB01'(!) = ''              | ''                 | ''       | 'CH05606JB01'    |'C0402'| '(C0402-0201)'                                                       | 'NA'       | '50V'         | '5%'     | 'IO'       | 'CAP CHIP 56P 50V(+-5%,NPO,0402)'                              | 'CHIP0402'     | ''          | ''   | ''        
 '220PF'    | '50V'   | '10%'     | '0402'      | 'X7R'     | 'TMP_QCH12206KB14'(!) = ''              | ''                 | ''       | 'CH12206KB14'    |'C0402'| '(C0402-0201)'                                                       | '220PF'    | '50V'         | '10%'    | 'DISCRETE' | 'CAP CHIP 220P 50V(+-10%,X7R,0402)'                            | 'CHIP0402'     | ''          | ''   | ''        
 '220PF'    | '50V'   | '10%'     | '0402'      | 'EMPTY'   | 'TMP_QCH12206KB14'(!) = ''              | ''                 | ''       | 'CH12206KB14'    |'C0402'| '(C0402-0201)'                                                       | 'NA'       | '50V'         | '10%'    | 'IO'       | 'CAP CHIP 220P 50V(+-10%,X7R,0402)'                            | 'CHIP0402'     | ''          | ''   | ''        
 '2200PF'   | '50V'   | '10%'     | '0402'      | 'X7R'     | 'TMP_QCH22206KB16'(!) = ''              | ''                 | ''       | 'CH22206KB16'    |'C0402'| '(C0402-0201)'                                                       | '2200PF'   | '50V'         | '10%'    | 'DISCRETE' | 'CAP CHIP 2200P 50V(+-10%,X7R,0402)'                           | 'CHIP0402'     | ''          | ''   | ''        
 '2200PF'   | '50V'   | '10%'     | '0402'      | 'EMPTY'   | 'TMP_QCH22206KB16'(!) = ''              | ''                 | ''       | 'CH22206KB16'    |'C0402'| '(C0402-0201)'                                                       | 'NA'       | '50V'         | '10%'    | 'IO'       | 'CAP CHIP 2200P 50V(+-10%,X7R,0402)'                           | 'CHIP0402'     | ''          | ''   | ''        
 '4700PF'   | '25V'   | '10%'     | '0402'      | 'X7R'     | 'TMP_QCH24704KB19'(!) = ''              | ''                 | ''       | 'CH24704KB19'    |'C0402'| '(C0402-0201)'                                                       | '4700PF'   | '25V'         | '10%'    | 'DISCRETE' | 'CAP CHIP 4700P 25V(+-10%,X7R,0402)'                           | 'CHIP0402'     | ''          | ''   | ''        
 '4700PF'   | '25V'   | '10%'     | '0402'      | 'EMPTY'   | 'TMP_QCH24704KB19'(!) = ''              | ''                 | ''       | 'CH24704KB19'    |'C0402'| '(C0402-0201)'                                                       | 'NA'       | '25V'         | '10%'    | 'IO'       | 'CAP CHIP 4700P 25V(+-10%,X7R,0402)'                           | 'CHIP0402'     | ''          | ''   | ''        
 '0.47UF'   | '6.3V'  | '10%'     | '0402'      | 'X5R'     | 'TMP_QCH4471K9B03'(!) = 'End of Design' | 'Comp-Release Qty' | ''       | 'CH4471K9B03'    |'C0402'| '(C0402-0201)'                                                       | '0.47UF'   | '6.3V'        | '10%'    | 'DISCRETE' | 'CAP CHIP 0.47U 6.3V(+-10%,X5R,0402)'                          | 'CHIP0402'     | ''          | ''   | ''        
 '0.47UF'   | '6.3V'  | '10%'     | '0402'      | 'EMPTY'   | 'TMP_QCH4471K9B03'(!) = 'End of Design' | 'Comp-Release Qty' | ''       | 'CH4471K9B03'    |'C0402'| '(C0402-0201)'                                                       | 'NA'       | '6.3V'        | '10%'    | 'IO'       | 'CAP CHIP 0.47U 6.3V(+-10%,X5R,0402)'                          | 'CHIP0402'     | ''          | ''   | ''        
 '0.47UF'   | '10V'   | '10%'     | '0402'      | 'X5R'     | 'TMP_QCH4472K9B00'(!) = ''              | ''                 | ''       | 'CH4472K9B00'    |'C0402'| '(C0402-0201)'                                                       | '0.47UF'   | '10V'         | '10%'    | 'DISCRETE' | 'CAP CHIP 0.47UF 10V(+-10%,X5R,0402)'                          | 'CHIP0402'     | ''          | ''   | ''        
 '0.47UF'   | '10V'   | '10%'     | '0402'      | 'EMPTY'   | 'TMP_QCH4472K9B00'(!) = ''              | ''                 | ''       | 'CH4472K9B00'    |'C0402'| '(C0402-0201)'                                                       | 'NA'       | '10V'         | '10%'    | 'IO'       | 'CAP CHIP 0.47UF 10V(+-10%,X5R,0402)'                          | 'CHIP0402'     | ''          | ''   | ''        
 '4.7UF'    | '6.3V'  | '20%'     | '0603'      | 'X5R'     | 'TMP_QCH5471M9907'(!) = 'End of Design' | 'Comp-Approve'     | ''       | 'CH5471M9907'    |'C0603'| '(SMC0603AW)'                                                        | '4.7UF'    | '6.3V'        | '20%'    | 'DISCRETE' | 'CAP CHIP 4.7U 6.3V(+-20%,X5R,0603)'                           | 'CHIP0603'     | ''          | ''   | ''        
 '4.7UF'    | '6.3V'  | '20%'     | '0603'      | 'EMPTY'   | 'TMP_QCH5471M9907'(!) = 'End of Design' | 'Comp-Approve'     | ''       | 'CH5471M9907'    |'C0603'| '(SMC0603AW)'                                                        | 'NA'       | '6.3V'        | '20%'    | 'IO'       | 'CAP CHIP 4.7U 6.3V(+-20%,X5R,0603)'                           | 'CHIP0603'     | ''          | ''   | ''        
 '10UF'     | '4V'    | '20%'     | '0603'      | 'X5R'     | 'TMP_QCH610KM9905'(!) = 'End of Design' | 'Comp-Approve'     | ''       | 'CH610KM9905'    |'C0603'| '(SMC0603AW)'                                                        | '10UF'     | '4V'          | '20%'    | 'DISCRETE' | 'CAP CHIP 10U,4V(+-20%,X5R,0603)'                              | 'CHIP0603'     | ''          | ''   | ''        
 '10UF'     | '4V'    | '20%'     | '0603'      | 'EMPTY'   | 'TMP_QCH610KM9905'(!) = 'End of Design' | 'Comp-Approve'     | ''       | 'CH610KM9905'    |'C0603'| '(SMC0603AW)'                                                        | 'NA'       | '4V'          | '20%'    | 'IO'       | 'CAP CHIP 10U,4V(+-20%,X5R,0603)'                              | 'CHIP0603'     | ''          | ''   | ''        
 '0.33UF'   | '16V'   | '10%'     | '0603'      | 'X7R'     | 'TMP_QCH4333K1905'(!) = 'End of Design' | 'Comp-Approve'     | ''       | 'CH4333K1905'    |'C0603'| '(SMC0603AW)'                                                        | '0.33UF'   | '16V'         | '10%'    | 'DISCRETE' | 'CAP CHIP 0.33UF 16V(+-10%,X7R,0603)'                          | 'CHIP0603'     | ''          | ''   | ''        
 '0.33UF'   | '16V'   | '10%'     | '0603'      | 'EMPTY'   | 'TMP_QCH4333K1905'(!) = 'End of Design' | 'Comp-Approve'     | ''       | 'CH4333K1905'    |'C0603'| '(SMC0603AW)'                                                        | 'NA'       | '16V'         | '10%'    | 'IO'       | 'CAP CHIP 0.33UF 16V(+-10%,X7R,0603)'                          | 'CHIP0603'     | ''          | ''   | ''        
 '0.1UF'    | '10V'   | '10%'     | '0402'      | 'X7R'     | 'TMP_QCH4102K1B03'(!) = 'End of Design' | 'Comp-Approve'     | ''       | 'CH4102K1B03'    |'C0402'| '(C0402-0201)'                                                       | '0.1UF'    | '10V'         | '10%'    | 'DISCRETE' | 'CAP CHIP 0.1U 10V(+-10%,X7R,0402)'                            | 'CHIP0402'     | ''          | ''   | ''        
 '0.1UF'    | '10V'   | '10%'     | '0402'      | 'EMPTY'   | 'TMP_QCH4102K1B03'(!) = 'End of Design' | 'Comp-Approve'     | ''       | 'CH4102K1B03'    |'C0402'| '(C0402-0201)'                                                       | 'NA'       | '10V'         | '10%'    | 'IO'       | 'CAP CHIP 0.1U 10V(+-10%,X7R,0402)'                            | 'CHIP0402'     | ''          | ''   | ''        
 '1UF'      | '6.3V'  | '20%'     | '0402'      | 'X5R'     | 'TMP_QCH5101M9B02'(!) = 'End of Design' | 'Comp-Approve'     | ''       | 'CH5101M9B02'    |'C0402'| '(C0402-0201)'                                                       | '1UF'      | '6.3V'        | '20%'    | 'DISCRETE' | 'CAP CHIP 1U 6.3V(+-20%,X5R,0402)'                             | 'CHIP0402'     | ''          | ''   | ''        
 '1UF'      | '6.3V'  | '20%'     | '0402'      | 'EMPTY'   | 'TMP_QCH5101M9B02'(!) = 'End of Design' | 'Comp-Approve'     | ''       | 'CH5101M9B02'    |'C0402'| '(C0402-0201)'                                                       | 'NA'       | '6.3V'        | '20%'    | 'IO'       | 'CAP CHIP 1U 6.3V(+-20%,X5R,0402)'                             | 'CHIP0402'     | ''          | ''   | ''        
 '0.1UF'    | '25V'   | '10%'     | '0402'      | 'X5R'     | 'TMP_QCH4104K9B03'(!) = 'End of Design' | 'Comp-Approve'     | ''       | 'CH4104K9B03'    |'C0402'| '(C0402-0201)'                                                       | '0.1UF'    | '25V'         | '10%'    | 'DISCRETE' | 'CAP CHIP 0.1U 25V(10%,X5R,0402)'                              | 'CHIP0402'     | ''          | ''   | ''        
 '0.1UF'    | '25V'   | '10%'     | '0402'      | 'EMPTY'   | 'TMP_QCH4104K9B03'(!) = 'End of Design' | 'Comp-Approve'     | ''       | 'CH4104K9B03'    |'C0402'| '(C0402-0201)'                                                       | 'NA'       | '25V'         | '10%'    | 'IO'       | 'CAP CHIP 0.1U 25V(10%,X5R,0402)'                              | 'CHIP0402'     | ''          | ''   | ''        
 '47UF'     | '4V'    | '20%'     | '0805'      | 'X5R'     | 'TMP_QCH647KM9A00'(!) = 'End of Design' | 'Comp-Approve'     | ''       | 'CH647KM9A00'    |'C0805_H61'| '(SMC0805AW)'                                                        | '47UF'     | '4V'          | '20%'    | 'DISCRETE' | 'CAP CHIP 47U 4V(+-20%,X5R,0805)H1.25'                         | 'CHIP0805'     | ''          | ''   | ''        
 '47UF'     | '4V'    | '20%'     | '0805'      | 'EMPTY'   | 'TMP_QCH647KM9A00'(!) = 'End of Design' | 'Comp-Approve'     | ''       | 'CH647KM9A00'    |'C0805_H61'| '(SMC0805AW)'                                                        | 'NA'       | '4V'          | '20%'    | 'IO'       | 'CAP CHIP 47U 4V(+-20%,X5R,0805)H1.25'                         | 'CHIP0805'     | ''          | ''   | ''        
 '47UF'     | '4V'    | '20%'     | '0805_FAC'  | 'X5R'     | 'CH647KM9A00'(!)   = 'End of Design' | 'Comp-Approve'     | ''       | 'CH647KM9A00'    |'C0805_H61'| '(SMC0805AW)'                                                        | '47UF'     | '4V'          | '20%'    | 'DISCRETE' | 'CAP CHIP 47U 4V(+-20%,X5R,0805)H1.25_FOR FAC ONLY'            | 'CHIP0805'     | ''          | ''   | '20100813'
 '47UF'     | '4V'    | '20%'     | '0805_FAC'  | 'EMPTY'   | 'CH647KM9A00'(!)   = 'End of Design' | 'Comp-Approve'     | ''       | 'CH647KM9A00'    |'C0805_H61'| '(SMC0805AW)'                                                        | 'NA'       | '4V'          | '20%'    | 'IO'       | 'CAP CHIP 47U 4V(+-20%,X5R,0805)H1.25_FOR FAC ONLY'            | 'CHIP0805'     | ''          | ''   | '20100813'
 '100UF'    | '6.3V'  | '20%'     | '1206'      | 'X5R'     | 'TMP_QCH7101M9200'(!) = 'End of Design' | 'Comp-Release Qty' | ''       | 'CH7101M9200'    |'C1206_H66'| '(SMC1206AW)'                                                        | '100UF'    | '6.3V'        | '20%'    | 'DISCRETE' | 'CAP CHIP 100U 6.3V(+-20%,X5R,1206)H1.6'                       | 'CHIP1206'     | ''          | ''   | ''        
 '100UF'    | '6.3V'  | '20%'     | '1206'      | 'EMPTY'   | 'TMP_QCH7101M9200'(!) = 'End of Design' | 'Comp-Release Qty' | ''       | 'CH7101M9200'    |'C1206_H66'| '(SMC1206AW)'                                                        | 'NA'       | '6.3V'        | '20%'    | 'IO'       | 'CAP CHIP 100U 6.3V(+-20%,X5R,1206)H1.6'                       | 'CHIP1206'     | ''          | ''   | ''        
 '47UF'     | '6.3V'  | '20%'     | '1206'      | 'X5R'     | 'TMP_QCH6471M9208'(!) = 'End of Design' | 'Comp-Approve'     | ''       | 'CH6471M9208'    |'C1206_H66'| '(SMC1206AW)'                                                        | '47UF'     | '6.3V'        | '20%'    | 'DISCRETE' | 'CAP CHIP 47U 6.3V(+-20%,X5R,1206)'                            | 'CHIP1206'     | ''          | ''   | ''        
 '47UF'     | '6.3V'  | '20%'     | '1206'      | 'EMPTY'   | 'TMP_QCH6471M9208'(!) = 'End of Design' | 'Comp-Approve'     | ''       | 'CH6471M9208'    |'C1206_H66'| '(SMC1206AW)'                                                        | 'NA'       | '6.3V'        | '20%'    | 'IO'       | 'CAP CHIP 47U 6.3V(+-20%,X5R,1206)'                            | 'CHIP1206'     | ''          | ''   | ''        
 '1UF'      | '10V'   | '10%'     | '0402'      | 'X7R'     | 'TMP_QCH5102K1B05'(!) = 'End of Design' | 'Comp-Approve'     | ''       | 'CH5102K1B05'    |'C0402'| '(C0402-0201)'                                                       | '1UF'      | '10V'         | '10%'    | 'DISCRETE' | 'CAP CHIP 1U,10V(+-10%,X7R,0402)'                              | 'CHIP0402'     | ''          | ''   | ''        
 '1UF'      | '10V'   | '10%'     | '0402'      | 'EMPTY'   | 'TMP_QCH5102K1B05'(!) = 'End of Design' | 'Comp-Approve'     | ''       | 'CH5102K1B05'    |'C0402'| '(C0402-0201)'                                                       | 'NA'       | '10V'         | '10%'    | 'IO'       | 'CAP CHIP 1U,10V(+-10%,X7R,0402)'                              | 'CHIP0402'     | ''          | ''   | ''        
 '0.047UF'  | '16V'   | '10%'     | '0603'      | 'X7R'     | 'TMP_QCH34703K916'(!) = ''              | ''                 | ''       | 'CH34703K916'    |'C0603'| '(SMC0603AW)'                                                        | '0.047UF'  | '16V'         | '10%'    | 'DISCRETE' | 'CAP CHIP 0.047UF 16V(+-10%,X7R,0603)'                         | 'CHIP0603'     | ''          | ''   | ''        
 '0.047UF'  | '16V'   | '10%'     | '0603'      | 'EMPTY'   | 'TMP_QCH34703K916'(!) = ''              | ''                 | ''       | 'CH34703K916'    |'C0603'| '(SMC0603AW)'                                                        | 'NA'       | '16V'         | '10%'    | 'IO'       | 'CAP CHIP 0.047UF 16V(+-10%,X7R,0603)'                         | 'CHIP0603'     | ''          | ''   | ''        
 '1UF'      | '10V'   | '20%'     | '0402'      | 'X5R'     | 'TMP_QCH5102M9B07'(!) = 'End of Design' | 'Comp-Approve'     | ''       | 'CH5102M9B07'    |'C0402'| '(C0402-0201)'                                                       | '1UF'      | '10V'         | '20%'    | 'DISCRETE' | 'CAP CHIP 1U 10V(+-20%,X5R,0402)H:0.5'                         | 'CHIP0402'     | ''          | ''   | ''        
 '1UF'      | '10V'   | '20%'     | '0402'      | 'EMPTY'   | 'TMP_QCH5102M9B07'(!) = 'End of Design' | 'Comp-Approve'     | ''       | 'CH5102M9B07'    |'C0402'| '(C0402-0201)'                                                       | 'NA'       | '10V'         | '20%'    | 'IO'       | 'CAP CHIP 1U 10V(+-20%,X5R,0402)H:0.5'                         | 'CHIP0402'     | ''          | ''   | ''        
 '22UF'     | '10V'   | '20%'     | '0805'      | 'X5R'     | 'TMP_QCH6222M9A01'(!) = ''              | 'End of Life'      | ''       | 'CH6222M9A01'    |'C0805_H61_EOL'| '(SMC0805AW)'                                                        | '22UF'     | '10V'         | '20%'    | 'DISCRETE' | 'CAP CHIP 22U 10V(+-20%,X5R,0805)'                             | 'CHIP0805'     | ''          | ''   | '20100527'
 '22UF'     | '10V'   | '20%'     | '0805'      | 'EMPTY'   | 'TMP_QCH6222M9A01'(!) = ''              | 'End of Life'      | ''       | 'CH6222M9A01'    |'C0805_H61_EOL'| '(SMC0805AW)'                                                        | 'NA'       | '10V'         | '20%'    | 'IO'       | 'CAP CHIP 22U 10V(+-20%,X5R,0805)'                             | 'CHIP0805'     | ''          | ''   | '20100527'
 '47UF'     | '6.3V'  | '20%'     | '0805'      | 'X5R'     | 'TMP_QCH6471M9A00'(!) = ''              | ''                 | ''       | 'CH6471M9A00'    |'C0805_H61'| '(SMC0805AW)'                                                        | '47UF'     | '6.3V'        | '20%'    | 'DISCRETE' | 'CAP CHIP 47U 6.3V(+-20%,X5R,0805)'                            | 'CHIP0805'     | ''          | ''   | '20100527'
 '47UF'     | '6.3V'  | '20%'     | '0805'      | 'EMPTY'   | 'TMP_QCH6471M9A00'(!) = ''              | ''                 | ''       | 'CH6471M9A00'    |'C0805_H61'| '(SMC0805AW)'                                                        | 'NA'       | '6.3V'        | '20%'    | 'IO'       | 'CAP CHIP 47U 6.3V(+-20%,X5R,0805)'                            | 'CHIP0805'     | ''          | ''   | '20100527'
 '1000PF'   | '50V'   | '10%'     | '0603'      | 'X7R'     | 'TMP_QCH21006K917'(!) = 'End of Design' | 'Comp-Approve'     | ''       | 'CH21006K917'    |'C0603'| '(SMC0603AW)'                                                        | '1000PF'   | '50V'         | '10%'    | 'DISCRETE' | 'CAP CHIP 1000P 50V(+-10%,X7R,0603)'                           | 'CHIP0603'     | ''          | ''   | '20100528'
 '1000PF'   | '50V'   | '10%'     | '0603'      | 'EMPTY'   | 'TMP_QCH21006K917'(!) = 'End of Design' | 'Comp-Approve'     | ''       | 'CH21006K917'    |'C0603'| '(SMC0603AW)'                                                        | 'NA'       | '50V'         | '10%'    | 'IO'       | 'CAP CHIP 1000P 50V(+-10%,X7R,0603)'                           | 'CHIP0603'     | ''          | ''   | '20100528'
 '0.047UF'  | '25V'   | '10%'     | '0603'      | 'X7R'     | 'TMP_QCH3474K1901'(!) = ''              | ''                 | 'SELASS' | 'CH3474K1901'    |'C0603'| '(SMC0603AW)'                                                        | '0.047UF'  | '25V'         | '10%'    | 'DISCRETE' | 'CAP CHIP 0.047UF 25V(10%,X7R,0603)SELASS'                     | 'CHIP0603'     | ''          | ''   | '20100528'
 '0.047UF'  | '25V'   | '10%'     | '0603'      | 'EMPTY'   | 'TMP_QCH3474K1901'(!) = ''              | ''                 | 'SELASS' | 'CH3474K1901'    |'C0603'| '(SMC0603AW)'                                                        | 'NA'       | '25V'         | '10%'    | 'IO'       | 'CAP CHIP 0.047UF 25V(10%,X7R,0603)SELASS'                     | 'CHIP0603'     | ''          | ''   | '20100528'
 '0.047UF'  | '16V'   | '10%'     | '0603'      | 'X7R'     | 'TMP_QCH3473K1919'(!) = 'End of Design' | 'Comp-Approve'     | ''       | 'CH3473K1919'    |'C0603'| '(SMC0603AW)'                                                        | '0.047UF'  | '16V'         | '10%'    | 'DISCRETE' | 'CAP CHIP 0.047U 16V(+-10%,X7R,0603)'                          | 'CHIP0603'     | ''          | ''   | '20100528'
 '0.047UF'  | '16V'   | '10%'     | '0603'      | 'EMPTY'   | 'TMP_QCH3473K1919'(!) = 'End of Design' | 'Comp-Approve'     | ''       | 'CH3473K1919'    |'C0603'| '(SMC0603AW)'                                                        | 'NA'       | '16V'         | '10%'    | 'IO'       | 'CAP CHIP 0.047U 16V(+-10%,X7R,0603)'                          | 'CHIP0603'     | ''          | ''   | '20100528'
 '0.1UF'    | '50V'   | '10%'     | '0603'      | 'X7R'     | 'TMP_QCH4106K1905'(!) = 'End of Design' | 'Comp-Approve'     | 'SELASS' | 'CH4106K1905'    |'C0603'| '(SMC0603AW)'                                                        | '0.1UF'    | '50V'         | '10%'    | 'DISCRETE' | 'CAP CHIP 0.1U 50V(+-10%,X7R,0603)SEL-ASS'                     | 'CHIP0603'     | ''          | ''   | '20100528'
 '0.1UF'    | '50V'   | '10%'     | '0603'      | 'EMPTY'   | 'TMP_QCH4106K1905'(!) = 'End of Design' | 'Comp-Approve'     | 'SELASS' | 'CH4106K1905'    |'C0603'| '(SMC0603AW)'                                                        | 'NA'       | '50V'         | '10%'    | 'IO'       | 'CAP CHIP 0.1U 50V(+-10%,X7R,0603)SEL-ASS'                     | 'CHIP0603'     | ''          | ''   | '20100528'
 '1UF'      | '25V'   | '10%'     | '0603'      | 'X7R'     | 'TMP_QCH5104K1901'(!) = 'End of Design' | 'Comp-Approve'     | 'SELASS' | 'CH5104K1901'    |'C0603'| '(SMC0603AW)'                                                        | '1UF'      | '25V'         | '10%'    | 'DISCRETE' | 'CAP CHIP 1U 25V(+-10%,X7R,0603)SELASS'                        | 'CHIP0603'     | ''          | ''   | '20100528'
 '1UF'      | '25V'   | '10%'     | '0603'      | 'EMPTY'   | 'TMP_QCH5104K1901'(!) = 'End of Design' | 'Comp-Approve'     | 'SELASS' | 'CH5104K1901'    |'C0603'| '(SMC0603AW)'                                                        | 'NA'       | '25V'         | '10%'    | 'IO'       | 'CAP CHIP 1U 25V(+-10%,X7R,0603)SELASS'                        | 'CHIP0603'     | ''          | ''   | '20100528'
 '2.2UF'    | '10V'   | '10%'     | '0603'      | 'X7R'     | 'TMP_QCH5222K1902'(!) = ''              | ''                 | 'SELASS' | 'CH5222K1902'    |'C0603'| '(SMC0603AW)'                                                        | '2.2UF'    | '10V'         | '10%'    | 'DISCRETE' | 'CAP CHIP 2.2UF 10V(+-10%,X7R,0603)SELASS'                     | 'CHIP0603'     | ''          | ''   | '20100528'
 '2.2UF'    | '10V'   | '10%'     | '0603'      | 'EMPTY'   | 'TMP_QCH5222K1902'(!) = ''              | ''                 | 'SELASS' | 'CH5222K1902'    |'C0603'| '(SMC0603AW)'                                                        | 'NA'       | '10V'         | '10%'    | 'IO'       | 'CAP CHIP 2.2UF 10V(+-10%,X7R,0603)SELASS'                     | 'CHIP0603'     | ''          | ''   | '20100528'
 '0.047UF'  | '25V'   | '10%'     | '0603'      | 'X7R'     | 'TMP_QCH3474K1905'(!) = 'End of Design' | 'Comp-Approve'     | ''       | 'CH3474K1905'    |'C0603'| '(SMC0603AW)'                                                        | '0.047UF'  | '25V'         | '10%'    | 'DISCRETE' | 'CAP CHIP 0.047UF 25V(+-10%,X7R,0603)'                         | 'CHIP0603'     | ''          | ''   | '20100528'
 '0.047UF'  | '25V'   | '10%'     | '0603'      | 'EMPTY'   | 'TMP_QCH3474K1905'(!) = 'End of Design' | 'Comp-Approve'     | ''       | 'CH3474K1905'    |'C0603'| '(SMC0603AW)'                                                        | 'NA'       | '25V'         | '10%'    | 'IO'       | 'CAP CHIP 0.047UF 25V(+-10%,X7R,0603)'                         | 'CHIP0603'     | ''          | ''   | '20100528'
 '1000PF'   | '50V'   | '5%'      | '0402'      | 'X7R'     | 'TMP_QCH21006JB10'(!) = ''              | ''                 | ''       | 'CH21006JB10'    |'C0402'| '(C0402-0201,C0402_OCTAGONXA)'                                       | '1000PF'   | '50V'         | '5%'     | 'DISCRETE' | 'CAP CHIP 1000P 50V(+-5%,X7R,0402)'                            | 'CHIP0402'     | ''          | ''   | '20100528'
 '1000PF'   | '50V'   | '5%'      | '0402'      | 'EMPTY'   | 'TMP_QCH21006JB10'(!) = ''              | ''                 | ''       | 'CH21006JB10'    |'C0402'| '(C0402-0201,C0402_OCTAGONXA)'                                       | 'NA'       | '50V'         | '5%'     | 'IO'       | 'CAP CHIP 1000P 50V(+-5%,X7R,0402)'                            | 'CHIP0402'     | ''          | ''   | '20100528'
 '0.01UF'   | '25V'   | '10%'     | '0402'      | 'X7R'     | 'TMP_QCH31004KB17'(!) = 'End of Design' | 'Comp-Release Qty' | ''       | 'CH31004KB17'    |'C0402'| '(C0402-0201,C0402_OCTAGONXA)'                                       | '0.01UF'   | '25V'         | '10%'    | 'DISCRETE' | 'CAP CHIP 0.01U 25V(+-10%,X7R,0402)'                           | 'CHIP0402'     | ''          | ''   | '20100528'
 '0.01UF'   | '25V'   | '10%'     | '0402'      | 'EMPTY'   | 'TMP_QCH31004KB17'(!) = 'End of Design' | 'Comp-Release Qty' | ''       | 'CH31004KB17'    |'C0402'| '(C0402-0201,C0402_OCTAGONXA)'                                       | 'NA'       | '25V'         | '10%'    | 'IO'       | 'CAP CHIP 0.01U 25V(+-10%,X7R,0402)'                           | 'CHIP0402'     | ''          | ''   | '20100528'
 '1UF'      | '10V'   | '10%'     | '0402'      | 'X5R'     | 'TMP_QCH5102K9B06'(!) = ''              | ''                 | ''       | 'CH5102K9B06'    |'C0402'| '(C0402-0201)'                                                       | '1UF'      | '10V'         | '10%'    | 'DISCRETE' | 'CAP CHIP 1UF 10V (+-10%,X5R,0402)'                            | 'CHIP0402'     | ''          | ''   | '20100528'
 '1UF'      | '10V'   | '10%'     | '0402'      | 'EMPTY'   | 'TMP_QCH5102K9B06'(!) = ''              | ''                 | ''       | 'CH5102K9B06'    |'C0402'| '(C0402-0201)'                                                       | 'NA'       | '10V'         | '10%'    | 'IO'       | 'CAP CHIP 1UF 10V (+-10%,X5R,0402)'                            | 'CHIP0402'     | ''          | ''   | '20100528'
 '10UF'     | '10V'   | '10%'     | '0805'      | 'X7R'     | 'TMP_QCH6102K1A01'(!) = ''              | ''                 | 'SELASS' | 'CH6102K1A01'    |'C0805_H61'| '(SMC0805AW)'                                                        | '10UF'     | '10V'         | '10%'    | 'DISCRETE' | 'CAP CHIP10UF 10V(+-10%,X7R,0805)SELASS'                       | 'CHIP0805'     | ''          | ''   | '20100528'
 '10UF'     | '10V'   | '10%'     | '0805'      | 'EMPTY'   | 'TMP_QCH6102K1A01'(!) = ''              | ''                 | 'SELASS' | 'CH6102K1A01'    |'C0805_H61'| '(SMC0805AW)'                                                        | 'NA'       | '10V'         | '10%'    | 'IO'       | 'CAP CHIP10UF 10V(+-10%,X7R,0805)SELASS'                       | 'CHIP0805'     | ''          | ''   | '20100528'
 '22UF'     | '6.3V'  | '20%'     | '0805'      | 'X5R'     | 'TMP_QCH6221M9A16'(!) = ''              | ''                 | 'SELASS' | 'CH6221M9A16'    |'C0805_H61'| '(SMC0805AW)'                                                        | '22UF'     | '6.3V'        | '20%'    | 'DISCRETE' | 'CAP CHIP 22U 6.3V(+-20%,X5R,0805)SELASS'                      | 'CHIP0805'     | ''          | ''   | '20100528'
 '22UF'     | '6.3V'  | '20%'     | '0805'      | 'EMPTY'   | 'TMP_QCH6221M9A16'(!) = ''              | ''                 | 'SELASS' | 'CH6221M9A16'    |'C0805_H61'| '(SMC0805AW)'                                                        | 'NA'       | '6.3V'        | '20%'    | 'IO'       | 'CAP CHIP 22U 6.3V(+-20%,X5R,0805)SELASS'                      | 'CHIP0805'     | ''          | ''   | '20100528'
 '10UF'     | '25V'   | '10%'     | '1206'      | 'X7R'     | 'TMP_QCH6104K1200'(!) = 'End of Design' | 'Comp-Release Qty' | 'SELASS' | 'CH6104K1200'    |'C1206_H76'| '(SMC1206AW)'                                                        | '10UF'     | '25V'         | '10%'    | 'DISCRETE' | 'CAP CHIP 10U 25V(+-10%,X7R,1206)SEL-ASS'                      | 'CHIP1206'     | ''          | ''   | '20100528'
 '10UF'     | '25V'   | '10%'     | '1206'      | 'EMPTY'   | 'TMP_QCH6104K1200'(!) = 'End of Design' | 'Comp-Release Qty' | 'SELASS' | 'CH6104K1200'    |'C1206_H76'| '(SMC1206AW)'                                                        | 'NA'       | '25V'         | '10%'    | 'IO'       | 'CAP CHIP 10U 25V(+-10%,X7R,1206)SEL-ASS'                      | 'CHIP1206'     | ''          | ''   | '20100528'
 '1000PF'   | '50V'   | '5%'      | '0603'      | 'NPO'     | 'TMP_QCH2106J0903'(!) = ''              | ''                 | 'SELASS' | 'CH2106J0903'    |'C0603'| '(SMC0603AW)'                                                        | '1000PF'   | '50V'         | '5%'     | 'DISCRETE' | 'CAP CHIP 1000P 50V(+-5%,NPO,0603)SELASS'                      | 'CHIP0603'     | ''          | ''   | '2010603' 
 '1000PF'   | '50V'   | '5%'      | '0603'      | 'EMPTY'   | 'TMP_QCH2106J0903'(!) = ''              | ''                 | 'SELASS' | 'CH2106J0903'    |'C0603'| '(SMC0603AW)'                                                        | 'NA'       | '50V'         | '5%'     | 'IO'       | 'CAP CHIP 1000P 50V(+-5%,NPO,0603)SELASS'                      | 'CHIP0603'     | ''          | ''   | '2010603' 
 '1800PF'   | '50V'   | '10%'     | '0603'      | 'X7R'     | 'TMP_QCH2186K1900'(!) = ''              | ''                 | 'SELASS' | 'CH2186K1900'    |'C0603'| '(SMC0603AW)'                                                        | '1800PF'   | '50V'         | '10%'    | 'DISCRETE' | 'CAP CHIP 1800P 50V(+-10%,X7R,0603)SELASS'                     | 'CHIP0603'     | ''          | ''   | '2010603' 
 '1800PF'   | '50V'   | '10%'     | '0603'      | 'EMPTY'   | 'TMP_QCH2186K1900'(!) = ''              | ''                 | 'SELASS' | 'CH2186K1900'    |'C0603'| '(SMC0603AW)'                                                        | 'NA'       | '50V'         | '10%'    | 'IO'       | 'CAP CHIP 1800P 50V(+-10%,X7R,0603)SELASS'                     | 'CHIP0603'     | ''          | ''   | '2010603' 
 '270PF'    | '50V'   | '5%'      | '0402'      | 'NPO'     | 'CH1276J0B02'(!)   = 'End of Design' | 'Comp-Approve'     | ''       | 'CH1276J0B02'    |'C0402'| '(C0402-0201)'                                                       | '270PF'    | '50V'         | '5%'     | 'DISCRETE' | 'CAP CHIP 270P 50V(+-5%,NPO,0402)'                             | 'CHIP0402'     | ''          | ''   | '20100609'
 '270PF'    | '50V'   | '5%'      | '0402'      | 'EMPTY'   | 'CH1276J0B02'(!)   = 'End of Design' | 'Comp-Approve'     | ''       | 'CH1276J0B02'    |'C0402'| '(C0402-0201)'                                                       | 'NA'       | '50V'         | '5%'     | 'IO'       | 'CAP CHIP 270P 50V(+-5%,NPO,0402)'                             | 'CHIP0402'     | ''          | ''   | '20100609'
 '1000PF'   | '50V'   | '5%'      | '0402'      | 'X7R'     | 'CH2106J1B03'(!)   = ''              | ''                 | 'SELASS' | 'CH2106J1B03'    |'C0402'| '(C0402-0201)'                                                       | '1000PF'   | '50V'         | '5%'     | 'DISCRETE' | 'CAP CHIP 1000P 50V(+-5%,X7R,0402)SELASS'                      | 'CHIP0402'     | ''          | ''   | '20100617'
 '1000PF'   | '50V'   | '5%'      | '0402'      | 'EMPTY'   | 'CH2106J1B03'(!)   = ''              | ''                 | 'SELASS' | 'CH2106J1B03'    |'C0402'| '(C0402-0201)'                                                       | 'NA'       | '50V'         | '5%'     | 'IO'       | 'CAP CHIP 1000P 50V(+-5%,X7R,0402)SELASS'                      | 'CHIP0402'     | ''          | ''   | '20100617'
 '100PF'    | '50V'   | '5%'      | '0402'      | 'NPO'     | 'CH11006JB00'(!)   = ''              | ''                 | ''       | 'CH11006JB00'    |'C0402'| '(C0402-0201)'                                                       | '100PF'    | '50V'         | '5%'     | 'DISCRETE' | 'CAP CHIP 100P 50V(+-5%,NPO,0402)'                             | 'CHIP0402'     | ''          | ''   | '20100618'
 '100PF'    | '50V'   | '5%'      | '0402'      | 'EMPTY'   | 'CH11006JB00'(!)   = ''              | ''                 | ''       | 'CH11006JB00'    |'C0402'| '(C0402-0201)'                                                       | 'NA'       | '50V'         | '5%'     | 'IO'       | 'CAP CHIP 100P 50V(+-5%,NPO,0402)'                             | 'CHIP0402'     | ''          | ''   | '20100618'
 '220PF'    | '50V'   | '10%'     | '0402'      | 'X7R'     | 'CH1226K1B06'(!)   = ''              | ''                 | 'SELASS' | 'CH1226K1B06'    |'C0402'| '(C0402-0201)'                                                       | '220PF'    | '50V'         | '10%'    | 'DISCRETE' | 'CAP CHIP 220PF 50V(+-10%,X7R,0402)SELASS'                     | 'CHIP0402'     | ''          | ''   | '20100618'
 '220PF'    | '50V'   | '10%'     | '0402'      | 'EMPTY'   | 'CH1226K1B06'(!)   = ''              | ''                 | 'SELASS' | 'CH1226K1B06'    |'C0402'| '(C0402-0201)'                                                       | 'NA'       | '50V'         | '10%'    | 'IO'       | 'CAP CHIP 220PF 50V(+-10%,X7R,0402)SELASS'                     | 'CHIP0402'     | ''          | ''   | '20100618'
 '1500PF'   | '50V'   | '10%'     | '0402'      | 'X7R'     | 'CH2156K1B03'(!)   = ''              | ''                 | 'SELASS' | 'CH2156K1B03'    |'C0402'| '(C0402-0201)'                                                       | '1500PF'   | '50V'         | '10%'    | 'DISCRETE' | 'CAP CHIP1500PF 50V(+-10%,X7R,0402)SELASS '                    | 'CHIP0402'     | ''          | ''   | '20100618'
 '1500PF'   | '50V'   | '10%'     | '0402'      | 'EMPTY'   | 'CH2156K1B03'(!)   = ''              | ''                 | 'SELASS' | 'CH2156K1B03'    |'C0402'| '(C0402-0201)'                                                       | 'NA'       | '50V'         | '10%'    | 'IO'       | 'CAP CHIP1500PF 50V(+-10%,X7R,0402)SELASS'                     | 'CHIP0402'     | ''          | ''   | '20100618'
 '10UF'     | '25V'   | '10%'     | '1206'      | 'X6S'     | 'CH6104KE203'(!)   = ''              | ''                 | 'SELASS' | 'CH6104KE203'    |'C1206_H76'| '(SMC1206AW)'                                                        | '10UF'     | '25V'         | '10%'    | 'DISCRETE' | 'CAP CHIP 10U 25V(+-10%,X6S,1206)SELASS'                       | 'CHIP1206'     | ''          | ''   | '20100618'
 '10UF'     | '25V'   | '10%'     | '1206'      | 'EMPTY'   | 'CH6104KE203'(!)   = ''              | ''                 | 'SELASS' | 'CH6104KE203'    |'C1206_H76'| '(SMC1206AW)'                                                        | 'NA'       | '25V'         | '10%'    | 'IO'       | 'CAP CHIP 10U 25V(+-10%,X6S,1206)SELASS'                       | 'CHIP1206'     | ''          | ''   | '20100618'
 '5600PF'   | '25V'   | '10%'     | '0402'      | 'X7R'     | 'CH25604KB18'(!)   = 'End of Design' | 'Comp-Approve'     | ''       | 'CH25604KB18'    |'C0402'| '(C0402-0201)'                                                       | '5600PF'   | '25V'         | '10%'    | 'DISCRETE' | 'CAP CHIP 5600P 25V(X7R,+-10%,0402)'                           | 'CHIP0402'     | ''          | ''   | '20100621'
 '5600PF'   | '25V'   | '10%'     | '0402'      | 'EMPTY'   | 'CH25604KB18'(!)   = 'End of Design' | 'Comp-Approve'     | ''       | 'CH25604KB18'    |'C0402'| '(C0402-0201)'                                                       | 'NA'       | '25V'         | '10%'    | 'IO'       | 'CAP CHIP 5600P 25V(X7R,+-10%,0402)'                           | 'CHIP0402'     | ''          | ''   | '20100621'
 '330PF'    | '50V'   | '10%'     | '0402'      | 'X7R'     | 'CH1336K1B02'(!)   = ''              | ''                 | ''       | 'CH1336K1B02'    |'C0402'| '(C0402-0201)'                                                       | '330PF'    | '50V'         | '10%'    | 'DISCRETE' | 'CAP CHIP 330P 50V(+-10%,X7R,0402)'                            | 'CHIP0402'     | ''          | ''   | '20100623'
 '330PF'    | '50V'   | '10%'     | '0402'      | 'EMPTY'   | 'CH1336K1B02'(!)   = ''              | ''                 | ''       | 'CH1336K1B02'    |'C0402'| '(C0402-0201)'                                                       | 'NA'       | '50V'         | '10%'    | 'IO'       | 'CAP CHIP 330P 50V(+-10%,X7R,0402)'                            | 'CHIP0402'     | ''          | ''   | '20100623'
 '0.068UF'  | '16V'   | '10%'     | '0402'      | 'X7R'     | 'CH3683K1B09'(!)   = ''              | ''                 | ''       | 'CH3683K1B09'    |'C0402'| '(C0402-0201)'                                                       | '0.068UF'  | '16V'         | '10%'    | 'DISCRETE' | 'CAP CHIP 0.068UF 16V(+-10%,X7R 0402)'                         | 'CHIP0402'     | ''          | ''   | '20100630'
 '0.068UF'  | '16V'   | '10%'     | '0402'      | 'EMPTY'   | 'CH3683K1B09'(!)   = ''              | ''                 | ''       | 'CH3683K1B09'    |'C0402'| '(C0402-0201)'                                                       | 'NA'       | '16V'         | '10%'    | 'IO'       | 'CAP CHIP 0.068UF 16V(+-10%,X7R 0402)'                         | 'CHIP0402'     | ''          | ''   | '20100630'
 '2200PF'   | '50V'   | '10%'     | '0603'      | 'X7R'     | 'CH22206K917'(!)   = 'End of Design' | 'Comp-Approve'     | ''       | 'CH22206K917'    |'C0603'| '(SMC0603AW)'                                                        | '2200PF'   | '50V'         | '10%'    | 'DISCRETE' | 'CAP CHIP 2200P 50V(+-10%,X7R,0603)'                           | 'CHIP0603'     | ''          | ''   | '2010702' 
 '2200PF'   | '50V'   | '10%'     | '0603'      | 'EMPTY'   | 'CH22206K917'(!)   = 'End of Design' | 'Comp-Approve'     | ''       | 'CH22206K917'    |'C0603'| '(SMC0603AW)'                                                        | 'NA'       | '50V'         | '10%'    | 'IO'       | 'CAP CHIP 2200P 50V(+-10%,X7R,0603)'                           | 'CHIP0603'     | ''          | ''   | '2010702' 
 '0.1UF'    | '16V'   | '20%'     | '0402'      | 'Y5V'     | 'CH41003ZB35'(!)   = 'End of Design' | 'Comp-Approve'     | ''       | 'CH41003ZB35'    |'C0402'| '(C0402-0201)'                                                       | '0.1UF'    | '16V'         | '20%'    | 'DISCRETE' | 'CAP CHIP 0.1U 16V(+80%-20%,Y5V,0402)'                         | 'CHIP0402'     | ''          | ''   | '2010709' 
 '0.1UF'    | '16V'   | '20%'     | '0402'      | 'EMPTY'   | 'CH41003ZB35'(!)   = 'End of Design' | 'Comp-Approve'     | ''       | 'CH41003ZB35'    |'C0402'| '(C0402-0201)'                                                       | 'NA'       | '16V'         | '20%'    | 'IO'       | 'CAP CHIP 0.1U 16V(+80%-20%,Y5V,0402)'                         | 'CHIP0402'     | ''          | ''   | '2010709' 
 '0.1UF'    | '50V'   | '10%'     | '0603'      | 'X7R'     | 'CH41006K911'(!)   = 'End of Design' | 'Comp-Approve'     | ''       | 'CH41006K911'    |'C0603'| '(SMC0603AW)'                                                        | '0.1UF'    | '50V'         | '10%'    | 'DISCRETE' | 'CAP CHIP 0.1U 50V(+-10%,X7R,0603)'                            | 'CHIP0603'     | ''          | ''   | '2010709' 
 '0.1UF'    | '50V'   | '10%'     | '0603'      | 'EMPTY'   | 'CH41006K911'(!)   = 'End of Design' | 'Comp-Approve'     | ''       | 'CH41006K911'    |'C0603'| '(SMC0603AW)'                                                        | 'NA'       | '50V'         | '10%'    | 'IO'       | 'CAP CHIP 0.1U 50V(+-10%,X7R,0603)'                            | 'CHIP0603'     | ''          | ''   | '2010709' 
 '0.1UF'    | '16V'   | '10%'     | '0402'      | 'X5R'     | 'CH4103K9B09'(!)   = 'End of Design' | 'Comp-Approve'     | ''       | 'CH4103K9B09'    |'C0402'| '(C0402-0201)'                                                       | '0.1UF'    | '16V'         | '10%'    | 'DISCRETE' | 'CAP CHIP 0.1U 16V(+-10%,X5R,0402) '                           | 'CHIP0402'     | ''          | ''   | '2010709' 
 '0.1UF'    | '16V'   | '10%'     | '0402'      | 'EMPTY'   | 'CH4103K9B09'(!)   = 'End of Design' | 'Comp-Approve'     | ''       | 'CH4103K9B09'    |'C0402'| '(C0402-0201)'                                                       | 'NA'       | '16V'         | '10%'    | 'IO'       | 'CAP CHIP 0.1U 16V(+-10%,X5R,0402) '                           | 'CHIP0402'     | ''          | ''   | '2010709' 
 '0.1UF'    | '25V'   | '20%'     | '0402'      | 'Y5V'     | 'CH4104Z3B07'(!)   = 'End of Design' | 'Comp-Approve'     | ''       | 'CH4104Z3B07'    |'C0402'| '(C0402-0201)'                                                       | '0.1UF'    | '25V'         | '20%'    | 'DISCRETE' | 'CAP CHIP 0.1U 25V(+80%-20%,Y5V,0402)'                         | 'CHIP0402'     | ''          | ''   | '2010709' 
 '0.1UF'    | '25V'   | '20%'     | '0402'      | 'EMPTY'   | 'CH4104Z3B07'(!)   = 'End of Design' | 'Comp-Approve'     | ''       | 'CH4104Z3B07'    |'C0402'| '(C0402-0201)'                                                       | 'NA'       | '25V'         | '20%'    | 'IO'       | 'CAP CHIP 0.1U 25V(+80%-20%,Y5V,0402)'                         | 'CHIP0402'     | ''          | ''   | '2010709' 
 '4.7UF'    | '25V'   | '10%'     | '0805'      | 'X6S'     | 'CH5474KEA06'(!)   = 'End of Design' | 'Comp-Approve'     | ''       | 'CH5474KEA06'    |'C0805_H61'| '(SMC0805AW)'                                                        | '4.7UF'    | '25V'         | '10%'    | 'DISCRETE' | 'CAP CHIP 4.7U 25V(+-10%,X6S,0805) EP'                         | 'CHIP0805'     | ''          | ''   | '2010709' 
 '4.7UF'    | '25V'   | '10%'     | '0805'      | 'EMPTY'   | 'CH5474KEA06'(!)   = 'End of Design' | 'Comp-Approve'     | ''       | 'CH5474KEA06'    |'C0805_H61'| '(SMC0805AW)'                                                        | 'NA'       | '25V'         | '10%'    | 'IO'       | 'CAP CHIP 4.7U 25V(+-10%,X6S,0805) EP'                         | 'CHIP0805'     | ''          | ''   | '2010709' 
 '22UF'     | '16V'   | '20%'     | '1206'      | 'X5R'     | 'CH6223M9200'(!)   = 'End of Design' | 'Comp-Approve'     | ''       | 'CH6223M9200'    |'C1206_H66'| '(SMC1206AW)'                                                        | '22UF'     | '16V'         | '20%'    | 'DISCRETE' | 'CAP CHIP 22UF 16V(+-20%,X5R,1206)'                            | 'CHIP1206'     | ''          | ''   | '2010709' 
 '22UF'     | '16V'   | '20%'     | '1206'      | 'EMPTY'   | 'CH6223M9200'(!)   = 'End of Design' | 'Comp-Approve'     | ''       | 'CH6223M9200'    |'C1206_H66'| '(SMC1206AW)'                                                        | 'NA'       | '16V'         | '20%'    | 'IO'       | 'CAP CHIP 22UF 16V(+-20%,X5R,1206)'                            | 'CHIP1206'     | ''          | ''   | '2010709' 
 '1UF'      | '10V'   | '20%'     | '0603'      | 'Y5V'     | 'CH5102Z3919'(!)   = 'End of Design' | 'Comp-Approve'     | ''       | 'CH5102Z3919'    |'C0603'| '(SMC0603AW)'                                                        | '1UF'      | '10V'         | '20%'    | 'DISCRETE' | 'CAP CHIP 1U 10V(+80%-20%,Y5V,0603)EP'                         | 'CHIP0603'     | ''          | ''   | '20107015'
 '1UF'      | '10V'   | '20%'     | '0603'      | 'EMPTY'   | 'CH5102Z3919'(!)   = 'End of Design' | 'Comp-Approve'     | ''       | 'CH5102Z3919'    |'C0603'| '(SMC0603AW)'                                                        | 'NA'       | '10V'         | '20%'    | 'IO'       | 'CAP CHIP 1U 10V(+80%-20%,Y5V,0603)EP'                         | 'CHIP0603'     | ''          | ''   | '20107015'
 '22PF '    | '50V'   | '5% '     | '0603'      | 'NPO'     | 'CH0226J0911'(!)   = ''              | 'End of Life'      | ''       | 'CH0226J0911'    |'C0603_EOL'| '(SMC0603AW)'                                                        | '22PF'     | '50V'         | '5% '    | 'DISCRETE' | 'CAP CHIP 22P 50V(+-5%,NPO,0603)    '                          | 'CHIP0603'     | ''          | ''   | '20107018'
 '22PF '    | '50V'   | '5% '     | '0603'      | 'EMPTY'   | 'CH0226J0911'(!)   = ''              | 'End of Life'      | ''       | 'CH0226J0911'    |'C0603_EOL'| '(SMC0603AW)'                                                        | 'NA'       | '50V'         | '5% '    | 'IO'       | 'CAP CHIP 22P 50V(+-5%,NPO,0603)    '                          | 'CHIP0603'     | ''          | ''   | '20107018'
 '0.1UF'    | '25V'   | '20%'     | '0603'      | 'Y5V'     | 'CH4104Z3916'(!)   = 'End of Design' | 'Comp-Approve'     | ''       | 'CH4104Z3916'    |'C0603'| '(SMC0603AW)'                                                        | '0.1UF'    | '25V'         | '20%'    | 'DISCRETE' | 'CAP CHIP 0.1U,25V(+80-20%,Y5V,0603)'                          | 'CHIP0603'     | ''          | ''   | '20107018'
 '0.1UF'    | '25V'   | '20%'     | '0603'      | 'EMPTY'   | 'CH4104Z3916'(!)   = 'End of Design' | 'Comp-Approve'     | ''       | 'CH4104Z3916'    |'C0603'| '(SMC0603AW)'                                                        | 'NA'       | '25V'         | '20%'    | 'IO'       | 'CAP CHIP 0.1U,25V(+80-20%,Y5V,0603)'                          | 'CHIP0603'     | ''          | ''   | '20107018'
 '10UF '    | '10V'   | '20%'     | '0603'      | 'X7R'     | 'CH6102M1909'(!)   = 'End of Design' | 'Comp-Approve'     | ''       | 'CH6102M1909'    |'C0603'| '(SMC0603AW)'                                                        | '10UF'     | '10V'         | '20%'    | 'DISCRETE' | 'CAP CHIP 10U,10V(+-20%,X7R,0603)   '                          | 'CHIP0603'     | ''          | ''   | '20107018'
 '10UF '    | '10V'   | '20%'     | '0603'      | 'EMPTY'   | 'CH6102M1909'(!)   = 'End of Design' | 'Comp-Approve'     | ''       | 'CH6102M1909'    |'C0603'| '(SMC0603AW)'                                                        | 'NA'       | '10V'         | '20%'    | 'IO'       | 'CAP CHIP 10U,10V(+-20%,X7R,0603)   '                          | 'CHIP0603'     | ''          | ''   | '20107018'
 '47UF '    | '10V'   | '20%'     | '1206'      | 'X5R'     | 'CH6472M9200'(!)   = 'End of Design' | 'Comp-Approve'     | ''       | 'CH6472M9200'    |'C1206_H76'| '(SMC1206AW)'                                                        | '47UF '    | '10V'         | '20%'    | 'DISCRETE' | 'CAP CHIP 47U 10V(+-20%,X5R,1206)  '                           | 'CHIP1206'     | ''          | ''   | '20107030'
 '47UF '    | '10V'   | '20%'     | '1206'      | 'EMPTY'   | 'CH6472M9200'(!)   = 'End of Design' | 'Comp-Approve'     | ''       | 'CH6472M9200'    |'C1206_H76'| '(SMC1206AW)'                                                        | 'NA'       | '10V'         | '20%'    | 'IO'       | 'CAP CHIP 47U 10V(+-20%,X5R,1206)  '                           | 'CHIP1206'     | ''          | ''   | '20107030'
 '27PF  '   | '50V '  | '5% '     | '0402'      | 'NPO'     | 'CH02706JB06'(!)   = ''              | ''                 | ''       | 'CH02706JB06'    |'C0402'| '(C0402-0201)'                                                       | '27PF'     | '50V'         | '5% '    | 'DISCRETE' | 'CAP CHIP 27P 50V(+-5% NPO 0402)          '                    | 'CHIP0402'     | ''          | ''   | '20100811'
 '27PF  '   | '50V '  | '5% '     | '0402'      | 'EMPTY'   | 'CH02706JB06'(!)   = ''              | ''                 | ''       | 'CH02706JB06'    |'C0402'| '(C0402-0201)'                                                       | 'NA'       | '50V'         | '5% '    | 'IO'       | 'CAP CHIP 27P 50V(+-5% NPO 0402)          '                    | 'CHIP0402'     | ''          | ''   | '20100811'
 '1NF'      | '50V'   | '10%'     | '0402'      | 'X7R'     | 'CH21006KB16'(!)   = ''              | ''                 | ''       | 'CH21006KB16'    |'C0402'| '(C0402-0201)'                                                       | '1NF'      | '50V'         | '10%'    | 'DISCRETE' | 'CAP CHIP 1N 50V(+-10%,X7R,0402)EP'                            | 'CHIP0402'     | ''          | ''   | '20100811'
 '1NF'      | '50V'   | '10%'     | '0402'      | 'EMPTY'   | 'CH21006KB16'(!)   = ''              | ''                 | ''       | 'CH21006KB16'    |'C0402'| '(C0402-0201)'                                                       | 'NA'       | '50V'         | '10%'    | 'IO'       | 'CAP CHIP 1N 50V(+-10%,X7R,0402)EP'                            | 'CHIP0402'     | ''          | ''   | '20100811'
 '0.1UF '   | '10V '  | '10%'     | '0402'      | 'X7R'     | 'CH4102K1B04'(!)   = ''              | ''                 | 'SELASS' | 'CH4102K1B04'    |'C0402'| '(C0402-0201)'                                                       | '0.1UF'    | '10V'         | '10%'    | 'DISCRETE' | 'CAP CHIP 0.1U 10V(+-10%,X7R,0402)SELASS  '                    | 'CHIP0402'     | ''          | ''   | '20100811'
 '0.1UF '   | '10V '  | '10%'     | '0402'      | 'EMPTY'   | 'CH4102K1B04'(!)   = ''              | ''                 | 'SELASS' | 'CH4102K1B04'    |'C0402'| '(C0402-0201)'                                                       | 'NA'       | '10V'         | '10%'    | 'IO'       | 'CAP CHIP 0.1U 10V(+-10%,X7R,0402)SELASS  '                    | 'CHIP0402'     | ''          | ''   | '20100811'
 '2.2UF '   | '6.3V'  | '20%'     | '0402'      | 'X5R'     | 'CH5221M9B02'(!)   = 'End of Design' | 'Comp-Release Qty' | ''       | 'CH5221M9B02'    |'C0402'| '(C0402-0201)'                                                       | '2.2UF'    | '6.3V'        | '20%'    | 'DISCRETE' | 'CAP CHIP 2.2U 6.3V(+-20%,X5R,0402)       '                    | 'CHIP0402'     | ''          | ''   | '20100811'
 '2.2UF '   | '6.3V'  | '20%'     | '0402'      | 'EMPTY'   | 'CH5221M9B02'(!)   = 'End of Design' | 'Comp-Release Qty' | ''       | 'CH5221M9B02'    |'C0402'| '(C0402-0201)'                                                       | 'NA'       | '6.3V'        | '20%'    | 'IO'       | 'CAP CHIP 2.2U 6.3V(+-20%,X5R,0402)       '                    | 'CHIP0402'     | ''          | ''   | '20100811'
 '2.2UF '   | '6.3V'  | '10%'     | '0603'      | 'X5R'     | 'CH5221K9911'(!)   = 'End of Design' | 'Comp-Approve'     | ''       | 'CH5221K9911'    |'C0603'| '(SMC0603AW)'                                                        | '2.2UF'    | '6.3V'        | '10%'    | 'DISCRETE' | 'CAP CHIP 2.2U 6.3V(10%,X5R,0603,H0.5)    '                    | 'CHIP0603'     | ''          | ''   | '20100811'
 '2.2UF '   | '6.3V'  | '10%'     | '0603'      | 'EMPTY'   | 'CH5221K9911'(!)   = 'End of Design' | 'Comp-Approve'     | ''       | 'CH5221K9911'    |'C0603'| '(SMC0603AW)'                                                        | 'NA'       | '6.3V'        | '10%'    | 'IO'       | 'CAP CHIP 2.2U 6.3V(10%,X5R,0603,H0.5)    '                    | 'CHIP0603'     | ''          | ''   | '20100811'
 '22UF  '   | '6.3V'  | '20%'     | '0805'      | 'X5R'     | 'CH6221M9A07'(!)   = 'End of Design' | 'Comp-Release Qty' | ''       | 'CH6221M9A07'    |'C0805_H61'| '(SMC0805AW)'                                                        | '22UF'     | '6.3V'        | '20%'    | 'DISCRETE' | 'CAP CHIP 22U 6.3V(+-20%,X5R,0805)        '                    | 'CHIP0805'     | ''          | ''   | '20100811'
 '22UF  '   | '6.3V'  | '20%'     | '0805'      | 'EMPTY'   | 'CH6221M9A07'(!)   = 'End of Design' | 'Comp-Release Qty' | ''       | 'CH6221M9A07'    |'C0805_H61'| '(SMC0805AW)'                                                        | 'NA'       | '6.3V'        | '20%'    | 'IO'       | 'CAP CHIP 22U 6.3V(+-20%,X5R,0805)        '                    | 'CHIP0805'     | ''          | ''   | '20100811'
 '1UF   '   | '25V '  | '10%'     | '0805'      | 'X5R'     | 'CH5104K9A08'(!)   = 'End of Design' | 'Comp-Approve'     | ''       | 'CH5104K9A08'    |'C0805_H43'| '(SMC0805AW)'                                                        | '1UF'      | '25V'         | '10%'    | 'DISCRETE' | 'CAP CHIP 1U 25V(+-10%,X5R,0805)H0.85     '                    | 'CHIP1206'     | ''          | ''   | '20107030'
 '1UF   '   | '25V '  | '10%'     | '0805'      | 'EMPTY'   | 'CH5104K9A08'(!)   = 'End of Design' | 'Comp-Approve'     | ''       | 'CH5104K9A08'    |'C0805_H43'| '(SMC0805AW)'                                                        | 'NA'       | '25V'         | '10%'    | 'IO'       | 'CAP CHIP 1U 25V(+-10%,X5R,0805)H0.85     '                    | 'CHIP1206'     | ''          | ''   | '20107030'
 '0.01UF '  | '25V'   | '10%'     | '0402'      | 'X7R'     | 'CH3104K1B08'(!)   = ''              | ''                 | 'SELASS' | 'CH3104K1B08'    |'C0402'| '(C0402-0201)'                                                       | '0.01UF'   | '25V'         | '10%'    | 'DISCRETE' | 'CAP CHIP 0.01U 25V(+-10%,X7R,0402)SELASS'                     | 'CHIP0402'     | ''          | ''   | '20100827'
 '0.01UF '  | '25V'   | '10%'     | '0402'      | 'EMPTY'   | 'CH3104K1B08'(!)   = ''              | ''                 | 'SELASS' | 'CH3104K1B08'    |'C0402'| '(C0402-0201)'                                                       | 'NA'       | '25V'         | '10%'    | 'IO'       | 'CAP CHIP 0.01U 25V(+-10%,X7R,0402)SELASS'                     | 'CHIP0402'     | ''          | ''   | '20100827'
 '20PF '    | '50V'   | '5% '     | '0603'      | 'NPO'     | 'CH02006J901'(!)   = ''              | ''                 | ''       | 'CH02006J901'    |'C0603'| '(SMC0603AW)'                                                        | '20PF'     | '50V'         | '5% '    | 'DISCRETE' | 'CAPACITOR CHIP 20P 50V(+-5%,NPO,0603)'                        | 'CHIP0603'     | ''          | ''   | '20100831'
 '20PF '    | '50V'   | '5% '     | '0603'      | 'EMPTY'   | 'CH02006J901'(!)   = ''              | ''                 | ''       | 'CH02006J901'    |'C0603'| '(SMC0603AW)'                                                        | 'NA'       | '50V'         | '5% '    | 'IO'       | 'CAPACITOR CHIP 20P 50V(+-5%,NPO,0603)'                        | 'CHIP0603'     | ''          | ''   | '20100831'
 '0.47UF'   | '10V'   | '10%'     | '0603'      | 'X7R'     | 'CH44702K912'(!)   = 'End of Design' | 'Comp-Approve'     | ''       | 'CH44702K912'    |'C0603'| '(SMC0603AW)'                                                        | '0.47UF'   | '10V'         | '10%'    | 'DISCRETE' | 'CAP CHIP 0.47U 10V(+-10%,X7R,0603)'                           | 'CHIP0603'     | ''          | ''   | ''        
 '0.47UF'   | '10V'   | '10%'     | '0603'      | 'EMPTY'   | 'CH44702K912'(!)   = 'End of Design' | 'Comp-Approve'     | ''       | 'CH44702K912'    |'C0603'| '(SMC0603AW)'                                                        | 'NA'       | '10V'         | '10%'    | 'IO'       | 'CAP CHIP 0.47U 10V(+-10%,X7R,0603)'                           | 'CHIP0603'     | ''          | ''   | ''        
 '1UF'      | '16V'   | '10%'     | '0603'      | 'X5R'     | 'CH5103K9901'(!)   = 'End of Design' | 'Comp-Approve'     | ''       | 'CH5103K9901'    |'C0603'| '(SMC0603AW)'                                                        | '1UF'      | '16V'         | '10%'    | 'DISCRETE' | 'CAP CHIP 1U 16V(+-10%,X5R,0603)'                              | 'CHIP0603'     | ''          | ''   | '20100914'
 '1UF'      | '16V'   | '10%'     | '0603'      | 'EMPTY'   | 'CH5103K9901'(!)   = 'End of Design' | 'Comp-Approve'     | ''       | 'CH5103K9901'    |'C0603'| '(SMC0603AW)'                                                        | 'NA'       | '16V'         | '10%'    | 'IO'       | 'CAP CHIP 1U 16V(+-10%,X5R,0603)'                              | 'CHIP0603'     | ''          | ''   | '20100914'
 '0.015UF'  | '50V'   | '10%'     | '0603'      | 'X7R'     | 'CH31506K917'(!)   = 'End of Design' | 'Comp-Approve'     | ''       | 'CH31506K917'    |'C0603'| '(SMC0603AW)'                                                        | '0.015UF'  | '50V'         | '10%'    | 'DISCRETE' | 'CAP CHIP 0.015U 50V(+-10%,X7R,0603)EP'                        | 'CHIP0603'     | ''          | ''   | '20100915'
 '0.015UF'  | '50V'   | '10%'     | '0603'      | 'EMPTY'   | 'CH31506K917'(!)   = 'End of Design' | 'Comp-Approve'     | ''       | 'CH31506K917'    |'C0603'| '(SMC0603AW)'                                                        | 'NA'       | '50V'         | '10%'    | 'IO'       | 'CAP CHIP 0.015U 50V(+-10%,X7R,0603)EP'                        | 'CHIP0603'     | ''          | ''   | '20100915'
 '0.22UF'   | '16V'   | '10%'     | '0402'      | 'X7R'     | 'CH4223K1B00'(!)   = 'End of Design' | 'Comp-Approve'     | ''       | 'CH4223K1B00'    |'C0402'| '(C0402_OCTAGONXA,C0402-0201)'                                       | '0.22UF'   | '16V'         | '10%'    | 'DISCRETE' | 'CAP CHIP 0.22U 16V(10%,X7R,0402)'                             | 'CHIP0402'     | ''          | ''   | '20100916'
 '0.22UF'   | '16V'   | '10%'     | '0402'      | 'EMPTY'   | 'CH4223K1B00'(!)   = 'End of Design' | 'Comp-Approve'     | ''       | 'CH4223K1B00'    |'C0402'| '(C0402_OCTAGONXA,C0402-0201)'                                       | 'NA'       | '16V'         | '10%'    | 'IO'       | 'CAP CHIP 0.22U 16V(10%,X7R,0402)'                             | 'CHIP0402'     | ''          | ''   | '20100916'
 '0.01UF'   | '16V'   | '10%'     | '0201'      | 'X7R'     | 'CH3103K1E00'(!)   = ''              | ''                 | ''       | 'CH3103K1E00'    |'C0201'| '(SMC0201AW)'                                                        | '0.01UF'   | '16V'         | '10%'    | 'DISCRETE' | 'CAP CHIP 0.01U 16V(+-10%,X7R,0201)'                           | 'CHIP0201'     | ''          | ''   | '20100923'
 '0.01UF'   | '16V'   | '10%'     | '0201'      | 'EMPTY'   | 'CH3103K1E00'(!)   = ''              | ''                 | ''       | 'CH3103K1E00'    |'C0201'| '(SMC0201AW)'                                                        | 'NA'       | '16V'         | '10%'    | 'IO'       | 'CAP CHIP 0.01U 16V(+-10%,X7R,0201)'                           | 'CHIP0201'     | ''          | ''   | '20100923'
 '18P'      | '50V'   | '5%'      | '0603'      | 'NPO'     | 'CH0186J0902'(!)   = 'End of Design' | 'Comp-Approve'     | ''       | 'CH0186J0902'    |'C0603'| '(SMC0603AW)'                                                        | '18PF'     | '50V'         | '5%'     | 'DISCRETE' | 'CAP CHIP 18P 50V(+-5%,NPO,0603)   '                           | 'CHIP0603'     | ''          | ''   | '20100923'
 '18P'      | '50V'   | '5%'      | '0603'      | 'EMPTY'   | 'CH0186J0902'(!)   = 'End of Design' | 'Comp-Approve'     | ''       | 'CH0186J0902'    |'C0603'| '(SMC0603AW)'                                                        | 'NA'       | '50V'         | '5%'     | 'IO'       | 'CAP CHIP 18P 50V(+-5%,NPO,0603)   '                           | 'CHIP0603'     | ''          | ''   | '20100923'
 '22PF'     | '50V'   | '5%'      | '0603'      | 'NPO'     | 'CH02206J909'(!)   = 'End of Design' | 'Comp-Approve'     | ''       | 'CH02206J909'    |'C0603'| '(SMC0603AW)'                                                        | '22PF'     | '50V'         | '5%'     | 'DISCRETE' | 'CAP CHIP 22P 50V(+-5%.NPO.0603)'                              | 'CHIP0603'     | ''          | ''   | '20100929'
 '22PF'     | '50V'   | '5%'      | '0603'      | 'EMPTY'   | 'CH02206J909'(!)   = 'End of Design' | 'Comp-Approve'     | ''       | 'CH02206J909'    |'C0603'| '(SMC0603AW)'                                                        | 'NA'       | '50V'         | '5%'     | 'IO'       | 'CAP CHIP 22P 50V(+-5%.NPO.0603)'                              | 'CHIP0603'     | ''          | ''   | '20100929'
 '100PF'    | '50V'   | '5%'      | '0402'      | 'X7R'     | 'CH11006JB18'(!)   = 'End of Design' | 'Comp-Approve'     | ''       | 'CH11006JB18'    |'C0402'| '(C0402-0201)'                                                       | '100PF'    | '50V'         | '5%'     | 'DISCRETE' | 'CAP CHIP 100P 50V(+-5%.X7R.0402)'                             | 'CHIP0402'     | ''          | ''   | '20100929'
 '100PF'    | '50V'   | '5%'      | '0402'      | 'EMPTY'   | 'CH11006JB18'(!)   = 'End of Design' | 'Comp-Approve'     | ''       | 'CH11006JB18'    |'C0402'| '(C0402-0201)'                                                       | 'NA'       | '50V'         | '5%'     | 'IO'       | 'CAP CHIP 100P 50V(+-5%.X7R.0402)'                             | 'CHIP0402'     | ''          | ''   | '20100929'
 '330PF'    | '50V'   | '5%'      | '0603'      | 'NPO'     | 'CH13306J907'(!)   = 'End of Design' | 'Comp-Approve'     | ''       | 'CH13306J907'    |'C0603'| '(SMC0603AW)'                                                        | '330PF'    | '50V'         | '5%'     | 'DISCRETE' | 'CAPACITOR CHIP 330P 50V(+-5%.NPO.0603)'                       | 'CHIP0603'     | ''          | ''   | '20100929'
 '330PF'    | '50V'   | '5%'      | '0603'      | 'EMPTY'   | 'CH13306J907'(!)   = 'End of Design' | 'Comp-Approve'     | ''       | 'CH13306J907'    |'C0603'| '(SMC0603AW)'                                                        | 'NA'       | '50V'         | '5%'     | 'IO'       | 'CAPACITOR CHIP 330P 50V(+-5%.NPO.0603)'                       | 'CHIP0603'     | ''          | ''   | '20100929'
 '3300PF'   | '50V'   | '10%'     | '0402'      | 'X7R'     | 'CH2336K1B01'(!)   = ''              | ''                 | 'SELASS' | 'CH2336K1B01'    |'C0402'| '(C0402-0201)'                                                       | '3300PF'   | '50V'         | '10%'    | 'DISCRETE' | 'CAP CHIP 3300P 50V(+-10%.X7R.0402)SELASS'                     | 'CHIP0402'     | ''          | ''   | '20100929'
 '3300PF'   | '50V'   | '10%'     | '0402'      | 'EMPTY'   | 'CH2336K1B01'(!)   = ''              | ''                 | 'SELASS' | 'CH2336K1B01'    |'C0402'| '(C0402-0201)'                                                       | 'NA'       | '50V'         | '10%'    | 'IO'       | 'CAP CHIP 3300P 50V(+-10%.X7R.0402)SELASS'                     | 'CHIP0402'     | ''          | ''   | '20100929'
 '1UF'      | '10V'   | '20%'     | '0603'      | 'Y5V'     | 'CH51002M930'(!)   = 'End of Design' | 'Comp-Approve'     | ''       | 'CH51002M930'    |'C0603'| '(SMC0603AW)'                                                        | '1UF'      | '10V'         | '20%'    | 'DISCRETE' | 'CAP CHIP 1U 10V(+-20%.Y5V.0603)'                              | 'CHIP0603'     | ''          | ''   | '20100929'
 '1UF'      | '10V'   | '20%'     | '0603'      | 'EMPTY'   | 'CH51002M930'(!)   = 'End of Design' | 'Comp-Approve'     | ''       | 'CH51002M930'    |'C0603'| '(SMC0603AW)'                                                        | 'NA'       | '10V'         | '20%'    | 'IO'       | 'CAP CHIP 1U 10V(+-20%.Y5V.0603)'                              | 'CHIP0603'     | ''          | ''   | '20100929'
 '3.3UF'    | '16V'   | '20%'     | '1206'      | 'Y5V'     | 'CH53303Z233'(!)   = 'End of Design' | 'Comp-Approve'     | ''       | 'CH53303Z233'    |'C1206_H56'| '(SMC1206AW)'                                                        | '3.3UF'    | '16V'         | '20%'    | 'DISCRETE' | 'CAP CHIP 3.3U.16V(+80%-20%.Y5V.1206)'                         | 'CHIP1206'     | ''          | ''   | '20100929'
 '3.3UF'    | '16V'   | '20%'     | '1206'      | 'EMPTY'   | 'CH53303Z233'(!)   = 'End of Design' | 'Comp-Approve'     | ''       | 'CH53303Z233'    |'C1206_H56'| '(SMC1206AW)'                                                        | 'NA'       | '16V'         | '20%'    | 'IO'       | 'CAP CHIP 3.3U.16V(+80%-20%.Y5V.1206)'                         | 'CHIP1206'     | ''          | ''   | '20100929'
 '10UF'     | '6.3V'  | '10%'     | '0805'      | 'X5R'     | 'CH61001KA94'(!)   = 'End of Design' | 'Comp-Approve'     | ''       | 'CH61001KA94'    |'C0805_H61'| '(SMC0805AW)'                                                        | '10UF'     | '6.3V'        | '10%'    | 'DISCRETE' | 'CAP CHIP 10UF.6.3V (+-10%.X5R.0805)'                          | 'CHIP0805'     | ''          | ''   | '20100929'
 '10UF'     | '6.3V'  | '10%'     | '0805'      | 'EMPTY'   | 'CH61001KA94'(!)   = 'End of Design' | 'Comp-Approve'     | ''       | 'CH61001KA94'    |'C0805_H61'| '(SMC0805AW)'                                                        | 'NA'       | '6.3V'        | '10%'    | 'IO'       | 'CAP CHIP 10UF.6.3V (+-10%.X5R.0805)'                          | 'CHIP0805'     | ''          | ''   | '20100929'
 '10PF'     | '50V'   | '5%'      | '0402'      | 'COG'     | 'CH01006JB08'(!)   = ''              | ''                 | ''       | 'CH01006JB08'    |'C0402'| '(C0402-0201)'                                                       | '10PF'     | '50V'         | '5%'     | 'DISCRETE' | 'CAP CHIP 10P 50V(+-5%,C0G,0402)'                              | 'CHIP0402'     | ''          | ''   | '20101013'
 '10PF'     | '50V'   | '5%'      | '0402'      | 'EMPTY'   | 'CH01006JB08'(!)   = ''              | ''                 | ''       | 'CH01006JB08'    |'C0402'| '(C0402-0201)'                                                       | 'NA'       | '50V'         | '5%'     | 'IO'       | 'CAP CHIP 10P 50V(+-5%,C0G,0402)'                              | 'CHIP0402'     | ''          | ''   | '20101013'
 '20PF'     | '50V'   | '5%'      | '0402'      | 'COG'     | 'CH0206J0B05'(!)   = ''              | ''                 | ''       | 'CH0206J0B05'    |'C0402'| '(C0402-0201)'                                                       | '20PF'     | '50V'         | '5%'     | 'DISCRETE' | 'CAP CHIP 20P 50V(+-5%,C0G,0402)'                              | 'CHIP0402'     | ''          | ''   | '20101026'
 '20PF'     | '50V'   | '5%'      | '0402'      | 'EMPTY'   | 'CH0206J0B05'(!)   = ''              | ''                 | ''       | 'CH0206J0B05'    |'C0402'| '(C0402-0201)'                                                       | 'NA'       | '50V'         | '5%'     | 'IO'       | 'CAP CHIP 20P 50V(+-5%,C0G,0402)'                              | 'CHIP0402'     | ''          | ''   | '20101026'
 '0.22UF'   | '6.3V'  | '10%'     | '0402'      | 'X5R'     | 'CH4221K9B00'(!)   = 'End of Design' | 'Comp-Approve'     | ''       | 'CH4221K9B00'    |'C0402'| '(C0402-0201)'                                                       | '0.22UF'   | '6.3V'        | '10%'    | 'DISCRETE' | 'CAP CHIP 0.22U 6.3V(+-10%,X5R,0402)'                          | 'CHIP0402'     | ''          | ''   | '20101026'
 '0.22UF'   | '6.3V'  | '10%'     | '0402'      | 'EMPTY'   | 'CH4221K9B00'(!)   = 'End of Design' | 'Comp-Approve'     | ''       | 'CH4221K9B00'    |'C0402'| '(C0402-0201)'                                                       | 'NA'       | '6.3V'        | '10%'    | 'IO'       | 'CAP CHIP 0.22U 6.3V(+-10%,X5R,0402)'                          | 'CHIP0402'     | ''          | ''   | '20101026'
 '1000PF'   | '2000V' | '10%'     | '1206'      | 'X7R'     | 'CH2100IK212'(!)   = ''              | ''                 | ''       | 'CH2100IK212'    |'C1206_H56'| '(SMC1206AW)'                                                        | '1000PF'   | '2KV'         | '10%'    | 'DISCRETE' | 'CAP CHIP 1000P 2KV(+-10%,X7R,1206)'                           | 'CHIP1206'     | ''          | ''   | '20101028'
 '1000PF'   | '2000V' | '10%'     | '1206'      | 'EMPTY'   | 'CH2100IK212'(!)   = ''              | ''                 | ''       | 'CH2100IK212'    |'C1206_H56'| '(SMC1206AW)'                                                        | 'NA'       | '2KV'         | '10%'    | 'IO'       | 'CAP CHIP 1000P 2KV(+-10%,X7R,1206)'                           | 'CHIP1206'     | ''          | ''   | '20101028'
 '18PF'     | '50V'   | '5%'      | '0402'      | 'C0G'     | 'CH01806JB07'(!)   = ''              | ''                 | ''       | 'CH01806JB07'    |'C0402'| '(C0402-0201)'                                                       | '18PF'     | '50V'         | '5%'     | 'DISCRETE' | 'CAP CHIP 18P 50V(+-5% C0G 0402)'                              | 'CHIP0402'     | ''          | ''   | '20110119'
 '18PF'     | '50V'   | '5%'      | '0402'      | 'EMPTY'   | 'CH01806JB07'(!)   = ''              | ''                 | ''       | 'CH01806JB07'    |'C0402'| '(C0402-0201)'                                                       | 'NA'       | '50V'         | '5%'     | 'IO'       | 'CAP CHIP 18P 50V(+-5% C0G 0402)'                              | 'CHIP0402'     | ''          | ''   | '20110119'
 '15PF'     | '50V'   | '5%'      | '0402'      | 'C0G'     | 'CH01506JB06'(!)   = ''              | ''                 | ''       | 'CH01506JB06'    |'C0402'| '(C0402-0201)'                                                       | '15PF'     | '50V'         | '5%'     | 'DISCRETE' | 'CAP CHIP 15P 50V(+-5% C0G 0402)'                              | 'CHIP0402'     | ''          | ''   | '20110207'
 '15PF'     | '50V'   | '5%'      | '0402'      | 'EMPTY'   | 'CH01506JB06'(!)   = ''              | ''                 | ''       | 'CH01506JB06'    |'C0402'| '(C0402-0201)'                                                       | 'NA'       | '50V'         | '5%'     | 'IO'       | 'CAP CHIP 15P 50V(+-5% C0G 0402)'                              | 'CHIP0402'     | ''          | ''   | '20110207'
 '1000PF'   | '3KV'   | '10%'     | '1808'      | 'X7R'     | 'CH2100GKI12'(!)   = ''              | ''                 | ''       | 'CH2100GKI12'    |'C1808_H86'| '(SMC1808AW)'                                                        | '1000PF'   | '3KV'         | '10%'    | 'DISCRETE' | 'CAP CHIP 1000P 3KV(+-10%.X7R.1808)'                           | 'CHIP1808'     | ''          | ''   | '20110207'
 '1000PF'   | '3KV'   | '10%'     | '1808'      | 'EMPTY'   | 'CH2100GKI12'(!)   = ''              | ''                 | ''       | 'CH2100GKI12'    |'C1808_H86'| '(SMC1808AW)'                                                        | 'NA'       | '3KV'         | '10%'    | 'IO'       | 'CAP CHIP 1000P 3KV(+-10%.X7R.1808)'                           | 'CHIP1808'     | ''          | ''   | '20110207'
 '3.3PF'    | '50V'   | '0.25P'   | '0402'      | 'C0G'     | 'CH-3306TB04'(!)   = ''              | ''                 | ''       | 'CH-3306TB04'    |'C0402'| '(C0402-0201)'                                                       | '3.3PF'    | '50V'         | '0.25P'  | 'DISCRETE' | 'CAP CHIP 3.3P 50V(+-0.25P C0G 0402)'                          | 'CHIP0402'     | ''          | ''   | '20110207'
 '3.3PF'    | '50V'   | '0.25P'   | '0402'      | 'EMPTY'   | 'CH-3306TB04'(!)   = ''              | ''                 | ''       | 'CH-3306TB04'    |'C0402'| '(C0402-0201)'                                                       | 'NA'       | '50V'         | '0.25P'  | 'IO'       | 'CAP CHIP 3.3P 50V(+-0.25P C0G 0402)'                          | 'CHIP0402'     | ''          | ''   | '20110207'
 '3PF'      | '50V'   | '0.25P'   | '0402'      | 'C0G'     | 'CH-3006TB03'(!)   = 'End of Design' | 'Comp-Approve'     | ''       | 'CH-3006TB03'    |'C0402'| '(C0402-0201)'                                                       | '3PF'      | '50V'         | '0.25P'  | 'DISCRETE' | 'CAP CHIP 3P 50V(+-0.25P,COG,0402)'                            | 'CHIP0402'     | ''          | ''   | '20110216'
 '3PF'      | '50V'   | '0.25P'   | '0402'      | 'EMPTY'   | 'CH-3006TB03'(!)   = 'End of Design' | 'Comp-Approve'     | ''       | 'CH-3006TB03'    |'C0402'| '(C0402-0201)'                                                       | 'NA'       | '50V'         | '0.25P'  | 'IO'       | 'CAP CHIP 3P 50V(+-0.25P,COG,0402)'                            | 'CHIP0402'     | ''          | ''   | '20110216'
 '10UF'     | '10V'   | '20%'     | '0603'      | 'X5R'     | 'CH6102M9900'(!)   = 'End of Design' | 'Comp-Approve'     | ''       | 'CH6102M9900'    |'C0603'| '(SMC0603AW)'                                                        | '10UF'     | '10V'         | '20%'    | 'DISCRETE' | 'CAP CHIP 10U 10V(+-20%.X5R.0603)'                             | 'CHIP0603'     | ''          | ''   | '20110223'
 '10UF'     | '10V'   | '20%'     | '0603'      | 'EMPTY'   | 'CH6102M9900'(!)   = 'End of Design' | 'Comp-Approve'     | ''       | 'CH6102M9900'    |'C0603'| '(SMC0603AW)'                                                        | 'NA'       | '10V'         | '20%'    | 'IO'       | 'CAP CHIP 10U 10V(+-20%.X5R.0603)'                             | 'CHIP0603'     | ''          | ''   | '20110223'
 '3.0PF'    | '50V'   | '0.25P'   | '0402'      | 'NPO'     | 'CH-306C0B07'(!)   = ''              | ''                 | ''       | 'CH-306C0B07'    |'C0402'| '(C0402-0201)'                                                       | '3.0PF'    | '50V'         | '0.25P'  | 'DISCRETE' | 'CAP CHIP 3P,50V(+-0.25P,NPO,0402)'                            | 'CHIP0402'     | ''          | ''   | '20110224'
 '3.0PF'    | '50V'   | '0.25P'   | '0402'      | 'EMPTY'   | 'CH-306C0B07'(!)   = ''              | ''                 | ''       | 'CH-306C0B07'    |'C0402'| '(C0402-0201)'                                                       | 'NA'       | '50V'         | '0.25P'  | 'IO'       | 'CAP CHIP 3P,50V(+-0.25P,NPO,0402)'                            | 'CHIP0402'     | ''          | ''   | '20110224'
 '6.8PF'    | '50V'   | '0.1P'    | '0402'      | 'NPO'     | 'CH-6816TB05'(!)   = 'End of Design' | 'Comp-Approve'     | ''       | 'CH-6816TB05'    |'C0402'| '(C0402-0201)'                                                       | '6.8PF'    | '50V'         | '0.1P'   | 'DISCRETE' | 'CAP CHIP 6.8P 50V (+-0.1P NPO 0402)'                          | 'CHIP0402'     | ''          | ''   | '20110224'
 '6.8PF'    | '50V'   | '0.1P'    | '0402'      | 'EMPTY'   | 'CH-6816TB05'(!)   = 'End of Design' | 'Comp-Approve'     | ''       | 'CH-6816TB05'    |'C0402'| '(C0402-0201)'                                                       | 'NA'       | '50V'         | '0.1P'   | 'IO'       | 'CAP CHIP 6.8P 50V (+-0.1P NPO 0402)'                          | 'CHIP0402'     | ''          | ''   | '20110224'
 '1UF'      | '25V'   | '10%'     | '0603'      | 'X7R'     | 'CH5104K1900'(!)   = 'End of Design' | 'Comp-Approve'     | ''       | 'CH5104K1900'    |'C0603'| '(SMC0603AW)'                                                        | '1UF'      | '25V'         | '10%'    | 'DISCRETE' | 'CAP CHIP 1U 25V(+-10%.X7R.0603)'                              | 'CHIP0603'     | ''          | ''   | '20110330'
 '1UF'      | '25V'   | '10%'     | '0603'      | 'EMPTY'   | 'CH5104K1900'(!)   = 'End of Design' | 'Comp-Approve'     | ''       | 'CH5104K1900'    |'C0603'| '(SMC0603AW)'                                                        | 'NA'       | '25V'         | '10%'    | 'IO'       | 'CAP CHIP 1U 25V(+-10%.X7R.0603)'                              | 'CHIP0603'     | ''          | ''   | '20110330'
 '0.022UF'  | '25V'   | '10%'     | '0402'      | 'X7R'     | 'CH3224K1B01'(!)   = ''              | ''                 | ''       | 'CH3224K1B01'    |'C0402'| '(C0402_OCTAGONXA,C0402-0201)'                                       | '0.022UF'  | '25V'         | '10%'    | 'DISCRETE' | 'CAP CHIP 0.022U 25V(+-10%,X7R,0402)'                          | 'CHIP0402'     | ''          | ''   | '20110413'
 '0.022UF'  | '25V'   | '10%'     | '0402'      | 'EMPTY'   | 'CH3224K1B01'(!)   = ''              | ''                 | ''       | 'CH3224K1B01'    |'C0402'| '(C0402_OCTAGONXA,C0402-0201)'                                       | 'NA'       | '25V'         | '10%'    | 'IO'       | 'CAP CHIP 0.022U 25V(+-10%,X7R,0402)'                          | 'CHIP0402'     | ''          | ''   | '20110413'
 '4.7UF'    | '4V'    | '10%'     | '0603'      | 'X6S'     | 'CH547KKE900'(!)   = 'End of Design' | 'Comp-Approve'     | ''       | 'CH547KKE900'    |'C0603'| '(SMC0603AW)'                                                        | '4.7UF'    | '4V'          | '10%'    | 'DISCRETE' | 'CAP CHIP 4.7U 4V(+-10%,X6S,0603)'                             | 'CHIP0603'     | ''          | ''   | '20110414'
 '4.7UF'    | '4V'    | '10%'     | '0603'      | 'EMPTY'   | 'CH547KKE900'(!)   = 'End of Design' | 'Comp-Approve'     | ''       | 'CH547KKE900'    |'C0603'| '(SMC0603AW)'                                                        | 'NA'       | '4V'          | '10%'    | 'IO'       | 'CAP CHIP 4.7U 4V(+-10%,X6S,0603)'                             | 'CHIP0603'     | ''          | ''   | '20110414'
 '10UF'     | '6.3V'  | '10%'     | '0805'      | 'X7R'     | 'CH6101K1A00'(!)   = 'End of Design' | 'Comp-Approve'     | ''       | 'CH6101K1A00'    |'C0805_H61'| '(SMC0805AW)'                                                        | '10UF'     | '6.3V'        | '10%'    | 'DISCRETE' | 'CAP CHIP 10UF 6.3V(+-10%,X7R,0805)H1.25'                      | 'CHIP0805'     | ''          | ''   | '20110415'
 '10UF'     | '6.3V'  | '10%'     | '0805'      | 'EMPTY'   | 'CH6101K1A00'(!)   = 'End of Design' | 'Comp-Approve'     | ''       | 'CH6101K1A00'    |'C0805_H61'| '(SMC0805AW)'                                                        | 'NA'       | '6.3V'        | '10%'    | 'IO'       | 'CAP CHIP 10UF 6.3V(+-10%,X7R,0805)H1.25'                      | 'CHIP0805'     | ''          | ''   | '20110415'
 '10UF'     | '6.3V'  | '20%'     | '0805'      | 'X6S'     | 'CH61001MEE3'(!)   = 'End of Design' | 'Comp-Approve'     | ''       | 'CH61001MEE3'    |'C0805_H61'| '(SMC0805AW)'                                                        | '10UF'     | '6.3V'        | '20%'    | 'DISCRETE' | 'CAP CHIP 10UF 6.3V(+-20%.X6S.0805)'                           | 'CHIP0805'     | ''          | ''   | '20110415'
 '10UF'     | '6.3V'  | '20%'     | '0805'      | 'EMPTY'   | 'CH61001MEE3'(!)   = 'End of Design' | 'Comp-Approve'     | ''       | 'CH61001MEE3'    |'C0805_H61'| '(SMC0805AW)'                                                        | 'NA'       | '6.3V'        | '20%'    | 'IO'       | 'CAP CHIP 10UF 6.3V(+-20%.X6S.0805)'                           | 'CHIP0805'     | ''          | ''   | '20110415'
 '10UF'     | '4V'    | '20%'     | '0805'      | 'X6S'     | 'CH6100KMEE3'(!)   = 'End of Design' | 'Comp-Approve'     | ''       | 'CH6100KMEE3'    |'C0805_H61'| '(SMC0805AW)'                                                        | '10UF'     | '4V'          | '20%'    | 'DISCRETE' | 'CAP CHIP 10U.4V(+-20%.X6S.0805) EP'                           | 'CHIP0805'     | ''          | ''   | '20110415'
 '10UF'     | '4V'    | '20%'     | '0805'      | 'EMPTY'   | 'CH6100KMEE3'(!)   = 'End of Design' | 'Comp-Approve'     | ''       | 'CH6100KMEE3'    |'C0805_H61'| '(SMC0805AW)'                                                        | 'NA'       | '4V'          | '20%'    | 'IO'       | 'CAP CHIP 10U.4V(+-20%.X6S.0805) EP'                           | 'CHIP0805'     | ''          | ''   | '20110415'
 '10UF'     | '4V'    | '20%'     | '0603'      | 'X6S'     | 'CH610KME901'(!)   = ''              | 'End of Life'      | ''       | 'CH610KME901'    |'C0603_EOL'| '(SMC0603AW)'                                                        | '10UF'     | '4V'          | '20%'    | 'DISCRETE' | 'CAP CHIP 10U 4V(+-20%,X6S,0603)'                              | 'CHIP0603'     | ''          | ''   | '20110415'
 '10UF'     | '4V'    | '20%'     | '0603'      | 'EMPTY'   | 'CH610KME901'(!)   = ''              | 'End of Life'      | ''       | 'CH610KME901'    |'C0603_EOL'| '(SMC0603AW)'                                                        | 'NA'       | '4V'          | '20%'    | 'IO'       | 'CAP CHIP 10U 4V(+-20%,X6S,0603)'                              | 'CHIP0603'     | ''          | ''   | '20110415'
 '4.7UF'    | '16V'   | '20%'     | '0805'      | 'X7R'     | 'CH5473M1A01'(!)   = 'End of Design' | 'Comp-Approve'     | ''       | 'CH5473M1A01'    |'C0805_H61'| '(SMC0805AW)'                                                        | '4.7UF'    | '16V'         | '20%'    | 'DISCRETE' | 'CAP CHIP 4.7U 16V(+-20%,X7R,0805)H1.25'                       | 'CHIP0805'     | ''          | ''   | '20110425'
 '4.7UF'    | '16V'   | '20%'     | '0805'      | 'EMPTY'   | 'CH5473M1A01'(!)   = 'End of Design' | 'Comp-Approve'     | ''       | 'CH5473M1A01'    |'C0805_H61'| '(SMC0805AW)'                                                        | 'NA'       | '16V'         | '20%'    | 'IO'       | 'CAP CHIP 4.7U 16V(+-20%,X7R,0805)H1.25'                       | 'CHIP0805'     | ''          | ''   | '20110425'
 '1500PF'   | '50V'   | '10%'     | '0603'      | 'X7R'     | 'CH21506K915'(!)   = 'End of Design' | 'Comp-Approve'     | ''       | 'CH21506K915'    |'C0603'| '(SMC0603AW)'                                                        | '1500PF'   | '50V'         | '10%'    | 'DISCRETE' | 'CAP CHIP 1500P 50V(+-10%.X7R.0603)'                           | 'CHIP0603'     | ''          | ''   | '20110624'
 '1500PF'   | '50V'   | '10%'     | '0603'      | 'EMPTY'   | 'CH21506K915'(!)   = 'End of Design' | 'Comp-Approve'     | ''       | 'CH21506K915'    |'C0603'| '(SMC0603AW)'                                                        | 'NA'       | '50V'         | '10%'    | 'IO'       | 'CAP CHIP 1500P 50V(+-10%.X7R.0603)'                           | 'CHIP0603'     | ''          | ''   | '20110624'
 '12PF'     | '50V'   | '2%'      | '0402'      | 'C0G'     | 'CH0126G0B00'(!)   = ''              | ''                 | ''       | 'CH0126G0B00'    |'C0402'| '(C0402-0201)'                                                       | '12PF'     | '50V'         | '2%'     | 'DISCRETE' | 'CAP CHIP 12P 50V(+-2%,C0G,0402)'                              | 'CHIP0402'     | ''          | ''   | '20110628'
 '12PF'     | '50V'   | '2%'      | '0402'      | 'EMPTY'   | 'CH0126G0B00'(!)   = ''              | ''                 | ''       | 'CH0126G0B00'    |'C0402'| '(C0402-0201)'                                                       | 'NA'       | '50V'         | '2%'     | 'IO'       | 'CAP CHIP 12P 50V(+-2%,C0G,0402)'                              | 'CHIP0402'     | ''          | ''   | '20110628'
 '39PF'     | '50V'   | '5%'      | '0402'      | 'NPO'     | 'CH03906JB06'(!)   = ''              | ''                 | ''       | 'CH03906JB06'    |'C0402'| '(C0402-0201)'                                                       | '39PF'     | '50V'         | '5%'     | 'DISCRETE' | 'CAP CHIP 39P 50V(+-5%.NPO.0402)'                              | 'CHIP0402'     | ''          | ''   | '20110628'
 '39PF'     | '50V'   | '5%'      | '0402'      | 'EMPTY'   | 'CH03906JB06'(!)   = ''              | ''                 | ''       | 'CH03906JB06'    |'C0402'| '(C0402-0201)'                                                       | 'NA'       | '50V'         | '5%'     | 'IO'       | 'CAP CHIP 39P 50V(+-5%.NPO.0402)'                              | 'CHIP0402'     | ''          | ''   | '20110628'
 '4.7UF'    | '10V'   | '10%'     | '0805'      | 'X7R'     | 'CH5472K1A00'(!)   = 'End of Design' | 'Comp-Approve'     | 'SELASS' | 'CH5472K1A00'    |'C0805_H61'| '(SMC0805AW)'                                                        | '4.7UF'    | '10V'         | '10%'    | 'DISCRETE' | 'CAP CHIP 4.7UF 10V(+-10%.X7R.0805)SELASS'                     | 'CHIP0805'     | ''          | ''   | '20100823'
 '4.7UF'    | '10V'   | '10%'     | '0805'      | 'EMPTY'   | 'CH5472K1A00'(!)   = 'End of Design' | 'Comp-Approve'     | 'SELASS' | 'CH5472K1A00'    |'C0805_H61'| '(SMC0805AW)'                                                        | 'NA'       | '10V'         | '10%'    | 'IO'       | 'CAP CHIP 4.7UF 10V(+-10%.X7R.0805)SELASS'                     | 'CHIP0805'     | ''          | ''   | '20100823'
 '3.3UF'    | '10V'   | '10%'     | '0603'      | 'X5R'     | 'CH5332K9900'(!)   = 'End of Design' | 'Comp-Approve'     | ''       | 'CH5332K9900'    |'C0603'| '(SMC0603AW)'                                                        | '3.3UF'    | '10V'         | '10%'    | 'DISCRETE' | 'CAP CHIP 3.3U 10V(+-10%,X5R,0603)'                            | 'CHIP0603'     | ''          | ''   | '20110720'
 '3.3UF'    | '10V'   | '10%'     | '0603'      | 'EMPTY'   | 'CH5332K9900'(!)   = 'End of Design' | 'Comp-Approve'     | ''       | 'CH5332K9900'    |'C0603'| '(SMC0603AW)'                                                        | 'NA'       | '10V'         | '10%'    | 'IO'       | 'CAP CHIP 3.3U 10V(+-10%,X5R,0603)'                            | 'CHIP0603'     | ''          | ''   | '20110720'
 '1800PF'   | '50V'   | '10%'     | '0402'      | 'X7R'     | 'CH21806KB15'(!)   = ''              | ''                 | ''       | 'CH21806KB15'    |'C0402'| '(C0402-0201)'                                                       | '1800PF'   | '50V'         | '10%'    | 'DISCRETE' | 'CAP CHIP 1800P 50V(+-10%.X7R.0402)'                           | 'CHIP0402'     | ''          | ''   | '20110826'
 '1800PF'   | '50V'   | '10%'     | '0402'      | 'EMPTY'   | 'CH21806KB15'(!)   = ''              | ''                 | ''       | 'CH21806KB15'    |'C0402'| '(C0402-0201)'                                                       | 'NA'       | '50V'         | '10%'    | 'IO'       | 'CAP CHIP 1800P 50V(+-10%.X7R.0402)'                           | 'CHIP0402'     | ''          | ''   | '20110826'
 '4700PF'   | '50V'   | '10%'     | '0603'      | 'X7R'     | 'CH2476K1929'(!)   = 'End of Design' | 'Comp-Approve'     | ''       | 'CH2476K1929'    |'C0603'| '(SMC0603AW)'                                                        | '4700PF'   | '50V'         | '10%'    | 'DISCRETE' | 'CAP CHIP 4700P,50V(+-10%,X7R,0603)'                           | 'CHIP0603'     | ''          | ''   | '20110920'
 '4700PF'   | '50V'   | '10%'     | '0603'      | 'EMPTY'   | 'CH2476K1929'(!)   = 'End of Design' | 'Comp-Approve'     | ''       | 'CH2476K1929'    |'C0603'| '(SMC0603AW)'                                                        | 'NA'       | '50V'         | '10%'    | 'IO'       | 'CAP CHIP 4700P,50V(+-10%,X7R,0603)'                           | 'CHIP0603'     | ''          | ''   | '20110920'
 '0.1UF'    | '10V'   | '10%'     | '0201'      | 'X5R'     | 'CH4102K9E00'(!)   = ''              | ''                 | ''       | 'CH4102K9E00'    |'C0201'| '(SMC0201AW)'                                                        | '0.1UF'    | '10V'         | '10%'    | 'DISCRETE' | 'CAP CHIP 0.1U 10V(+-10%.X5R.0201)'                            | 'CHIP0201'     | ''          | ''   | '20111207'
 '0.1UF'    | '10V'   | '10%'     | '0201'      | 'EMPTY'   | 'CH4102K9E00'(!)   = ''              | ''                 | ''       | 'CH4102K9E00'    |'C0201'| '(SMC0201AW)'                                                        | 'NA'       | '10V'         | '10%'    | 'IO'       | 'CAP CHIP 0.1U 10V(+-10%.X5R.0201)'                            | 'CHIP0201'     | ''          | ''   | '20111207'
 '27PF'     | '50V'   | '5%'      | '0603'      | 'NPO'     | 'CH0276J0905'(!)   = 'End of Design' | 'Comp-Approve'     | 'SELASS' | 'CH0276J0905'    |'C0603'| '(SMC0603AW)'                                                        | '27PF'     | '50V'         | '5%'     | 'DISCRETE' | 'CAP CHIP 27P 50V(+-5%.NPO.0603)SELASS'                        | 'CHIP0603'     | ''          | ''   | '20111208'
 '27PF'     | '50V'   | '5%'      | '0603'      | 'EMPTY'   | 'CH0276J0905'(!)   = 'End of Design' | 'Comp-Approve'     | 'SELASS' | 'CH0276J0905'    |'C0603'| '(SMC0603AW)'                                                        | 'NA'       | '50V'         | '5%'     | 'IO'       | 'CAP CHIP 27P 50V(+-5%.NPO.0603)SELASS'                        | 'CHIP0603'     | ''          | ''   | '20111208'
 '0.015UF'  | '16V'   | '10%'     | '0402'      | 'X7R'     | 'CH3153K1B12'(!)   = ''              | ''                 | ''       | 'CH3153K1B12'    |'C0402'| '(C0402-0201)'                                                       | '0.015UF'  | '16V'         | '10%'    | 'DISCRETE' | 'CAP CHIP 0.015U 16V(+-10%.X7R.0402)'                          | 'CHIP0402'     | ''          | ''   | '20111209'
 '0.015UF'  | '16V'   | '10%'     | '0402'      | 'EMPTY'   | 'CH3153K1B12'(!)   = ''              | ''                 | ''       | 'CH3153K1B12'    |'C0402'| '(C0402-0201)'                                                       | 'NA'       | '16V'         | '10%'    | 'IO'       | 'CAP CHIP 0.015U 16V(+-10%.X7R.0402)'                          | 'CHIP0402'     | ''          | ''   | '20111209'
 '0.047UF'  | '10V'   | '10%'     | '0402'      | 'X7R'     | 'CH34702KB10'(!)   = ''              | ''                 | ''       | 'CH34702KB10'    |'C0402'| '(C0402-0201)'                                                       | '0.047UF'  | '10V'         | '10%'    | 'DISCRETE' | 'CAP CHIP 0.047U 10V(+-10% X7R 0402)'                          | 'CHIP0402'     | ''          | ''   | '20111209'
 '0.047UF'  | '10V'   | '10%'     | '0402'      | 'EMPTY'   | 'CH34702KB10'(!)   = ''              | ''                 | ''       | 'CH34702KB10'    |'C0402'| '(C0402-0201)'                                                       | 'NA'       | '10V'         | '10%'    | 'IO'       | 'CAP CHIP 0.047U 10V(+-10% X7R 0402)'                          | 'CHIP0402'     | ''          | ''   | '20111209'
 '10PF'     | '50V'   | '0.5P'    | 'C0402'     | 'COH'     | 'CH01006JBD1'(!)   = 'End of Design' | 'Comp-Approve'     | ''       | 'CH01006JBD1'    |'C0402'| '(C0402-0201)'                                                       | '10PF'     | '50V'         | '0.5P'   | 'DISCRETE' | 'CAP CHIP 10P 50V(+-0.5P.COH.0402)'                            | 'CHIP0402'     | ''          | ''   | '20111213'
 '10PF'     | '50V'   | '0.5P'    | 'C0402'     | 'EMPTY'   | 'CH01006JBD1'(!)   = 'End of Design' | 'Comp-Approve'     | ''       | 'CH01006JBD1'    |'C0402'| '(C0402-0201)'                                                       | 'NA'       | '50V'         | '0.5P'   | 'IO'       | 'CAP CHIP 10P 50V(+-0.5P.COH.0402)'                            | 'CHIP0402'     | ''          | ''   | '20111213'
 '0.01UF'   | '50V'   | '5%'      | 'C0603'     | 'X7R'     | 'CH3106J1905'(!)   = 'End of Design' | 'Comp-Approve'     | ''       | 'CH3106J1905'    |'C0603'| '(SMC0603AW)'                                                        | '0.01UF'   | '50V'         | '5%'     | 'DISCRETE' | 'CAP CHIP 0.01U 50V(+-5%.X7R.0603)'                            | 'CHIP0603'     | ''          | ''   | '20111213'
 '0.01UF'   | '50V'   | '5%'      | 'C0603'     | 'EMPTY'   | 'CH3106J1905'(!)   = 'End of Design' | 'Comp-Approve'     | ''       | 'CH3106J1905'    |'C0603'| '(SMC0603AW)'                                                        | 'NA'       | '50V'         | '5%'     | 'IO'       | 'CAP CHIP 0.01U 50V(+-5%.X7R.0603)'                            | 'CHIP0603'     | ''          | ''   | '20111213'
 '0.1UF'    | '16V'   | '10%'     | 'C0603'     | 'X7R'     | 'CH41003K914'(!)   = 'End of Design' | 'Comp-Approve'     | ''       | 'CH41003K914'    |'C0603'| '(SMC0603AW)'                                                        | '0.1UF'    | '16V'         | '10%'    | 'DISCRETE' | 'CAP CHIP 0.1U 16V(+-10%. X7R.0603)'                           | 'CHIP0603'     | ''          | ''   | '20111213'
 '0.1UF'    | '16V'   | '10%'     | 'C0603'     | 'EMPTY'   | 'CH41003K914'(!)   = 'End of Design' | 'Comp-Approve'     | ''       | 'CH41003K914'    |'C0603'| '(SMC0603AW)'                                                        | 'NA'       | '16V'         | '10%'    | 'IO'       | 'CAP CHIP 0.1U 16V(+-10%. X7R.0603)'                           | 'CHIP0603'     | ''          | ''   | '20111213'
 '4.7UF'    | '6.3V'  | '10%'     | 'C0603'     | 'X5R'     | 'CH5471K9E07'(!)   = 'End of Design' | 'Comp-Release Qty' | ''       | 'CH5471K9E07'    |'C0603'| '(SMC0603AW)'                                                        | '4.7UF'    | '6.3V'        | '10%'    | 'DISCRETE' | 'CAP CHIP 4.7U 6.3V(+-10%.X5R.0603)'                           | 'CHIP0603'     | ''          | ''   | '20111213'
 '4.7UF'    | '6.3V'  | '10%'     | 'C0603'     | 'EMPTY'   | 'CH5471K9E07'(!)   = 'End of Design' | 'Comp-Release Qty' | ''       | 'CH5471K9E07'    |'C0603'| '(SMC0603AW)'                                                        | 'NA'       | '6.3V'        | '10%'    | 'IO'       | 'CAP CHIP 4.7U 6.3V(+-10%.X5R.0603)'                           | 'CHIP0603'     | ''          | ''   | '20111213'
 '8200PF'   | '25V'   | '10%'     | 'C0402'     | 'X7R'     | 'CH2824K1B05'(!)   = ''              | ''                 | ''       | 'CH2824K1B05'    |'C0402'| '(C0402-0201)'                                                       | '8200PF'   | '25V'         | '10%'    | 'DISCRETE' | 'CAP CHIP 8200P 25V (+-10%.X7R.0402)'                          | 'CHIP0402'     | ''          | ''   | '20111229'
 '8200PF'   | '25V'   | '10%'     | 'C0402'     | 'EMPTY'   | 'CH2824K1B05'(!)   = ''              | ''                 | ''       | 'CH2824K1B05'    |'C0402'| '(C0402-0201)'                                                       | 'NA'       | '25V'         | '10%'    | 'IO'       | 'CAP CHIP 8200P 25V (+-10%.X7R.0402)'                          | 'CHIP0402'     | ''          | ''   | '20111229'
 '100PF'    | '50V'   | '5%'      | 'C0402_SEL' | 'C0G'     | 'CH1106J0B09'(!)   = ''              | ''                 | 'SELASS' | 'CH1106J0B09'    |'C0402'| '(C0402-0201)'                                                       | '100PF'    | '50V'         | '5%'     | 'DISCRETE' | 'CAP CHIP 100P 50V(+-5%.C0G.0402)SEL ASN'                      | 'CHIP0402'     | ''          | ''   | '20111229'
 '100PF'    | '50V'   | '5%'      | 'C0402_SEL' | 'EMPTY'   | 'CH1106J0B09'(!)   = ''              | ''                 | 'SELASS' | 'CH1106J0B09'    |'C0402'| '(C0402-0201)'                                                       | 'NA'       | '50V'         | '5%'     | 'IO'       | 'CAP CHIP 100P 50V(+-5%.C0G.0402)SEL ASN'                      | 'CHIP0402'     | ''          | ''   | '20111229'
 '22UF'     | '6.3V'  | '10%'     | 'C0805_SEL' | 'X5R'     | 'CH6221M9A16'(!)   = ''              | ''                 | 'SELASS' | 'CH6221M9A16'    |'C0805_H61'| '(SMC0805AW)'                                                        | '22UF'     | '6.3V'        | '10%'    | 'DISCRETE' | 'CAP CHIP 22U 6.3V(+-20%.X5R.0805)SELASS'                      | 'CHIP0805'     | ''          | ''   | '20111229'
 '22UF'     | '6.3V'  | '10%'     | 'C0805_SEL' | 'EMPTY'   | 'CH6221M9A16'(!)   = ''              | ''                 | 'SELASS' | 'CH6221M9A16'    |'C0805_H61'| '(SMC0805AW)'                                                        | 'NA'       | '6.3V'        | '10%'    | 'IO'       | 'CAP CHIP 22U 6.3V(+-20%.X5R.0805)SELASS'                      | 'CHIP0805'     | ''          | ''   | '20111229'
 '0.033UF'  | '16V'   | '10%'     | 'C0402'     | 'X7R'     | 'CH3333K1B02'(!)   = 'End of Design' | 'Comp-Release Qty' | ''       | 'CH3333K1B02'    |'C0402'| '(C0402-0201)'                                                       | '0.033UF'  | '16V'         | '10%'    | 'DISCRETE' | 'CAP CHIP 0.033U 16V(+-10%.X7R.0402)'                          | 'CHIP0402'     | ''          | ''   | '20111230'
 '0.033UF'  | '16V'   | '10%'     | 'C0402'     | 'EMPTY'   | 'CH3333K1B02'(!)   = 'End of Design' | 'Comp-Release Qty' | ''       | 'CH3333K1B02'    |'C0402'| '(C0402-0201)'                                                       | 'NA'       | '16V'         | '10%'    | 'IO'       | 'CAP CHIP 0.033U 16V(+-10%.X7R.0402)'                          | 'CHIP0402'     | ''          | ''   | '20111230'
 '470PF'    | '50V'   | '5%'      | 'C0402'     | 'NPO'     | 'CH1476J0B08'(!)   = ''              | ''                 | ''       | 'CH1476J0B08'    |'C0402'| '(C0402-0201)'                                                       | '470PF'    | '50V'         | '5%'     | 'DISCRETE' | 'CAP CHIP 470P,50V(+-5%,NPO,0402)'                             | 'CHIP0402'     | ''          | ''   | '20120113'
 '470PF'    | '50V'   | '5%'      | 'C0402'     | 'EMPTY'   | 'CH1476J0B08'(!)   = ''              | ''                 | ''       | 'CH1476J0B08'    |'C0402'| '(C0402-0201)'                                                       | 'NA'       | '50V'         | '5%'     | 'IO'       | 'CAP CHIP 470P,50V(+-5%,NPO,0402)'                             | 'CHIP0402'     | ''          | ''   | '20120113'
 '6800PF'   | '50V'   | '10%'     | 'C0402'     | 'X7R'     | 'CH2686K1B01'(!)   = ''              | ''                 | ''       | 'CH2686K1B01'    |'C0402'| '(C0402-0201)'                                                       | '6800PF'   | '50V'         | '10%'    | 'DISCRETE' | 'CAP CHIP 6800P 50V(+-10%,X7R,0402)'                           | 'CHIP0402'     | ''          | ''   | '20120113'
 '6800PF'   | '50V'   | '10%'     | 'C0402'     | 'EMPTY'   | 'CH2686K1B01'(!)   = ''              | ''                 | ''       | 'CH2686K1B01'    |'C0402'| '(C0402-0201)'                                                       | 'NA'       | '50V'         | '10%'    | 'IO'       | 'CAP CHIP 6800P 50V(+-10%,X7R,0402)'                           | 'CHIP0402'     | ''          | ''   | '20120113'
 '0.047UF'  | '16V'   | '10%'     | 'C0402'     | 'X7R'     | 'CH3473K1B00'(!)   = ''              | ''                 | ''       | 'CH3473K1B00'    |'C0402'| '(C0402-0201)'                                                       | '0.047UF'  | '16V'         | '10%'    | 'DISCRETE' | 'CAP CHIP 0.047U 16V(+-10%,X7R,0402)'                          | 'CHIP0402'     | ''          | ''   | '20120113'
 '0.047UF'  | '16V'   | '10%'     | 'C0402'     | 'EMPTY'   | 'CH3473K1B00'(!)   = ''              | ''                 | ''       | 'CH3473K1B00'    |'C0402'| '(C0402-0201)'                                                       | 'NA'       | '16V'         | '10%'    | 'IO'       | 'CAP CHIP 0.047U 16V(+-10%,X7R,0402)'                          | 'CHIP0402'     | ''          | ''   | '20120113'
 '0.068UF'  | '25V'   | '10%'     | 'C0603'     | 'X7R'     | 'CH3684K1904'(!)   = 'End of Design' | 'Comp-Approve'     | ''       | 'CH3684K1904'    |'C0603'| '(SMC0603AW)'                                                        | '0.068UF'  | '25V'         | '10%'    | 'DISCRETE' | 'CAP CHIP 0.068UF 25V(10%,X7R,0603)'                           | 'CHIP0603'     | ''          | ''   | '20120113'
 '0.068UF'  | '25V'   | '10%'     | 'C0603'     | 'EMPTY'   | 'CH3684K1904'(!)   = 'End of Design' | 'Comp-Approve'     | ''       | 'CH3684K1904'    |'C0603'| '(SMC0603AW)'                                                        | 'NA'       | '25V'         | '10%'    | 'IO'       | 'CAP CHIP 0.068UF 25V(10%,X7R,0603)'                           | 'CHIP0603'     | ''          | ''   | '20120113'
 '0.1UF'    | '100V'  | '10%'     | 'C0805'     | 'X7R'     | 'CH4108K1A00'(!)   = 'End of Design' | 'Comp-Approve'     | ''       | 'CH4108K1A00'    |'C0805_H61'| '(SMC0805AW)'                                                        | '0.1UF'    | '100V'        | '10%'    | 'DISCRETE' | 'CAP CHIP 0.1UF 100V(+-10%,X7R,0805)H1.25'                     | 'CHIP0805'     | ''          | ''   | '20120114'
 '0.1UF'    | '100V'  | '10%'     | 'C0805'     | 'EMPTY'   | 'CH4108K1A00'(!)   = 'End of Design' | 'Comp-Approve'     | ''       | 'CH4108K1A00'    |'C0805_H61'| '(SMC0805AW)'                                                        | 'NA'       | '100V'        | '10%'    | 'IO'       | 'CAP CHIP 0.1UF 100V(+-10%,X7R,0805)H1.25'                     | 'CHIP0805'     | ''          | ''   | '20120114'
 '4.7UF'    | '16V'   | '10%'     | 'C0805'     | 'X7R'     | 'CH5473K1A00'(!)   = 'End of Design' | 'Comp-Approve'     | ''       | 'CH5473K1A00'    |'C0805_H61'| '(SMC0805AW)'                                                        | '4.7UF'    | '16V'         | '10%'    | 'DISCRETE' | 'CAP CHIP 4.7UF 16V(+-10%,X7R,0805,H1.25)'                     | 'CHIP0805'     | ''          | ''   | '20120114'
 '4.7UF'    | '16V'   | '10%'     | 'C0805'     | 'EMPTY'   | 'CH5473K1A00'(!)   = 'End of Design' | 'Comp-Approve'     | ''       | 'CH5473K1A00'    |'C0805_H61'| '(SMC0805AW)'                                                        | 'NA'       | '16V'         | '10%'    | 'IO'       | 'CAP CHIP 4.7UF 16V(+-10%,X7R,0805,H1.25)'                     | 'CHIP0805'     | ''          | ''   | '20120114'
 '0.22UF'   | '25V'   | '10%'     | 'C0603'     | 'X5R'     | 'CH4224K9904'(!)   = ''              | ''                 | ''       | 'CH4224K9904'    |'C0603'| '(SMC0603AW)'                                                        | '0.22UF'   | '25V'         | '10%'    | 'DISCRETE' | 'CAP CHIP 0.22U 25V(10%.X5R.0603)'                             | 'CHIP0603'     | ''          | ''   | '20120114'
 '0.22UF'   | '25V'   | '10%'     | 'C0603'     | 'EMPTY'   | 'CH4224K9904'(!)   = ''              | ''                 | ''       | 'CH4224K9904'    |'C0603'| '(SMC0603AW)'                                                        | 'NA'       | '25V'         | '10%'    | 'IO'       | 'CAP CHIP 0.22U 25V(10%.X5R.0603)'                             | 'CHIP0603'     | ''          | ''   | '20120114'
 '2200PF'   | '2KV'   | '10%'     | 'C1812'     | 'X7R'     | 'CH222IK1400'(!)   = ''              | ''                 | ''       | 'CH222IK1400'    |'C1812_H63'| '(SMC1812AW)'                                                        | '2200PF'   | '2KV'         | '10%'    | 'DISCRETE' | 'CAP CHIP 2200PF 2KV(+-10%.X7R.1812)H1.3'                      | 'CHIP1812'     | ''          | ''   | '20120116'
 '2200PF'   | '2KV'   | '10%'     | 'C1812'     | 'EMPTY'   | 'CH222IK1400'(!)   = ''              | ''                 | ''       | 'CH222IK1400'    |'C1812_H63'| '(SMC1812AW)'                                                        | 'NA'       | '2KV'         | '10%'    | 'IO'       | 'CAP CHIP 2200PF 2KV(+-10%.X7R.1812)H1.3'                      | 'CHIP1812'     | ''          | ''   | '20120116'
 '1UF'      | '100V'  | '10%'     | 'C1206'     | 'X7R'     | 'CH5108K1202'(!)   = 'End of Design' | 'Comp-Approve'     | ''       | 'CH5108K1202'    |'C1206_H66'| '(SMC1206AW)'                                                        | '1UF'      | '100V'        | '10%'    | 'DISCRETE' | 'CAP CHIP 1U 100V(10%.1206.X7R)'                               | 'CHIP1206'     | ''          | ''   | '20120116'
 '1UF'      | '100V'  | '10%'     | 'C1206'     | 'EMPTY'   | 'CH5108K1202'(!)   = 'End of Design' | 'Comp-Approve'     | ''       | 'CH5108K1202'    |'C1206_H66'| '(SMC1206AW)'                                                        | 'NA'       | '100V'        | '10%'    | 'IO'       | 'CAP CHIP 1U 100V(10%.1206.X7R)'                               | 'CHIP1206'     | ''          | ''   | '20120116'
 '0.15UF'   | '10V'   | '10%'     | 'C0603'     | 'X7R'     | 'CH41502K909'(!)   = ''              | ''                 | ''       | 'CH41502K909'    |'C0603'| '(SMC0603AW)'                                                        | '0.15UF'   | '10V'         | '10%'    | 'DISCRETE' | 'CAP CHIP 0.15U 10V(+-10%.X7R.0603)'                           | 'CHIP0603'     | ''          | ''   | '20120119'
 '0.15UF'   | '10V'   | '10%'     | 'C0603'     | 'EMPTY'   | 'CH41502K909'(!)   = ''              | ''                 | ''       | 'CH41502K909'    |'C0603'| '(SMC0603AW)'                                                        | 'NA'       | '10V'         | '10%'    | 'IO'       | 'CAP CHIP 0.15U 10V(+-10%.X7R.0603)'                           | 'CHIP0603'     | ''          | ''   | '20120119'
 '33PF'     | '16V'   | '5%'      | 'C0402'     | 'NP0'     | 'CH0333J0B00'(!)   = 'End of Design' | 'Comp-Approve'     | ''       | 'CH0333J0B00'    |'C0402'| '(C0402-0201)'                                                       | '33PF'     | '16V'         | '5%'     | 'DISCRETE' | 'CAP CHIP 33P 16V(+-5%,NP0,0402)'                              | 'CHIP0402'     | ''          | ''   | '20120120'
 '33PF'     | '16V'   | '5%'      | 'C0402'     | 'EMPTY'   | 'CH0333J0B00'(!)   = 'End of Design' | 'Comp-Approve'     | ''       | 'CH0333J0B00'    |'C0402'| '(C0402-0201)'                                                       | 'NA'       | '16V'         | '5%'     | 'IO'       | 'CAP CHIP 33P 16V(+-5%,NP0,0402)'                              | 'CHIP0402'     | ''          | ''   | '20120120'
 '1500PF'   | '100V'  | '10%'     | 'C0402'     | 'X7R'     | 'CH2158K1B00'(!)   = 'End of Design' | 'Comp-Approve'     | ''       | 'CH2158K1B00'    |'C0402'| '(C0402-0201)'                                                       | '1500PF'   | '100V'        | '10%'    | 'DISCRETE' | 'CAP CHIP 1500P 100V(+-10%.X7R.0402)'                          | 'CHIP0402'     | ''          | ''   | '20120120'
 '1500PF'   | '100V'  | '10%'     | 'C0402'     | 'EMPTY'   | 'CH2158K1B00'(!)   = 'End of Design' | 'Comp-Approve'     | ''       | 'CH2158K1B00'    |'C0402'| '(C0402-0201)'                                                       | 'NA'       | '100V'        | '10%'    | 'IO'       | 'CAP CHIP 1500P 100V(+-10%.X7R.0402)'                          | 'CHIP0402'     | ''          | ''   | '20120120'
 '390PF'    | '50V'   | '5%'      | 'C0402'     | 'C0G'     | 'CH1396J0B02'(!)   = ''              | ''                 | ''       | 'CH1396J0B02'    |'C0402'| '(C0402-0201)'                                                       | '390PF'    | '50V'         | '5%'     | 'DISCRETE' | 'CAP CHIP 390P 50V (+-5%,C0G,0402)'                            | 'CHIP0402'     | ''          | ''   | '20120120'
 '390PF'    | '50V'   | '5%'      | 'C0402'     | 'EMPTY'   | 'CH1396J0B02'(!)   = ''              | ''                 | ''       | 'CH1396J0B02'    |'C0402'| '(C0402-0201)'                                                       | 'NA'       | '50V'         | '5%'     | 'IO'       | 'CAP CHIP 390P 50V (+-5%,C0G,0402)'                            | 'CHIP0402'     | ''          | ''   | '20120120'
 '22UF'     | '4V'    | '20%'     | 'C0603'     | 'X5R'     | 'CH622KM9900'(!)   = 'End of Design' | 'Comp-Approve'     | ''       | 'CH622KM9900'    |'C0603'| '(SMC0603AW)'                                                        | '22UF'     | '4V'          | '20%'    | 'DISCRETE' | 'CAP CHIP 22UF 4V(+-20%,X5R,0603)H0.8'                         | 'CHIP0603'     | ''          | ''   | '20120202'
 '22UF'     | '4V'    | '20%'     | 'C0603'     | 'EMPTY'   | 'CH622KM9900'(!)   = 'End of Design' | 'Comp-Approve'     | ''       | 'CH622KM9900'    |'C0603'| '(SMC0603AW)'                                                        | 'NA'       | '4V'          | '20%'    | 'IO'       | 'CAP CHIP 22UF 4V(+-20%,X5R,0603)H0.8'                         | 'CHIP0603'     | ''          | ''   | '20120202'
 '82PF'     | '50V'   | '1%'      | 'C0402'     | 'C0G'     | 'CH0826F0B00'(!)   = ''              | ''                 | 'SELASS' | 'CH0826F0B00'    |'C0402'| '(C0402-0201)'                                                       | '82PF'     | '50V'         | '1%'     | 'DISCRETE' | 'CAP CHIP 82PF 50V(+-1%.C0G.0402)SELASS'                       | 'CHIP0402'     | ''          | ''   | '20120207'
 '82PF'     | '50V'   | '1%'      | 'C0402'     | 'EMPTY'   | 'CH0826F0B00'(!)   = ''              | ''                 | 'SELASS' | 'CH0826F0B00'    |'C0402'| '(C0402-0201)'                                                       | 'NA'       | '50V'         | '1%'     | 'IO'       | 'CAP CHIP 82PF 50V(+-1%.C0G.0402)SELASS'                       | 'CHIP0402'     | ''          | ''   | '20120207'
 '0.01UF'   | '50V'   | '10%'     | 'C0402'     | 'X7R'     | 'CH31006KB18'(!)   = ''              | ''                 | ''       | 'CH31006KB18'    |'C0402'| '(C0402_OCTAGONXA,C0402-0201)'                                       | '0.01UF'   | '50V'         | '10%'    | 'DISCRETE' | 'CAP CHIP 0.01U 50V(+-10%,X7R,0402)'                           | 'CHIP0402'     | ''          | ''   | '20120326'
 '0.01UF'   | '50V'   | '10%'     | 'C0402'     | 'EMPTY'   | 'CH31006KB18'(!)   = ''              | ''                 | ''       | 'CH31006KB18'    |'C0402'| '(C0402_OCTAGONXA,C0402-0201)'                                       | 'NA'       | '50V'         | '10%'    | 'IO'       | 'CAP CHIP 0.01U 50V(+-10%,X7R,0402)'                           | 'CHIP0402'     | ''          | ''   | '20120326'
 '120PF'    | '50V'   | '5%'      | 'C0402'     | 'NPO'     | 'CH11206JB07'(!)   = ''              | ''                 | ''       | 'CH11206JB07'    |'C0402'| '(C0402-0201)'                                                       | '120PF'    | '50V'         | '10%'    | 'DISCRETE' | 'CAP CHIP 120P 50V(+-5%,NPO,0402)'                             | 'CHIP0402'     | ''          | ''   | '20120326'
 '120PF'    | '50V'   | '5%'      | 'C0402'     | 'EMPTY'   | 'CH11206JB07'(!)   = ''              | ''                 | ''       | 'CH11206JB07'    |'C0402'| '(C0402-0201)'                                                       | 'NA'       | '50V'         | '10%'    | 'IO'       | 'CAP CHIP 120P 50V(+-5%,NPO,0402)'                             | 'CHIP0402'     | ''          | ''   | '20120326'
 '1000PF'   | '2KV'   | '10%'     | 'THLF'      | 'CERAMIC' | 'CG2100FKD00'(!)   = ''              | ''                 | ''       | 'CG2100FKD00'    |'EC315_P197_V'| '(EC315_P197_V)'                                                     | '1000PF'   | '2KV'         | '10%'    | 'DISCRETE' | 'CAP CERAMIC 1000P 2KV(+-10%,P5,DIP)'                          | 'DIP'          | ''          | ''   | '20120405'
 '1000PF'   | '2KV'   | '10%'     | 'THLF'      | 'EMPTY'   | 'CG2100FKD00'(!)   = ''              | ''                 | ''       | 'CG2100FKD00'    |'EC315_P197_V'| '(EC315_P197_V)'                                                     | 'NA'       | '2KV'         | '10%'    | 'IO'       | 'CAP CERAMIC 1000P 2KV(+-10%,P5,DIP)'                          | 'DIP'          | ''          | ''   | '20120405'
 '1000PF'   | '50V'   | '10%'     | 'C0603'     | 'NPO'     | 'CH21006K909'(!)   = 'End of Design' | 'Comp-Approve'     | ''       | 'CH21006K909'    |'C0603'| '(SMC0603AW)'                                                        | '1000PF'   | '50V'         | '10%'    | 'DISCRETE' | 'CAP CHIP 1000P 50V(+-10%,NPO,0603)'                           | 'CHIP0603'     | ''          | ''   | '20120406'
 '1000PF'   | '50V'   | '10%'     | 'C0603'     | 'EMPTY'   | 'CH21006K909'(!)   = 'End of Design' | 'Comp-Approve'     | ''       | 'CH21006K909'    |'C0603'| '(SMC0603AW)'                                                        | 'NA'       | '50V'         | '10%'    | 'IO'       | 'CAP CHIP 1000P 50V(+-10%,NPO,0603)'                           | 'CHIP0603'     | ''          | ''   | '20120406'
 '0.022UF'  | '50V'   | '10%'     | 'C0603'     | 'X7R'     | 'CH3226K1901'(!)   = 'End of Design' | 'Comp-Approve'     | ''       | 'CH3226K1901'    |'C0603'| '(SMC0603AW)'                                                        | '0.022UF'  | '50V'         | '10%'    | 'DISCRETE' | 'CAP CHIP 0.022U 50V(+-10%.X7R.0603)L-F'                       | 'CHIP0603'     | ''          | ''   | '20120416'
 '0.022UF'  | '50V'   | '10%'     | 'C0603'     | 'EMPTY'   | 'CH3226K1901'(!)   = 'End of Design' | 'Comp-Approve'     | ''       | 'CH3226K1901'    |'C0603'| '(SMC0603AW)'                                                        | 'NA'       | '50V'         | '10%'    | 'IO'       | 'CAP CHIP 0.022U 50V(+-10%.X7R.0603)L-F'                       | 'CHIP0603'     | ''          | ''   | '20120416'
 '10UF'     | '25V'   | '10%'     | 'C1206'     | 'X6S'     | 'CH6104KE201'(!)   = 'End of Design' | 'Comp-Approve'     | ''       | 'CH6104KE201'    |'C1206_H76'| '(SMC1206AW)'                                                        | '10UF'     | '25V'         | '10%'    | 'DISCRETE' | 'CAP CHIP 10U 25V(+-10%.X6S.1206)'                             | 'CHIP1206'     | ''          | ''   | '20120419'
 '10UF'     | '25V'   | '10%'     | 'C1206'     | 'EMPTY'   | 'CH6104KE201'(!)   = 'End of Design' | 'Comp-Approve'     | ''       | 'CH6104KE201'    |'C1206_H76'| '(SMC1206AW)'                                                        | 'NA'       | '25V'         | '10%'    | 'IO'       | 'CAP CHIP 10U 25V(+-10%.X6S.1206)'                             | 'CHIP1206'     | ''          | ''   | '20120419'
 '22UF'     | '2.5V'  | '20%'     | 'C0805'     | 'X6S'     | 'CH622LMEA00'(!)   = 'End of Design' | 'Comp-Approve'     | ''       | 'CH622LMEA00'    |'C0805_H36'| '(SMC0805AW)'                                                        | '22UF'     | '2.5V'        | '20%'    | 'DISCRETE' | 'CAP CHIP 22UF 2.5V(20%,X6S,0805,H0.85)'                       | 'CHIP0805'     | ''          | ''   | '20120420'
 '22UF'     | '2.5V'  | '20%'     | 'C0805'     | 'EMPTY'   | 'CH622LMEA00'(!)   = 'End of Design' | 'Comp-Approve'     | ''       | 'CH622LMEA00'    |'C0805_H36'| '(SMC0805AW)'                                                        | 'NA'       | '2.5V'        | '20%'    | 'IO'       | 'CAP CHIP 22UF 2.5V(20%,X6S,0805,H0.85)'                       | 'CHIP0805'     | ''          | ''   | '20120420'
 '22UF'     | '6.3V'  | '20%'     | 'C0805'     | 'X5R'     | 'CH6221M9A00'(!)   = 'End of Design' | 'Comp-Approve'     | ''       | 'CH6221M9A00'    |'C0805_H61'| '(SMC0805AW)'                                                        | '22UF'     | '6.3V'        | '20%'    | 'DISCRETE' | 'CAP CHIP 22U 6.3V(+-20%,X5R,0805)H1.25'                       | 'CHIP0805'     | ''          | ''   | '20120420'
 '22UF'     | '6.3V'  | '20%'     | 'C0805'     | 'EMPTY'   | 'CH6221M9A00'(!)   = 'End of Design' | 'Comp-Approve'     | ''       | 'CH6221M9A00'    |'C0805_H61'| '(SMC0805AW)'                                                        | 'NA'       | '6.3V'        | '20%'    | 'IO'       | 'CAP CHIP 22U 6.3V(+-20%,X5R,0805)H1.25'                       | 'CHIP0805'     | ''          | ''   | '20120420'
 '0.039UF'  | '16V'   | '10%'     | 'C0603'     | 'X7R'     | 'CH33903K911'(!)   = ''              | ''                 | ''       | 'CH33903K911'    |'C0603'| '(SMC0603AW)'                                                        | '0.039UF'  | '16V'         | '10%'    | 'DISCRETE' | 'CAP CHIP 0.039U 16V(+-10%.X7R.0603)'                          | 'CHIP0603'     | ''          | ''   | '20120423'
 '0.039UF'  | '16V'   | '10%'     | 'C0603'     | 'EMPTY'   | 'CH33903K911'(!)   = ''              | ''                 | ''       | 'CH33903K911'    |'C0603'| '(SMC0603AW)'                                                        | 'NA'       | '16V'         | '10%'    | 'IO'       | 'CAP CHIP 0.039U 16V(+-10%.X7R.0603)'                          | 'CHIP0603'     | ''          | ''   | '20120423'
 '0.056UF'  | '16V'   | '10%'     | 'C0402'     | 'X7R'     | 'CH3563K1B00'(!)   = ''              | ''                 | ''       | 'CH3563K1B00'    |'C0402'| '(C0402-0201)'                                                       | '0.056UF'  | '16V'         | '10%'    | 'DISCRETE' | 'CAP CHIP 0.056U 16V(+-10%,X7R,0402)'                          | 'CHIP0402'     | ''          | ''   | '20120424'
 '0.056UF'  | '16V'   | '10%'     | 'C0402'     | 'EMPTY'   | 'CH3563K1B00'(!)   = ''              | ''                 | ''       | 'CH3563K1B00'    |'C0402'| '(C0402-0201)'                                                       | 'NA'       | '16V'         | '10%'    | 'IO'       | 'CAP CHIP 0.056U 16V(+-10%,X7R,0402)'                          | 'CHIP0402'     | ''          | ''   | '20120424'
 '100UF'    | '4V'    | '20%'     | 'C0805'     | 'X5R'     | 'CH710KM9A00'(!)   = 'End of Design' | 'Comp-Approve'     | ''       | 'CH710KM9A00'    |'C0805_H61'| '(SMC0805AW)'                                                        | '100UF'    | '4V'          | '20%'    | 'DISCRETE' | 'CAP CHIP 100U 4V(+-20%,X5R,0805)H1.25'                        | 'CHIP0805'     | ''          | ''   | '20120509'
 '100UF'    | '4V'    | '20%'     | 'C0805'     | 'EMPTY'   | 'CH710KM9A00'(!)   = 'End of Design' | 'Comp-Approve'     | ''       | 'CH710KM9A00'    |'C0805_H61'| '(SMC0805AW)'                                                        | 'NA'       | '4V'          | '20%'    | 'IO'       | 'CAP CHIP 100U 4V(+-20%,X5R,0805)H1.25'                        | 'CHIP0805'     | ''          | ''   | '20120509'
 '10UF'     | '6.3V'  | '20%'     | 'C0402'     | 'X5R'     | 'CH6101M9B02'(!)   = ''              | ''                 | ''       | 'CH6101M9B02'    |'C0402'| '(C0402-0201)'                                                       | '10UF'     | '6.3V'        | '20%'    | 'DISCRETE' | 'CAP CHIP 10U 6.3V(+-20%,X5R,0402)'                            | 'CHIP0402'     | ''          | ''   | '20120521'
 '10UF'     | '6.3V'  | '20%'     | 'C0402'     | 'EMPTY'   | 'CH6101M9B02'(!)   = ''              | ''                 | ''       | 'CH6101M9B02'    |'C0402'| '(C0402-0201)'                                                       | 'NA'       | '6.3V'        | '20%'    | 'IO'       | 'CAP CHIP 10U 6.3V(+-20%,X5R,0402)'                            | 'CHIP0402'     | ''          | ''   | '20120521'
 '0.1UF'    | '6.3V'  | '10%'     | 'C0201'     | 'X5R'     | 'CH4101K9E01'(!)   = ''              | ''                 | ''       | 'CH4101K9E01'    |'C0201'| '(SMC0201AW)'                                                        | '0.1UF'    | '6.3V'        | '10%'    | 'DISCRETE' | 'CAP CHIP 0.1UF 6.3V(+-10%,X5R,0201)'                          | 'CHIP0201'     | ''          | ''   | '20120528'
 '0.1UF'    | '6.3V'  | '10%'     | 'C0201'     | 'EMPTY'   | 'CH4101K9E01'(!)   = ''              | ''                 | ''       | 'CH4101K9E01'    |'C0201'| '(SMC0201AW)'                                                        | 'NA'       | '6.3V'        | '10%'    | 'IO'       | 'CAP CHIP 0.1UF 6.3V(+-10%,X5R,0201)'                          | 'CHIP0201'     | ''          | ''   | '20120528'
 '1000PF'   | '16V'   | '10%'     | 'C0201'     | 'X7R'     | 'CH2103K1E14'(!)   = ''              | ''                 | ''       | 'CH2103K1E14'    |'C0201'| '(SMC0201AW)'                                                        | '1000PF'   | '16V'         | '10%'    | 'DISCRETE' | 'CAP CHIP 1000P 16V(10%,X7R,0201)'                             | 'CHIP0201'     | ''          | ''   | '20120528'
 '1000PF'   | '16V'   | '10%'     | 'C0201'     | 'EMPTY'   | 'CH2103K1E14'(!)   = ''              | ''                 | ''       | 'CH2103K1E14'    |'C0201'| '(SMC0201AW)'                                                        | 'NA'       | '16V'         | '10%'    | 'IO'       | 'CAP CHIP 1000P 16V(10%,X7R,0201)'                             | 'CHIP0201'     | ''          | ''   | '20120528'
 '0.22UF'   | '6.3V'  | '20%'     | 'C0201'     | 'X5R'     | 'CH4221M9E00'(!)   = 'End of Design' | 'Comp-Release Qty' | ''       | 'CH4221M9E00'    |'C0201'| '(SMC0201AW)'                                                        | '0.22UF'   | '6.3V'        | '20%'    | 'DISCRETE' | 'CAP CHIP 0.22UF 6.3V(20%,X5R,0201)'                           | 'CHIP0201'     | ''          | ''   | '20120528'
 '0.22UF'   | '6.3V'  | '20%'     | 'C0201'     | 'EMPTY'   | 'CH4221M9E00'(!)   = 'End of Design' | 'Comp-Release Qty' | ''       | 'CH4221M9E00'    |'C0201'| '(SMC0201AW)'                                                        | 'NA'       | '6.3V'        | '20%'    | 'IO'       | 'CAP CHIP 0.22UF 6.3V(20%,X5R,0201)'                           | 'CHIP0201'     | ''          | ''   | '20120528'
 '4.7UF'    | '6.3V'  | '20%'     | 'C0402'     | 'X5R'     | 'CH5471M9B00'(!)   = 'End of Design' | 'Comp-Release Qty' | ''       | 'CH5471M9B00'    |'C0402'| '(C0402-0201)'                                                       | '4.7UF'    | '6.3V'        | '20%'    | 'DISCRETE' | 'CAP CHIP 4.7U 6.3V(+-20%.X5R.0402)'                           | 'CHIP0402'     | ''          | ''   | '20120528'
 '4.7UF'    | '6.3V'  | '20%'     | 'C0402'     | 'EMPTY'   | 'CH5471M9B00'(!)   = 'End of Design' | 'Comp-Release Qty' | ''       | 'CH5471M9B00'    |'C0402'| '(C0402-0201)'                                                       | 'NA'       | '6.3V'        | '20%'    | 'IO'       | 'CAP CHIP 4.7U 6.3V(+-20%.X5R.0402)'                           | 'CHIP0402'     | ''          | ''   | '20120528'
 '22UF'     | '6.3V'  | '20%'     | 'C0603'     | 'X5R'     | 'CH6221M9900'(!)   = ''              | ''                 | ''       | 'CH6221M9900'    |'C0603'| '(SMC0603AW)'                                                        | '22UF'     | '6.3V'        | '20%'    | 'DISCRETE' | 'CAP CHIP 22U 6.3V(+-20%,X5R,0603)HF'                          | 'CHIP0603'     | ''          | ''   | '20120528'
 '22UF'     | '6.3V'  | '20%'     | 'C0603'     | 'EMPTY'   | 'CH6221M9900'(!)   = ''              | ''                 | ''       | 'CH6221M9900'    |'C0603'| '(SMC0603AW)'                                                        | 'NA'       | '6.3V'        | '20%'    | 'IO'       | 'CAP CHIP 22U 6.3V(+-20%,X5R,0603)HF'                          | 'CHIP0603'     | ''          | ''   | '20120528'
 '1UF'      | '6.3V'  | '20%'     | 'C0201'     | 'X5R'     | 'CH5101M9E02'(!)   = ''              | ''                 | ''       | 'CH5101M9E02'    |'C0201'| '(SMC0201AW)'                                                        | '1UF'      | '6.3V'        | '20%'    | 'DISCRETE' | 'CAP CHIP 1UF 6.3V(+-20%,X5R,0201)'                            | 'CHIP0201'     | ''          | ''   | '20120528'
 '1UF'      | '6.3V'  | '20%'     | 'C0201'     | 'EMPTY'   | 'CH5101M9E02'(!)   = ''              | ''                 | ''       | 'CH5101M9E02'    |'C0201'| '(SMC0201AW)'                                                        | 'NA'       | '6.3V'        | '20%'    | 'IO'       | 'CAP CHIP 1UF 6.3V(+-20%,X5R,0201)'                            | 'CHIP0201'     | ''          | ''   | '20120528'
 '5.6PF'    | '25V'   | '0.25PF'  | 'C0201'     | 'C0G'     | 'CH-564C0E00'(!)   = ''              | ''                 | ''       | 'CH-564C0E00'    |'C0201'| '(SMC0201AW)'                                                        | '5.6PF'    | '25V'         | '0.25PF' | 'DISCRETE' | 'CAP 5.6PF 25V(0.25PF,C0G,0201,HQ,ESR250)'                     | 'CHIP0201'     | ''          | ''   | '20120601'
 '5.6PF'    | '25V'   | '0.25PF'  | 'C0201'     | 'EMPTY'   | 'CH-564C0E00'(!)   = ''              | ''                 | ''       | 'CH-564C0E00'    |'C0201'| '(SMC0201AW)'                                                        | 'NA'       | '25V'         | '0.25PF' | 'IO'       | 'CAP 5.6PF 25V(0.25PF,C0G,0201,HQ,ESR250)'                     | 'CHIP0201'     | ''          | ''   | '20120601'
 '22UF'     | '6.3V'  | '20%'     | 'C0805'     | 'X5R'     | 'CH6221M9A01'(!)   = 'End of Design' | 'End of Life'      | ''       | 'CH6221M9A01'    |'C0805_H61_EOL'| '(SMC0805AW)'                                                        | '22UF'     | '6.3V'        | '20%'    | 'DISCRETE' | 'CAP CHIP 22U 6.3V(+-20%.X5R.0805)H1.25'                       | 'CHIP0805'     | ''          | ''   | '20120604'
 '22UF'     | '6.3V'  | '20%'     | 'C0805'     | 'EMPTY'   | 'CH6221M9A01'(!)   = 'End of Design' | 'End of Life'      | ''       | 'CH6221M9A01'    |'C0805_H61_EOL'| '(SMC0805AW)'                                                        | 'NA'       | '6.3V'        | '20%'    | 'IO'       | 'CAP CHIP 22U 6.3V(+-20%.X5R.0805)H1.25'                       | 'CHIP0805'     | ''          | ''   | '20120604'
 '4.7UF'    | '10V'   | '20%'     | 'C0603'     | 'X5R'     | 'CH5472M9901'(!)   = 'End of Design' | 'Comp-Approve'     | ''       | 'CH5472M9901'    |'C0603'| '(SMC0603AW)'                                                        | '4.7UF'    | '10V'         | '20%'    | 'DISCRETE' | 'CAP CHIP 4.7U,10V(+-20%,X5R,0603)'                            | 'CHIP0603'     | ''          | ''   | '20120604'
 '4.7UF'    | '10V'   | '20%'     | 'C0603'     | 'EMPTY'   | 'CH5472M9901'(!)   = 'End of Design' | 'Comp-Approve'     | ''       | 'CH5472M9901'    |'C0603'| '(SMC0603AW)'                                                        | 'NA'       | '10V'         | '20%'    | 'IO'       | 'CAP CHIP 4.7U,10V(+-20%,X5R,0603)'                            | 'CHIP0603'     | ''          | ''   | '20120604'
 '0.033UF'  | '50V'   | '10%'     | 'C0603'     | 'X7R'     | 'CH33306K915'(!)   = 'End of Design' | 'Comp-Approve'     | ''       | 'CH33306K915'    |'C0603'| '(SMC0603AW)'                                                        | '0.033UF'  | '50V'         | '10%'    | 'DISCRETE' | 'CAP CHIP 0.033U 50V(+-10%,X7R,0603)'                          | 'CHIP0603'     | ''          | ''   | '20120727'
 '0.033UF'  | '50V'   | '10%'     | 'C0603'     | 'EMPTY'   | 'CH33306K915'(!)   = 'End of Design' | 'Comp-Approve'     | ''       | 'CH33306K915'    |'C0603'| '(SMC0603AW)'                                                        | 'NA'       | '50V'         | '10%'    | 'IO'       | 'CAP CHIP 0.033U 50V(+-10%,X7R,0603)'                          | 'CHIP0603'     | ''          | ''   | '20120727'
 '4.7UF'    | '25V'   | '20%'     | 'C1206'     | 'X7R'     | 'CH5474M1200'(!)   = 'End of Design' | 'Comp-Approve'     | ''       | 'CH5474M1200'    |'C1206_H66'| '(SMC1206AW)'                                                        | '4.7UF'    | '25V'         | '20%'    | 'DISCRETE' | 'CAP CHIP 4.7U 25V(+-20%,X7R,1206)H1.6'                        | 'CHIP1206'     | ''          | ''   | '20120814'
 '4.7UF'    | '25V'   | '20%'     | 'C1206'     | 'EMPTY'   | 'CH5474M1200'(!)   = 'End of Design' | 'Comp-Approve'     | ''       | 'CH5474M1200'    |'C1206_H66'| '(SMC1206AW)'                                                        | 'NA'       | '25V'         | '20%'    | 'IO'       | 'CAP CHIP 4.7U 25V(+-20%,X7R,1206)H1.6'                        | 'CHIP1206'     | ''          | ''   | '20120814'
 '0.01UF'   | '250V'  | '10%'     | 'C0805'     | 'X7R'     | 'CH3100CKA14'(!)   = ''              | ''                 | ''       | 'CH3100CKA14'    |'C0805_H61'| '(SMC0805AW)'                                                        | '0.01UF'   | '250V'        | '10%'    | 'DISCRETE' | 'CAP CHIP 0.01U 250V(+-10%.X7R.0805)'                          | 'CHIP0805'     | ''          | ''   | '20120905'
 '0.01UF'   | '250V'  | '10%'     | 'C0805'     | 'EMPTY'   | 'CH3100CKA14'(!)   = ''              | ''                 | ''       | 'CH3100CKA14'    |'C0805_H61'| '(SMC0805AW)'                                                        | 'NA'       | '250V'        | '10%'    | 'IO'       | 'CAP CHIP 0.01U 250V(+-10%.X7R.0805)'                          | 'CHIP0805'     | ''          | ''   | '20120905'
 '0.33UF'   | '6.3V'  | '10%'     | 'C0402'     | 'X5R'     | 'CH4331K9B06'(!)   = 'End of Design' | 'Comp-Approve'     | ''       | 'CH4331K9B06'    |'C0402'| '(C0402-0201)'                                                       | '0.33UF'   | '6.3V'        | '10%'    | 'DISCRETE' | 'CAP CHIP 0.33U 6.3V(10%.X5R.0402)'                            | 'CHIP0402'     | ''          | ''   | '20120906'
 '0.33UF'   | '6.3V'  | '10%'     | 'C0402'     | 'EMPTY'   | 'CH4331K9B06'(!)   = 'End of Design' | 'Comp-Approve'     | ''       | 'CH4331K9B06'    |'C0402'| '(C0402-0201)'                                                       | 'NA'       | '6.3V'        | '10%'    | 'IO'       | 'CAP CHIP 0.33U 6.3V(10%.X5R.0402)'                            | 'CHIP0402'     | ''          | ''   | '20120906'
 '39NF'     | '16V'   | '10%'     | 'C0402'     | 'X7R'     | 'CH3393K1B00'(!)   = ''              | ''                 | ''       | 'CH3393K1B00'    |'C0402'| '(C0402-0201)'                                                       | '39NF'     | '16V'         | '10%'    | 'DISCRETE' | 'CAP CHIP 39NF 16V(+-10%,X7R,0402)'                            | 'CHIP0402'     | ''          | ''   | '20120917'
 '39NF'     | '16V'   | '10%'     | 'C0402'     | 'EMPTY'   | 'CH3393K1B00'(!)   = ''              | ''                 | ''       | 'CH3393K1B00'    |'C0402'| '(C0402-0201)'                                                       | 'NA'       | '16V'         | '10%'    | 'IO'       | 'CAP CHIP 39NF 16V(+-10%,X7R,0402)'                            | 'CHIP0402'     | ''          | ''   | '20120917'
 '1UF'      | '10V'   | '10%'     | 'C0402'     | 'X6S'     | 'CH5102KEB00'(!)   = ''              | ''                 | ''       | 'CH5102KEB00'    |'C0402'| '(C0402-0201)'                                                       | '1UF'      | '10V'         | '10%'    | 'DISCRETE' | 'CAP CHIP 1UF 10V(+-10%,X6S,0402)'                             | 'CHIP0402'     | ''          | ''   | '20120919'
 '1UF'      | '10V'   | '10%'     | 'C0402'     | 'EMPTY'   | 'CH5102KEB00'(!)   = ''              | ''                 | ''       | 'CH5102KEB00'    |'C0402'| '(C0402-0201)'                                                       | 'NA'       | '10V'         | '10%'    | 'IO'       | 'CAP CHIP 1UF 10V(+-10%,X6S,0402)'                             | 'CHIP0402'     | ''          | ''   | '20120919'
 '0.47UF'   | '10V'   | '10%'     | 'C0402'     | 'X6S'     | 'CH44702KEB0'(!)   = 'End of Design' | 'Comp-Approve'     | ''       | 'CH44702KEB0'    |'C0402'| '(C0402-0201)'                                                       | '0.47UF'   | '10V'         | '10%'    | 'DISCRETE' | 'CAP CHIP 0.47UF 10V(+-10%,X6S,0402)'                          | 'CHIP0402'     | ''          | ''   | '20121002'
 '0.47UF'   | '10V'   | '10%'     | 'C0402'     | 'EMPTY'   | 'CH44702KEB0'(!)   = 'End of Design' | 'Comp-Approve'     | ''       | 'CH44702KEB0'    |'C0402'| '(C0402-0201)'                                                       | 'NA'       | '10V'         | '10%'    | 'IO'       | 'CAP CHIP 0.47UF 10V(+-10%,X6S,0402)'                          | 'CHIP0402'     | ''          | ''   | '20121002'
 '0.33UF'   | '6.3V'  | '10%'     | 'C0402'     | 'X6S'     | 'CH4331KEB01'(!)   = 'End of Design' | 'Comp-Approve'     | ''       | 'CH4331KEB01'    |'C0402'| '(C0402-0201)'                                                       | '0.33UF'   | '6.3V'        | '10%'    | 'DISCRETE' | 'CAP CHIP 0.33UF 6.3V(10%,X6S,0402)'                           | 'CHIP0402'     | ''          | ''   | '20121009'
 '0.33UF'   | '6.3V'  | '10%'     | 'C0402'     | 'EMPTY'   | 'CH4331KEB01'(!)   = 'End of Design' | 'Comp-Approve'     | ''       | 'CH4331KEB01'    |'C0402'| '(C0402-0201)'                                                       | 'NA'       | '6.3V'        | '10%'    | 'IO'       | 'CAP CHIP 0.33UF 6.3V(10%,X6S,0402)'                           | 'CHIP0402'     | ''          | ''   | '20121009'
 '0.47UF'   | '6.3V'  | '10%'     | 'C0402'     | 'X6S'     | 'CH4471KEB01'(!)   = 'End of Design' | 'Comp-Approve'     | ''       | 'CH4471KEB01'    |'C0402'| '(C0402-0201)'                                                       | '0.47UF'   | '6.3V'        | '10%'    | 'DISCRETE' | 'CAP CHIP 0.47UF 6.3V(10%,X6S,0402)'                           | 'CHIP0402'     | ''          | ''   | '20121009'
 '0.47UF'   | '6.3V'  | '10%'     | 'C0402'     | 'EMPTY'   | 'CH4471KEB01'(!)   = 'End of Design' | 'Comp-Approve'     | ''       | 'CH4471KEB01'    |'C0402'| '(C0402-0201)'                                                       | 'NA'       | '6.3V'        | '10%'    | 'IO'       | 'CAP CHIP 0.47UF 6.3V(10%,X6S,0402)'                           | 'CHIP0402'     | ''          | ''   | '20121009'
 '22UF'     | '25V'   | '10%'     | 'C1206'     | 'X5R'     | 'CH6224K9200'(!)   = 'End of Design' | 'Comp-Approve'     | ''       | 'CH6224K9200'    |'C1206_H76'| '(SMC1206AW)'                                                        | '22UF'     | '25V'         | '10%'    | 'DISCRETE' | 'CAP CHIP 22U 25V(+-10%,X5R,1206)'                             | 'CHIP1206'     | ''          | ''   | '20121201'
 '22UF'     | '25V'   | '10%'     | 'C1206'     | 'EMPTY'   | 'CH6224K9200'(!)   = 'End of Design' | 'Comp-Approve'     | ''       | 'CH6224K9200'    |'C1206_H76'| '(SMC1206AW)'                                                        | 'NA'       | '25V'         | '10%'    | 'IO'       | 'CAP CHIP 22U 25V(+-10%,X5R,1206)'                             | 'CHIP1206'     | ''          | ''   | '20121201'
 '4.7PF'    | '50V'   | '0.1P'    | 'C0402'     | 'NPO'     | 'CH-4716TB06'(!)   = ''              | ''                 | ''       | 'CH-4716TB06'    |'C0402'| '(C0402-0201)'                                                       | '4.7PF'    | '50V'         | '0.10%'  | 'DISCRETE' | 'CAP CHIP 4.7P 50V(+-0.1P.NPO.0402)'                           | 'CHIP0402'     | ''          | ''   | '20121216'
 '4.7PF'    | '50V'   | '0.1P'    | 'C0402'     | 'EMPTY'   | 'CH-4716TB06'(!)   = ''              | ''                 | ''       | 'CH-4716TB06'    |'C0402'| '(C0402-0201)'                                                       | 'NA'       | '50V'         | '0.10%'  | 'IO'       | 'CAP CHIP 4.7P 50V(+-0.1P.NPO.0402)'                           | 'CHIP0402'     | ''          | ''   | '20121216'
 '0.47UF'   | '100V'  | '10%'     | 'C0805'     | 'X7R'     | 'CH4478K1A00'(!)   = ''              | ''                 | ''       | 'CH4478K1A00'    |'C0805_H61'| '(SMC0805AW)'                                                        | '0.47UF'   | '100V'        | '10%'    | 'DISCRETE' | 'CAP CHIP 0.47U 100V(+-10%.X7R.0805)'                          | 'CHIP0805'     | ''          | ''   | '20121219'
 '0.47UF'   | '100V'  | '10%'     | 'C0805'     | 'EMPTY'   | 'CH4478K1A00'(!)   = ''              | ''                 | ''       | 'CH4478K1A00'    |'C0805_H61'| '(SMC0805AW)'                                                        | 'NA'       | '100V'        | '10%'    | 'IO'       | 'CAP CHIP 0.47U 100V(+-10%.X7R.0805)'                          | 'CHIP0805'     | ''          | ''   | '20121219'
 '2.2UF'    | '100V'  | '10%'     | 'C1206'     | 'X7R'     | 'CH5228K1202'(!)   = 'End of Design' | 'Comp-Approve'     | ''       | 'CH5228K1202'    |'C1206_H76'| '(SMC1206AW)'                                                        | '2.2UF'    | '100V'        | '10%'    | 'DISCRETE' | 'CAP CHIP 2.2UF 100V(+-10%,X7R,1206)'                          | 'CHIP1206'     | ''          | ''   | '20121219'
 '2.2UF'    | '100V'  | '10%'     | 'C1206'     | 'EMPTY'   | 'CH5228K1202'(!)   = 'End of Design' | 'Comp-Approve'     | ''       | 'CH5228K1202'    |'C1206_H76'| '(SMC1206AW)'                                                        | 'NA'       | '100V'        | '10%'    | 'IO'       | 'CAP CHIP 2.2UF 100V(+-10%,X7R,1206)'                          | 'CHIP1206'     | ''          | ''   | '20121219'
 '0.01UF'   | '1KV'   | '10%'     | 'C1206'     | 'X7R'     | 'CH310FK1200'(!)   = ''              | ''                 | ''       | 'CH310FK1200'    |'C1206_H56'| '(SMC1206AW)'                                                        | '0.01UF'   | '1KV'         | '10%'    | 'DISCRETE' | 'CAP CHIP 0.01U 1KV(+-10%,X7R,1206)H1.25'                      | 'CHIP1206'     | ''          | ''   | '20130103'
 '0.01UF'   | '1KV'   | '10%'     | 'C1206'     | 'EMPTY'   | 'CH310FK1200'(!)   = ''              | ''                 | ''       | 'CH310FK1200'    |'C1206_H56'| '(SMC1206AW)'                                                        | 'NA'       | '1KV'         | '10%'    | 'IO'       | 'CAP CHIP 0.01U 1KV(+-10%,X7R,1206)H1.25'                      | 'CHIP1206'     | ''          | ''   | '20130103'
 '0.01UF'   | '100V'  | '10%'     | 'C0603'     | 'X7R'     | 'CH3108K1900'(!)   = ''              | ''                 | ''       | 'CH3108K1900'    |'C0603'| '(SMC0603AW)'                                                        | '0.01UF'   | '100V'        | '10%'    | 'DISCRETE' | 'CAP CHIP 0.01U 100V(+-10%.X7R.0603)'                          | 'CHIP0603'     | ''          | ''   | '20130110'
 '0.01UF'   | '100V'  | '10%'     | 'C0603'     | 'EMPTY'   | 'CH3108K1900'(!)   = ''              | ''                 | ''       | 'CH3108K1900'    |'C0603'| '(SMC0603AW)'                                                        | 'NA'       | '100V'        | '10%'    | 'IO'       | 'CAP CHIP 0.01U 100V(+-10%.X7R.0603)'                          | 'CHIP0603'     | ''          | ''   | '20130110'
 '560PF'    | '50V'   | '10%'     | 'C0402'     | 'X7R'     | 'CH1566K1B09'(!)   = ''              | ''                 | ''       | 'CH1566K1B09'    |'C0402'| '(C0402_OCTAGONXA,C0402-0201)'                                       | '560PF'    | '50V'         | '10%'    | 'DISCRETE' | 'CAP CHIP 560P 50V(+-10%,X7R,0402)'                            | 'CHIP0402'     | ''          | ''   | '20130114'
 '560PF'    | '50V'   | '10%'     | 'C0402'     | 'EMPTY'   | 'CH1566K1B09'(!)   = ''              | ''                 | ''       | 'CH1566K1B09'    |'C0402'| '(C0402_OCTAGONXA,C0402-0201)'                                       | 'NA'       | '50V'         | '10%'    | 'IO'       | 'CAP CHIP 560P 50V(+-10%,X7R,0402)'                            | 'CHIP0402'     | ''          | ''   | '20130114'
 '820PF'    | '50V'   | '10%'     | 'C0402'     | 'X7R'     | 'CH18206KB11'(!)   = ''              | ''                 | ''       | 'CH18206KB11'    |'C0402'| '(C0402-0201)'                                                       | '820PF'    | '50V'         | '10%'    | 'DISCRETE' | 'CAP CHIP 820P 50V(+-10%,X7R,0402)'                            | 'CHIP0402'     | ''          | ''   | '20130114'
 '820PF'    | '50V'   | '10%'     | 'C0402'     | 'EMPTY'   | 'CH18206KB11'(!)   = ''              | ''                 | ''       | 'CH18206KB11'    |'C0402'| '(C0402-0201)'                                                       | 'NA'       | '50V'         | '10%'    | 'IO'       | 'CAP CHIP 820P 50V(+-10%,X7R,0402)'                            | 'CHIP0402'     | ''          | ''   | '20130114'
 '2.2UF'    | '16V'   | '20%'     | 'C0805'     | 'Y5V'     | 'CH52203ZA30'(!)   = ''              | ''                 | ''       | 'CH52203ZA30'    |'C0805_H64'| '(SMC0805AW)'                                                        | '2.2UF'    | '16V'         | '20%'    | 'DISCRETE' | 'CAP CHIP 2.2U.16V(+80-20%.Y5V.0805)'                          | 'CHIP0805'     | ''          | ''   | '20130214'
 '2.2UF'    | '16V'   | '20%'     | 'C0805'     | 'EMPTY'   | 'CH52203ZA30'(!)   = ''              | ''                 | ''       | 'CH52203ZA30'    |'C0805_H64'| '(SMC0805AW)'                                                        | 'NA'       | '16V'         | '20%'    | 'IO'       | 'CAP CHIP 2.2U.16V(+80-20%.Y5V.0805)'                          | 'CHIP0805'     | ''          | ''   | '20130214'
 '22UF'     | '4V'    | '20%'     | 'C0603'     | 'X6S'     | 'CH622KME901'(!)   = ''              | ''                 | ''       | 'CH622KME901'    |'C0603'| '(SMC0603AW)'                                                        | '22UF'     | '4V'          | '20%'    | 'DISCRETE' | 'CAP CHIP 22UF 4V(+-20%,X6S,0603)'                             | 'CHIP0603'     | ''          | ''   | '20130321'
 '22UF'     | '4V'    | '20%'     | 'C0603'     | 'EMPTY'   | 'CH622KME901'(!)   = ''              | ''                 | ''       | 'CH622KME901'    |'C0603'| '(SMC0603AW)'                                                        | 'NA'       | '4V'          | '20%'    | 'IO'       | 'CAP CHIP 22UF 4V(+-20%,X6S,0603)'                             | 'CHIP0603'     | ''          | ''   | '20130321'
 '0.68UF'   | '16V'   | '80%'     | 'C0603'     | 'Y5V'     | 'CH4683Z3900'(!)   = 'End of Design' | 'Comp-Approve'     | ''       | 'CH4683Z3900'    |'C0603'| '(SMC0603AW)'                                                        | '0.68UF'   | '16V'         | '80%'    | 'DISCRETE' | 'CAP CHIP 0.68U 16V(+80%-20%,Y5V,0603)'                        | 'CHIP0603'     | ''          | ''   | '20130321'
 '0.68UF'   | '16V'   | '80%'     | 'C0603'     | 'EMPTY'   | 'CH4683Z3900'(!)   = 'End of Design' | 'Comp-Approve'     | ''       | 'CH4683Z3900'    |'C0603'| '(SMC0603AW)'                                                        | 'NA'       | '16V'         | '80%'    | 'IO'       | 'CAP CHIP 0.68U 16V(+80%-20%,Y5V,0603)'                        | 'CHIP0603'     | ''          | ''   | '20130321'
 '22UF'     | '4V'    | '20%'     | 'C0402'     | 'X5R'     | 'CH622KM9B02'(!)   = 'End of Design' | 'Comp-Approve'     | ''       | 'CH622KM9B02'    |'C0402'| '(C0402-0201)'                                                       | '22UF'     | '4V'          | '20%'    | 'DISCRETE' | 'CAP CHIP 22UF 4V (+-20%, X5R,0402)'                           | 'CHIP0402'     | ''          | ''   | '20130408'
 '22UF'     | '4V'    | '20%'     | 'C0402'     | 'EMPTY'   | 'CH622KM9B02'(!)   = 'End of Design' | 'Comp-Approve'     | ''       | 'CH622KM9B02'    |'C0402'| '(C0402-0201)'                                                       | 'NA'       | '4V'          | '20%'    | 'IO'       | 'CAP CHIP 22UF 4V (+-20%, X5R,0402)'                           | 'CHIP0402'     | ''          | ''   | '20130408'
 '180PF'    | '50V'   | '5%'      | 'C0402'     | 'NPO'     | 'CH11806JB09'(!)   = ''              | ''                 | ''       | 'CH11806JB09'    |'C0402'| '(C0402-0201)'                                                       | '180PF'    | '50V'         | '5%'     | 'DISCRETE' | 'CAP CHIP 180P 50V(+-5%.NPO.0402)'                             | 'CHIP0402'     | ''          | ''   | '20130628'
 '180PF'    | '50V'   | '5%'      | 'C0402'     | 'EMPTY'   | 'CH11806JB09'(!)   = ''              | ''                 | ''       | 'CH11806JB09'    |'C0402'| '(C0402-0201)'                                                       | 'NA'       | '50V'         | '5%'     | 'IO'       | 'CAP CHIP 180P 50V(+-5%.NPO.0402)'                             | 'CHIP0402'     | ''          | ''   | '20130628'
 '12PF'     | '50V'   | '5%'      | 'C0402'     | 'C0G'     | 'CH01206JB05'(!)   = ''              | ''                 | ''       | 'CH01206JB05'    |'C0402'| '(C0402-0201)'                                                       | '12PF'     | '50V'         | '5%'     | 'DISCRETE' | 'CAP CHIP 12P 50V(+-5%.C0G.0402)'                              | 'CHIP0402'     | ''          | ''   | '20130703'
 '12PF'     | '50V'   | '5%'      | 'C0402'     | 'EMPTY'   | 'CH01206JB05'(!)   = ''              | ''                 | ''       | 'CH01206JB05'    |'C0402'| '(C0402-0201)'                                                       | 'NA'       | '50V'         | '5%'     | 'IO'       | 'CAP CHIP 12P 50V(+-5%.C0G.0402)'                              | 'CHIP0402'     | ''          | ''   | '20130703'
 '4700PF'   | '6.3V'  | '10%'     | 'C0201'     | 'X7R'     | 'CH2471K1E01'(!)   = ''              | ''                 | ''       | 'CH2471K1E01'    |'C0201'| '(SMC0201AW)'                                                        | '4700PF'   | '6.3V'        | '10%'    | 'DISCRETE' | 'CAP CHIP 4700P 6.3V (+-10%,X7R,0201)'                         | 'CHIP0201'     | ''          | ''   | '20131017'
 '4700PF'   | '6.3V'  | '10%'     | 'C0201'     | 'EMPTY'   | 'CH2471K1E01'(!)   = ''              | ''                 | ''       | 'CH2471K1E01'    |'C0201'| '(SMC0201AW)'                                                        | 'NA'       | '6.3V'        | '10%'    | 'IO'       | 'CAP CHIP 4700P 6.3V (+-10%,X7R,0201)'                         | 'CHIP0201'     | ''          | ''   | '20131017'
 '0.1UF'    | '4V'    | '20%'     | 'C0201'     | 'X6S'     | 'CH410KMEE00'(!)   = 'End of Design' | 'Comp-Approve'     | ''       | 'CH410KMEE00'    |'C0201'| '(SMC0201AW)'                                                        | '0.1UF'    | '4V'          | '20%'    | 'DISCRETE' | 'CAP CHIP 0.1U 4V(+-20%,X6S,0201)'                             | 'CHIP0201'     | ''          | ''   | '20131017'
 '0.1UF'    | '4V'    | '20%'     | 'C0201'     | 'EMPTY'   | 'CH410KMEE00'(!)   = 'End of Design' | 'Comp-Approve'     | ''       | 'CH410KMEE00'    |'C0201'| '(SMC0201AW)'                                                        | 'NA'       | '4V'          | '20%'    | 'IO'       | 'CAP CHIP 0.1U 4V(+-20%,X6S,0201)'                             | 'CHIP0201'     | ''          | ''   | '20131017'
 '2.2UF'    | '10V'   | '10%'     | 'C0603'     | 'X5R'     | 'CH5222K9907'(!)   = 'End of Design' | 'Comp-Approve'     | ''       | 'CH5222K9907'    |'C0603'| '(SMC0603AW)'                                                        | '2.2UF'    | '10V'         | '10%'    | 'DISCRETE' | 'CAP CHIP 2.2U 10V(+-10%.X5R.0603)'                            | 'CHIP0603'     | ''          | ''   | '20140325'
 '2.2UF'    | '10V'   | '10%'     | 'C0603'     | 'EMPTY'   | 'CH5222K9907'(!)   = 'End of Design' | 'Comp-Approve'     | ''       | 'CH5222K9907'    |'C0603'| '(SMC0603AW)'                                                        | 'NA'       | '10V'         | '10%'    | 'IO'       | 'CAP CHIP 2.2U 10V(+-10%.X5R.0603)'                            | 'CHIP0603'     | ''          | ''   | '20140325'
 '0.047UF'  | '25V'   | '10%'     | 'C0402'     | 'X7R'     | 'CH3474K1B04'(!)   = ''              | ''                 | ''       | 'CH3474K1B04'    |'C0402'| '(C0402_OCTAGONXA,C0402-0201)'                                       | '0.047UF'  | '25V'         | '10%'    | 'DISCRETE' | 'CAP CHIP 0.047U 25V(+-10% X7R 0402)'                          | 'CHIP0402'     | ''          | ''   | '20140325'
 '0.047UF'  | '25V'   | '10%'     | 'C0402'     | 'EMPTY'   | 'CH3474K1B04'(!)   = ''              | ''                 | ''       | 'CH3474K1B04'    |'C0402'| '(C0402_OCTAGONXA,C0402-0201)'                                       | 'NA'       | '25V'         | '10%'    | 'IO'       | 'CAP CHIP 0.047U 25V(+-10% X7R 0402)'                          | 'CHIP0402'     | ''          | ''   | '20140325'
 '3900PF'   | '50V'   | '10%'     | 'C0402'     | 'X7R'     | 'CH23906KB14'(!)   = ''              | ''                 | ''       | 'CH23906KB14'    |'C0402'| '(C0402-0201)'                                                       | '3900PF'   | '50V'         | '10%'    | 'DISCRETE' | 'CAP CHIP 3900P 50V(+-10%,X7R,0402)'                           | 'CHIP0402'     | ''          | ''   | '20140325'
 '3900PF'   | '50V'   | '10%'     | 'C0402'     | 'EMPTY'   | 'CH23906KB14'(!)   = ''              | ''                 | ''       | 'CH23906KB14'    |'C0402'| '(C0402-0201)'                                                       | 'NA'       | '50V'         | '10%'    | 'IO'       | 'CAP CHIP 3900P 50V(+-10%,X7R,0402)'                           | 'CHIP0402'     | ''          | ''   | '20140325'
 '8.2PF'    | '50V'   | '0.1P'    | 'C0402'     | 'NP0'     | 'CH-8216TB09'(!)   = ''              | ''                 | ''       | 'CH-8216TB09'    |'C0402'| '(C0402-0201)'                                                       | '8.2PF'    | '50V'         | '0.1P'   | 'DISCRETE' | 'CAP CHIP 8.2P 50V (+-0.1P NP0 0402)'                          | 'CHIP0402'     | ''          | ''   | '20140326'
 '8.2PF'    | '50V'   | '0.1P'    | 'C0402'     | 'EMPTY'   | 'CH-8216TB09'(!)   = ''              | ''                 | ''       | 'CH-8216TB09'    |'C0402'| '(C0402-0201)'                                                       | 'NA'       | '50V'         | '0.1P'   | 'IO'       | 'CAP CHIP 8.2P 50V (+-0.1P NP0 0402)'                          | 'CHIP0402'     | ''          | ''   | '20140326'
 '220PF'    | '100V'  | '10%'     | 'C0402'     | 'X7R'     | 'CH1228K1B00'(!)   = 'End of Design' | 'Comp-Approve'     | ''       | 'CH1228K1B00'    |'C0402'| '(C0402-0201)'                                                       | '220PF'    | '100V'        | '10%'    | 'DISCRETE' | 'CAP CHIP 220PF 100V(10%,X7R,0402)'                            | 'CHIP0402'     | ''          | ''   | '20140326'
 '220PF'    | '100V'  | '10%'     | 'C0402'     | 'EMPTY'   | 'CH1228K1B00'(!)   = 'End of Design' | 'Comp-Approve'     | ''       | 'CH1228K1B00'    |'C0402'| '(C0402-0201)'                                                       | 'NA'       | '100V'        | '10%'    | 'IO'       | 'CAP CHIP 220PF 100V(10%,X7R,0402)'                            | 'CHIP0402'     | ''          | ''   | '20140326'
 '10UF'     | '25V'   | '10%'     | 'C0805'     | 'X6S'     | 'CH6104KEA00'(!)   = ''              | ''                 | ''       | 'CH6104KEA00'    |'C0805_H61'| '(SMC0805AW)'                                                        | '10UF'     | '25V'         | '10%'    | 'DISCRETE' | 'CAP CHIP 10U 25V(+-10%,X6S,0805,H1.25)'                       | 'CHIP0805'     | ''          | ''   | '20140327'
 '10UF'     | '25V'   | '10%'     | 'C0805'     | 'EMPTY'   | 'CH6104KEA00'(!)   = ''              | ''                 | ''       | 'CH6104KEA00'    |'C0805_H61'| '(SMC0805AW)'                                                        | 'NA'       | '25V'         | '10%'    | 'IO'       | 'CAP CHIP 10U 25V(+-10%,X6S,0805,H1.25)'                       | 'CHIP0805'     | ''          | ''   | '20140327'
 '1UF'      | '25V'   | '10%'     | 'C0402'     | 'X6S'     | 'CH5104KEB02'(!)   = ''              | ''                 | ''       | 'CH5104KEB02'    |'C0402'| '(C0402_OCTAGONXA,C0402-0201)'                                       | '1UF'      | '25V'         | '10%'    | 'DISCRETE' | 'CAP CHIP 1UF 25V(+-10%,X6S,0402)'                             | 'CHIP0402'     | ''          | ''   | '20140327'
 '1UF'      | '25V'   | '10%'     | 'C0402'     | 'EMPTY'   | 'CH5104KEB02'(!)   = ''              | ''                 | ''       | 'CH5104KEB02'    |'C0402'| '(C0402_OCTAGONXA,C0402-0201)'                                       | 'NA'       | '25V'         | '10%'    | 'IO'       | 'CAP CHIP 1UF 25V(+-10%,X6S,0402)'                             | 'CHIP0402'     | ''          | ''   | '20140327'
 '2.2UF'    | '16V'   | '10%'     | 'C0603'     | 'X6S'     | 'CH5223KE901'(!)   = ''              | ''                 | ''       | 'CH5223KE901'    |'C0603'| '(SMC0603AW)'                                                        | '2.2UF'    | '16V'         | '10%'    | 'DISCRETE' | 'CAP CHIP 2.2U 16V(+-10%,X6S,0603)'                            | 'CHIP0603'     | ''          | ''   | '20140327'
 '2.2UF'    | '16V'   | '10%'     | 'C0603'     | 'EMPTY'   | 'CH5223KE901'(!)   = ''              | ''                 | ''       | 'CH5223KE901'    |'C0603'| '(SMC0603AW)'                                                        | 'NA'       | '16V'         | '10%'    | 'IO'       | 'CAP CHIP 2.2U 16V(+-10%,X6S,0603)'                            | 'CHIP0603'     | ''          | ''   | '20140327'
 '22UF'     | '6.3V'  | '20%'     | 'C0603'     | 'X6S'     | 'CH6221ME900'(!)   = ''              | ''                 | ''       | 'CH6221ME900'    |'C0603'| '(SMC0603AW)'                                                        | '22UF'     | '6.3V'        | '20%'    | 'DISCRETE' | 'CAP CHIP 22U 6.3V(+-20%,X6S,0603)'                            | 'CHIP0603'     | ''          | ''   | '20140327'
 '22UF'     | '6.3V'  | '20%'     | 'C0603'     | 'EMPTY'   | 'CH6221ME900'(!)   = ''              | ''                 | ''       | 'CH6221ME900'    |'C0603'| '(SMC0603AW)'                                                        | 'NA'       | '6.3V'        | '20%'    | 'IO'       | 'CAP CHIP 22U 6.3V(+-20%,X6S,0603)'                            | 'CHIP0603'     | ''          | ''   | '20140327'
 '2.2UF'    | '10V'   | '10%'     | 'C0603'     | 'X7R'     | 'CH5222K1906'(!)   = ''              | ''                 | ''       | 'CH5222K1906'    |'C0603'| '(SMC0603AW)'                                                        | '2.2UF'    | '10V'         | '10%'    | 'DISCRETE' | 'CAP CHIP 2.2UF 10V(+-10%.X7R.0603)'                           | 'CHIP0603'     | ''          | ''   | '20140327'
 '2.2UF'    | '10V'   | '10%'     | 'C0603'     | 'EMPTY'   | 'CH5222K1906'(!)   = ''              | ''                 | ''       | 'CH5222K1906'    |'C0603'| '(SMC0603AW)'                                                        | 'NA'       | '10V'         | '10%'    | 'IO'       | 'CAP CHIP 2.2UF 10V(+-10%.X7R.0603)'                           | 'CHIP0603'     | ''          | ''   | '20140327'
 '0.47UF'   | '25V'   | '10%'     | 'C0603'     | 'X7R'     | 'CH4474K1907'(!)   = 'End of Design' | 'Comp-Approve'     | ''       | 'CH4474K1907'    |'C0603'| '(SMC0603AW)'                                                        | '0.47UF'   | '25V'         | '10%'    | 'DISCRETE' | 'CAP CHIP 0.47UF 25V(+-10%,X7R,0603)'                          | 'CHIP0603'     | ''          | ''   | '20140328'
 '0.47UF'   | '25V'   | '10%'     | 'C0603'     | 'EMPTY'   | 'CH4474K1907'(!)   = 'End of Design' | 'Comp-Approve'     | ''       | 'CH4474K1907'    |'C0603'| '(SMC0603AW)'                                                        | 'NA'       | '25V'         | '10%'    | 'IO'       | 'CAP CHIP 0.47UF 25V(+-10%,X7R,0603)'                          | 'CHIP0603'     | ''          | ''   | '20140328'
 '1000PF'   | '50V'   | '5%'      | 'C0603'     | 'NPO'     | 'CH21006J902'(!)   = 'End of Design' | 'Comp-Approve'     | ''       | 'CH21006J902'    |'C0603'| '(SMC0603AW)'                                                        | '1000PF'   | '50V'         | '5%'     | 'DISCRETE' | 'CAP CHIP 1000P 50V(+-5%.NPO.0603)EP'                          | 'CHIP0603'     | ''          | ''   | '20140328'
 '1000PF'   | '50V'   | '5%'      | 'C0603'     | 'EMPTY'   | 'CH21006J902'(!)   = 'End of Design' | 'Comp-Approve'     | ''       | 'CH21006J902'    |'C0603'| '(SMC0603AW)'                                                        | 'NA'       | '50V'         | '5%'     | 'IO'       | 'CAP CHIP 1000P 50V(+-5%.NPO.0603)EP'                          | 'CHIP0603'     | ''          | ''   | '20140328'
 '0.047UF'  | '50V'   | '10%'     | 'C0603'     | 'X7R'     | 'CH34706K912'(!)   = 'End of Design' | 'Comp-Approve'     | ''       | 'CH34706K912'    |'C0603'| '(SMC0603AW)'                                                        | '0.047UF'  | '50V'         | '10%'    | 'DISCRETE' | 'CAP. CHIP 0.047UF 50V(+-10%,X7R,0603)'                        | 'CHIP0603'     | ''          | ''   | '20140328'
 '0.047UF'  | '50V'   | '10%'     | 'C0603'     | 'EMPTY'   | 'CH34706K912'(!)   = 'End of Design' | 'Comp-Approve'     | ''       | 'CH34706K912'    |'C0603'| '(SMC0603AW)'                                                        | 'NA'       | '50V'         | '10%'    | 'IO'       | 'CAP. CHIP 0.047UF 50V(+-10%,X7R,0603)'                        | 'CHIP0603'     | ''          | ''   | '20140328'
 '10UF'     | '25V'   | '20%'     | 'C0603'     | 'X5R'     | 'CH6104M9901'(!)   = ''              | ''                 | ''       | 'CH6104M9901'    |'C0603'| '(SMC0603AW)'                                                        | '10UF'     | '25V'         | '20%'    | 'DISCRETE' | 'CAP CHIP 10UF 25V(+-20%,X5R,0603)'                            | 'CHIP0603'     | ''          | ''   | '20140331'
 '10UF'     | '25V'   | '20%'     | 'C0603'     | 'EMPTY'   | 'CH6104M9901'(!)   = ''              | ''                 | ''       | 'CH6104M9901'    |'C0603'| '(SMC0603AW)'                                                        | 'NA'       | '25V'         | '20%'    | 'IO'       | 'CAP CHIP 10UF 25V(+-20%,X5R,0603)'                            | 'CHIP0603'     | ''          | ''   | '20140331'
 '10UF'     | '16V'   | '10%'     | 'C0805'     | 'X7R'     | 'CH6103K1A00'(!)   = ''              | ''                 | ''       | 'CH6103K1A00'    |'C0805_H61'| '(SMC0805AW)'                                                        | '10UF'     | '16V'         | '10%'    | 'DISCRETE' | 'CAP CHIP 10UF 16V(+-10%,X7R,0805)'                            | 'CHIP0805'     | ''          | ''   | '20140331'
 '10UF'     | '16V'   | '10%'     | 'C0805'     | 'EMPTY'   | 'CH6103K1A00'(!)   = ''              | ''                 | ''       | 'CH6103K1A00'    |'C0805_H61'| '(SMC0805AW)'                                                        | 'NA'       | '16V'         | '10%'    | 'IO'       | 'CAP CHIP 10UF 16V(+-10%,X7R,0805)'                            | 'CHIP0805'     | ''          | ''   | '20140331'
 '0.01UF'   | '1KV'   | '10%'     | 'C1206'     | 'X7R'     | 'CH310FK1201'(!)   = 'End of Design' | 'Comp-Approve'     | ''       | 'CH310FK1201'    |'C1206_H76'| '(SMC1206AW)'                                                        | '0.01UF'   | '1KV'         | '10%'    | 'DISCRETE' | 'CAP CHIP 0.01U 1KV(+-10%,X7R,1206)H1.6'                       | 'CHIP1206'     | ''          | ''   | '20140331'
 '0.01UF'   | '1KV'   | '10%'     | 'C1206'     | 'EMPTY'   | 'CH310FK1201'(!)   = 'End of Design' | 'Comp-Approve'     | ''       | 'CH310FK1201'    |'C1206_H76'| '(SMC1206AW)'                                                        | 'NA'       | '1KV'         | '10%'    | 'IO'       | 'CAP CHIP 0.01U 1KV(+-10%,X7R,1206)H1.6'                       | 'CHIP1206'     | ''          | ''   | '20140331'
 '0.1UF'    | '100V'  | '10%'     | 'C1206'     | 'X7R'     | 'CH4108K1202'(!)   = 'End of Design' | 'Comp-Approve'     | ''       | 'CH4108K1202'    |'C1206_H42'| '(SMC1206AW)'                                                        | '0.1UF'    | '100V'        | '10%'    | 'DISCRETE' | 'CAP CHIP 0.1U 100V(+-10%.X7R.1206)H1.25'                      | 'CHIP1206'     | ''          | ''   | '20140331'
 '0.1UF'    | '100V'  | '10%'     | 'C1206'     | 'EMPTY'   | 'CH4108K1202'(!)   = 'End of Design' | 'Comp-Approve'     | ''       | 'CH4108K1202'    |'C1206_H42'| '(SMC1206AW)'                                                        | 'NA'       | '100V'        | '10%'    | 'IO'       | 'CAP CHIP 0.1U 100V(+-10%.X7R.1206)H1.25'                      | 'CHIP1206'     | ''          | ''   | '20140331'
 '0.1UF'    | '250V'  | '10%'     | 'C1206'     | 'X7R'     | 'CH410CK1200'(!)   = 'End of Design' | 'Comp-Approve'     | ''       | 'CH410CK1200'    |'C1206_H66'| '(SMC1206AW)'                                                        | '0.1UF'    | '250V'        | '10%'    | 'DISCRETE' | 'CAP CHIP 0.1U 250V(10%,X7R,1206)H1.6'                         | 'CHIP1206'     | ''          | ''   | '20140331'
 '0.1UF'    | '250V'  | '10%'     | 'C1206'     | 'EMPTY'   | 'CH410CK1200'(!)   = 'End of Design' | 'Comp-Approve'     | ''       | 'CH410CK1200'    |'C1206_H66'| '(SMC1206AW)'                                                        | 'NA'       | '250V'        | '10%'    | 'IO'       | 'CAP CHIP 0.1U 250V(10%,X7R,1206)H1.6'                         | 'CHIP1206'     | ''          | ''   | '20140331'
 '0.015UF'  | '50V'   | '10%'     | 'C0402'     | 'X7R'     | 'CH3156K1B00'(!)   = 'End of Design' | 'Comp-Approve'     | ''       | 'CH3156K1B00'    |'C0402'| '(C0402-0201)'                                                       | '0.015UF'  | '50V'         | '10%'    | 'DISCRETE' | 'CAP CHIP 0.015U 50V(+-10%,X7R,0402)'                          | 'CHIP0402'     | ''          | ''   | '20140331'
 '0.015UF'  | '50V'   | '10%'     | 'C0402'     | 'EMPTY'   | 'CH3156K1B00'(!)   = 'End of Design' | 'Comp-Approve'     | ''       | 'CH3156K1B00'    |'C0402'| '(C0402-0201)'                                                       | 'NA'       | '50V'         | '10%'    | 'IO'       | 'CAP CHIP 0.015U 50V(+-10%,X7R,0402)'                          | 'CHIP0402'     | ''          | ''   | '20140331'
 '22UF'     | '16V'   | '10%'     | 'C1206'     | 'X6S'     | 'CH6223KE200'(!)   = 'End of Design' | 'Comp-Approve'     | ''       | 'CH6223KE200'    |'C1206_H66'| '(SMC1206AW)'                                                        | '22UF'     | '16V'         | '10%'    | 'DISCRETE' | 'CAP CHIP 22UF 16V(+-10%,X6S,1206)'                            | 'CHIP1206'     | ''          | ''   | '20140401'
 '22UF'     | '16V'   | '10%'     | 'C1206'     | 'EMPTY'   | 'CH6223KE200'(!)   = 'End of Design' | 'Comp-Approve'     | ''       | 'CH6223KE200'    |'C1206_H66'| '(SMC1206AW)'                                                        | 'NA'       | '16V'         | '10%'    | 'IO'       | 'CAP CHIP 22UF 16V(+-10%,X6S,1206)'                            | 'CHIP1206'     | ''          | ''   | '20140401'
 '10UF'     | '6.3V'  | '20%'     | 'C0603'     | 'X6S'     | 'CH6101ME900'(!)   = 'End of Design' | 'Comp-Approve'     | ''       | 'CH6101ME900'    |'C0603'| '(SMC0603AW)'                                                        | '10UF'     | '6.3V'        | '20%'    | 'DISCRETE' | 'CAP CHIP 10U 6.3V(+-20%,X6S,0603)'                            | 'CHIP0603'     | ''          | ''   | '20140415'
 '10UF'     | '6.3V'  | '20%'     | 'C0603'     | 'EMPTY'   | 'CH6101ME900'(!)   = 'End of Design' | 'Comp-Approve'     | ''       | 'CH6101ME900'    |'C0603'| '(SMC0603AW)'                                                        | 'NA'       | '6.3V'        | '20%'    | 'IO'       | 'CAP CHIP 10U 6.3V(+-20%,X6S,0603)'                            | 'CHIP0603'     | ''          | ''   | '20140415'
 '1000PF'   | '2KV'   | '20%'     | 'C1808'     | 'X7R'     | 'CH210IM1I00'(!)   = 'End of Design' | 'Comp-Release Qty' | ''       | 'CH210IM1I00'    |'C1808_H80'| '(SMC1808AW)'                                                        | '1000PF'   | '2KV'         | '20%'    | 'DISCRETE' | 'CAP CHIP 1000P 2KV(20%,X7R,1808,H2.03)'                       | 'CHIP1808'     | ''          | ''   | '20140418'
 '1000PF'   | '2KV'   | '20%'     | 'C1808'     | 'EMPTY'   | 'CH210IM1I00'(!)   = 'End of Design' | 'Comp-Release Qty' | ''       | 'CH210IM1I00'    |'C1808_H80'| '(SMC1808AW)'                                                        | 'NA'       | '2KV'         | '20%'    | 'IO'       | 'CAP CHIP 1000P 2KV(20%,X7R,1808,H2.03)'                       | 'CHIP1808'     | ''          | ''   | '20140418'
 '33NF'     | '25V'   | '10%'     | 'C0402'     | 'X7R'     | 'CH3334K1B00'(!)   = ''              | ''                 | ''       | 'CH3334K1B00'    |'C0402'| '(C0402_OCTAGONXA,C0402-0201)'                                       | '33NF'     | '25V'         | '10%'    | 'DISCRETE' | 'CAP CHIP 33NF 25V(+-10%,X7R,0402)'                            | 'CHIP0402'     | ''          | ''   | '20140507'
 '33NF'     | '25V'   | '10%'     | 'C0402'     | 'EMPTY'   | 'CH3334K1B00'(!)   = ''              | ''                 | ''       | 'CH3334K1B00'    |'C0402'| '(C0402_OCTAGONXA,C0402-0201)'                                       | 'NA'       | '25V'         | '10%'    | 'IO'       | 'CAP CHIP 33NF 25V(+-10%,X7R,0402)'                            | 'CHIP0402'     | ''          | ''   | '20140507'
 '0.1UF'    | '6.3V'  | '10%'     | 'C0201'     | 'X6S'     | 'CH4101KEE01'(!)   = ''              | ''                 | ''       | 'CH4101KEE01'    |'C0201'| '(SMC0201AW)'                                                        | '0.1UF'    | '6.3V'        | '10%'    | 'DISCRETE' | 'CAP CHIP 0.1UF 6.3V(10%,X6S,0201,H0.3)'                       | 'CHIP0201'     | ''          | ''   | '20140508'
 '0.1UF'    | '6.3V'  | '10%'     | 'C0201'     | 'EMPTY'   | 'CH4101KEE01'(!)   = ''              | ''                 | ''       | 'CH4101KEE01'    |'C0201'| '(SMC0201AW)'                                                        | 'NA'       | '6.3V'        | '10%'    | 'IO'       | 'CAP CHIP 0.1UF 6.3V(10%,X6S,0201,H0.3)'                       | 'CHIP0201'     | ''          | ''   | '20140508'
 '0.1UF'    | '16V'   | '10%'     | 'C0201'     | 'X6S'     | 'CH4103KEE01'(!)   = ''              | ''                 | ''       | 'CH4103KEE01'    |'C0201'| '(SMC0201AW)'                                                        | '0.1UF'    | '16V'         | '10%'    | 'DISCRETE' | 'CAP CHIP 0.1UF 16V(+-10%,X6S,0201)'                           | 'CHIP0201'     | ''          | ''   | '20140508'
 '0.1UF'    | '16V'   | '10%'     | 'C0201'     | 'EMPTY'   | 'CH4103KEE01'(!)   = ''              | ''                 | ''       | 'CH4103KEE01'    |'C0201'| '(SMC0201AW)'                                                        | 'NA'       | '16V'         | '10%'    | 'IO'       | 'CAP CHIP 0.1UF 16V(+-10%,X6S,0201)'                           | 'CHIP0201'     | ''          | ''   | '20140508'
 '3300PF'   | '16V'   | '10%'     | 'C0201'     | 'X7R'     | 'CH2333K1E00'(!)   = ''              | ''                 | ''       | 'CH2333K1E00'    |'C0201'| '(C0201_HOME-PLATE_H22)'                                             | '3300PF'   | '16V'         | '10%'    | 'DISCRETE' | 'CAP CHIP 3300P 16V(+-10%,X7R,0201)'                           | 'CHIP0201'     | ''          | ''   | '20140707'
 '3300PF'   | '16V'   | '10%'     | 'C0201'     | 'EMPTY'   | 'CH2333K1E00'(!)   = ''              | ''                 | ''       | 'CH2333K1E00'    |'C0201'| '(C0201_HOME-PLATE_H22)'                                             | 'NA'       | '16V'         | '10%'    | 'IO'       | 'CAP CHIP 3300P 16V(+-10%,X7R,0201)'                           | 'CHIP0201'     | ''          | ''   | '20140707'
 '6800PF'   | '10V'   | '10%'     | 'C0201'     | 'X7R'     | 'CH2682K1E02'(!)   = ''              | ''                 | ''       | 'CH2682K1E02'    |'C0201'| '(SMC0201AW)'                                                        | '6800PF'   | '10V'         | '10%'    | 'DISCRETE' | 'CAP CHIP 6800PF 10V(10%,X7R,0201)'                            | 'CHIP0201'     | ''          | ''   | '20140707'
 '6800PF'   | '10V'   | '10%'     | 'C0201'     | 'EMPTY'   | 'CH2682K1E02'(!)   = ''              | ''                 | ''       | 'CH2682K1E02'    |'C0201'| '(SMC0201AW)'                                                        | 'NA'       | '10V'         | '10%'    | 'IO'       | 'CAP CHIP 6800PF 10V(10%,X7R,0201)'                            | 'CHIP0201'     | ''          | ''   | '20140707'
 '100PF'    | '25V'   | '5%'      | 'C0201'     | 'COG'     | 'CH1104J0E07'(!)   = ''              | ''                 | ''       | 'CH1104J0E07'    |'C0201'| '(SMC0201AW)'                                                        | '100PF'    | '25V'         | '5%'     | 'DISCRETE' | 'CAP CHIP 100P 25V(+-5%,COG,0201)'                             | 'CHIP0201'     | ''          | ''   | '20140707'
 '100PF'    | '25V'   | '5%'      | 'C0201'     | 'EMPTY'   | 'CH1104J0E07'(!)   = ''              | ''                 | ''       | 'CH1104J0E07'    |'C0201'| '(SMC0201AW)'                                                        | 'NA'       | '25V'         | '5%'     | 'IO'       | 'CAP CHIP 100P 25V(+-5%,COG,0201)'                             | 'CHIP0201'     | ''          | ''   | '20140707'
 '330PF'    | '25V'   | '5%'      | 'C0201'     | 'X7R'     | 'CH1334J1E00'(!)   = ''              | ''                 | ''       | 'CH1334J1E00'    |'C0201'| '(SMC0201AW)'                                                        | '330PF'    | '25V'         | '5%'     | 'DISCRETE' | 'CAP CHIP 330P 25V(+-5%,X7R,0201)'                             | 'CHIP0201'     | ''          | ''   | '20140707'
 '330PF'    | '25V'   | '5%'      | 'C0201'     | 'EMPTY'   | 'CH1334J1E00'(!)   = ''              | ''                 | ''       | 'CH1334J1E00'    |'C0201'| '(SMC0201AW)'                                                        | 'NA'       | '25V'         | '5%'     | 'IO'       | 'CAP CHIP 330P 25V(+-5%,X7R,0201)'                             | 'CHIP0201'     | ''          | ''   | '20140707'
 '22UF'     | '10V'   | '10%'     | 'C1206'     | 'X7R'     | 'CH6222K1200'(!)   = 'End of Design' | 'Comp-Approve'     | ''       | 'CH6222K1200'    |'C1206_H76'| '(SMC1206AW)'                                                        | '22UF'     | '10V'         | '10%'    | 'DISCRETE' | 'CAP CHIP 22U 10V(+-10%. X7R.1206)H1.6'                        | 'CHIP1206'     | ''          | ''   | '20140711'
 '22UF'     | '10V'   | '10%'     | 'C1206'     | 'EMPTY'   | 'CH6222K1200'(!)   = 'End of Design' | 'Comp-Approve'     | ''       | 'CH6222K1200'    |'C1206_H76'| '(SMC1206AW)'                                                        | 'NA'       | '10V'         | '10%'    | 'IO'       | 'CAP CHIP 22U 10V(+-10%. X7R.1206)H1.6'                        | 'CHIP1206'     | ''          | ''   | '20140711'
 '22UF'     | '6.3V'  | '20%'     | 'C0805'     | 'X6S'     | 'CH6221MEA02'(!)   = ''              | ''                 | 'SELASS' | 'CH6221MEA02'    |'C0805_H61'| '(SMC0805AW)'                                                        | '22UF'     | '6.3V'        | '20%'    | 'DISCRETE' | 'CAP CHIP 22U 6.3V(+-20%,X6S,0805)SELASS'                      | 'CHIP0805'     | ''          | ''   | '20140714'
 '22UF'     | '6.3V'  | '20%'     | 'C0805'     | 'EMPTY'   | 'CH6221MEA02'(!)   = ''              | ''                 | 'SELASS' | 'CH6221MEA02'    |'C0805_H61'| '(SMC0805AW)'                                                        | 'NA'       | '6.3V'        | '20%'    | 'IO'       | 'CAP CHIP 22U 6.3V(+-20%,X6S,0805)SELASS'                      | 'CHIP0805'     | ''          | ''   | '20140714'
 '1000PF'   | '2000V' | '10%'     | 'THLF'      | 'MEF'     | 'CD2100FKD00'(!)   = ''              | ''                 | ''       | 'CD2100FKD00'    |'EC591_R158X709_394'| '(EC591_R158X709_394)'                                               | '1000PF'   | '2000V'       | '10%'    | 'DISCRETE' | 'CAP MYLAR DIP 1000P 2000V(+-10%,P15)'                         | 'DIP'          | ''          | ''   | '20140725'
 '1000PF'   | '2000V' | '10%'     | 'THLF'      | 'EMPTY'   | 'CD2100FKD00'(!)   = ''              | ''                 | ''       | 'CD2100FKD00'    |'EC591_R158X709_394'| '(EC591_R158X709_394)'                                               | 'NA'       | '2000V'       | '10%'    | 'IO'       | 'CAP MYLAR DIP 1000P 2000V(+-10%,P15)'                         | 'DIP'          | ''          | ''   | '20140725'
 '1PF'      | '50V'   | '0.05P'   | 'C0402'     | 'COG'     | 'CH-106T0B00'(!)   = ''              | ''                 | ''       | 'CH-106T0B00'    |'C0402'| '(C0402-0201)'                                                       | '1PF'      | '50V'         | '0.05P'  | 'DISCRETE' | 'CAP CHIP 1P 50V(+-0.05P,COG,0402)'                            | 'CHIP0402'     | ''          | ''   | '20140812'
 '1PF'      | '50V'   | '0.05P'   | 'C0402'     | 'EMPTY'   | 'CH-106T0B00'(!)   = ''              | ''                 | ''       | 'CH-106T0B00'    |'C0402'| '(C0402-0201)'                                                       | 'NA'       | '50V'         | '0.05P'  | 'IO'       | 'CAP CHIP 1P 50V(+-0.05P,COG,0402)'                            | 'CHIP0402'     | ''          | ''   | '20140812'
 '18NF'     | '100V'  | '10%'     | 'C0603'     | 'X7R'     | 'CH3188K1900'(!)   = ''              | ''                 | ''       | 'CH3188K1900'    |'C0603'| '(SMC0603AW)'                                                        | '18NF'     | '100V'        | '10%'    | 'DISCRETE' | 'CAP CHIP 18NF 100V(+-10%,X7R,0603)'                           | 'CHIP0603'     | ''          | ''   | '20140813'
 '18NF'     | '100V'  | '10%'     | 'C0603'     | 'EMPTY'   | 'CH3188K1900'(!)   = ''              | ''                 | ''       | 'CH3188K1900'    |'C0603'| '(SMC0603AW)'                                                        | 'NA'       | '100V'        | '10%'    | 'IO'       | 'CAP CHIP 18NF 100V(+-10%,X7R,0603)'                           | 'CHIP0603'     | ''          | ''   | '20140813'
 '0.39UF'   | '10V'   | '10%'     | 'C0402'     | 'X5R'     | 'CH4392K9B00'(!)   = 'End of Design' | 'Comp-Release Qty' | ''       | 'CH4392K9B00'    |'C0402'| '(C0402-0201)'                                                       | '0.39UF'   | '10V'         | '10%'    | 'DISCRETE' | 'CAP CHIP 0.39UF 10V(+-10%,X5R,0402)'                          | 'CHIP0402'     | ''          | ''   | '20140813'
 '0.39UF'   | '10V'   | '10%'     | 'C0402'     | 'EMPTY'   | 'CH4392K9B00'(!)   = 'End of Design' | 'Comp-Release Qty' | ''       | 'CH4392K9B00'    |'C0402'| '(C0402-0201)'                                                       | 'NA'       | '10V'         | '10%'    | 'IO'       | 'CAP CHIP 0.39UF 10V(+-10%,X5R,0402)'                          | 'CHIP0402'     | ''          | ''   | '20140813'
 '0.47UF'   | '50V'   | '10%'     | 'C0603'     | 'X5R'     | 'CH4476K9901'(!)   = 'End of Design' | 'Comp-Approve'     | ''       | 'CH4476K9901'    |'C0603'| '(SMC0603AW)'                                                        | '0.47UF'   | '50V'         | '10%'    | 'DISCRETE' | 'CAP CHIP 0.47UF 50V(10%,X5R,0603)'                            | 'CHIP0603'     | ''          | ''   | '20140817'
 '0.47UF'   | '50V'   | '10%'     | 'C0603'     | 'EMPTY'   | 'CH4476K9901'(!)   = 'End of Design' | 'Comp-Approve'     | ''       | 'CH4476K9901'    |'C0603'| '(SMC0603AW)'                                                        | 'NA'       | '50V'         | '10%'    | 'IO'       | 'CAP CHIP 0.47UF 50V(10%,X5R,0603)'                            | 'CHIP0603'     | ''          | ''   | '20140817'
 '0.01UF'   | '25V'   | '5%'      | 'C0402'     | 'X7R'     | 'CH3104J1B00'(!)   = ''              | ''                 | ''       | 'CH3104J1B00'    |'C0402'| '(C0402-0201)'                                                       | '0.01UF'   | '25V'         | '5%'     | 'DISCRETE' | 'CAP CHIP 0.01U 25V (+-5%,X7R,0402)'                           | 'CHIP0402'     | ''          | ''   | '20140819'
 '0.01UF'   | '25V'   | '5%'      | 'C0402'     | 'EMPTY'   | 'CH3104J1B00'(!)   = ''              | ''                 | ''       | 'CH3104J1B00'    |'C0402'| '(C0402-0201)'                                                       | 'NA'       | '25V'         | '5%'     | 'IO'       | 'CAP CHIP 0.01U 25V (+-5%,X7R,0402)'                           | 'CHIP0402'     | ''          | ''   | '20140819'
 '22UF'     | '25V'   | '20%'     | 'C0805'     | 'X5R'     | 'CH6224M9A00'(!)   = ''              | ''                 | ''       | 'CH6224M9A00'    |'C0805_H61'| '(SMC0805AW)'                                                        | '22UF'     | '25V'         | '20%'    | 'DISCRETE' | 'CAP CHIP 22U 25V(+-20%,X5R,0805)'                             | 'CHIP0805'     | ''          | ''   | '20140819'
 '22UF'     | '25V'   | '20%'     | 'C0805'     | 'EMPTY'   | 'CH6224M9A00'(!)   = ''              | ''                 | ''       | 'CH6224M9A00'    |'C0805_H61'| '(SMC0805AW)'                                                        | 'NA'       | '25V'         | '20%'    | 'IO'       | 'CAP CHIP 22U 25V(+-20%,X5R,0805)'                             | 'CHIP0805'     | ''          | ''   | '20140819'
 '100UF'    | '10V'   | '20%'     | 'C1206'     | 'X5R'     | 'CH7102M9201'(!)   = 'End of Design' | 'Comp-Approve'     | ''       | 'CH7102M9201'    |'C1206_H76'| '(SMC1206AW)'                                                        | '100UF'    | '10V'         | '20%'    | 'DISCRETE' | 'CAP CHIP 100U 10V(+-20%,X5R,3216)'                            | 'CHIP1206'     | ''          | ''   | '20140819'
 '100UF'    | '10V'   | '20%'     | 'C1206'     | 'EMPTY'   | 'CH7102M9201'(!)   = 'End of Design' | 'Comp-Approve'     | ''       | 'CH7102M9201'    |'C1206_H76'| '(SMC1206AW)'                                                        | 'NA'       | '10V'         | '20%'    | 'IO'       | 'CAP CHIP 100U 10V(+-20%,X5R,3216)'                            | 'CHIP1206'     | ''          | ''   | '20140819'
 '10UF'     | '35V'   | '10%'     | 'C1206'     | 'X7R'     | 'CH6105K1200'(!)   = 'End of Design' | 'Comp-Approve'     | ''       | 'CH6105K1200'    |'C1206_H76'| '(SMC1206AW)'                                                        | '10UF'     | '35V'         | '10%'    | 'DISCRETE' | 'CAP CHIP 10U 35V(+-10%.X7R.1206)H1.6'                         | 'CHIP1206'     | ''          | ''   | '20140826'
 '10UF'     | '35V'   | '10%'     | 'C1206'     | 'EMPTY'   | 'CH6105K1200'(!)   = 'End of Design' | 'Comp-Approve'     | ''       | 'CH6105K1200'    |'C1206_H76'| '(SMC1206AW)'                                                        | 'NA'       | '35V'         | '10%'    | 'IO'       | 'CAP CHIP 10U 35V(+-10%.X7R.1206)H1.6'                         | 'CHIP1206'     | ''          | ''   | '20140826'
 '1UF'      | '16V'   | '10%'     | 'C0402'     | 'X6S'     | 'CH5103KEB01'(!)   = ''              | ''                 | ''       | 'CH5103KEB01'    |'C0402'| '(C0402_OCTAGONXA,C0402-0201)'                                       | '1UF'      | '16V'         | '10%'    | 'DISCRETE' | 'CAP CHIP 1UF 16V(10%,X6S,0402)'                               | 'CHIP0402'     | ''          | ''   | '20140828'
 '1UF'      | '16V'   | '10%'     | 'C0402'     | 'EMPTY'   | 'CH5103KEB01'(!)   = ''              | ''                 | ''       | 'CH5103KEB01'    |'C0402'| '(C0402_OCTAGONXA,C0402-0201)'                                       | 'NA'       | '16V'         | '10%'    | 'IO'       | 'CAP CHIP 1UF 16V(10%,X6S,0402)'                               | 'CHIP0402'     | ''          | ''   | '20140828'
 '10UF'     | '6.3V'  | '10%'     | 'C0805'     | 'X6S'     | 'CH6101KEA00'(!)   = 'End of Design' | 'Comp-Approve'     | ''       | 'CH6101KEA00'    |'C0805_H61'| '(SMC0805AW)'                                                        | '10UF'     | '6.3V'        | '10%'    | 'DISCRETE' | 'CAP CHIP 10UF,6.3V (+-10%,X6S,0805)'                          | 'CHIP0805'     | ''          | ''   | '20140829'
 '10UF'     | '6.3V'  | '10%'     | 'C0805'     | 'EMPTY'   | 'CH6101KEA00'(!)   = 'End of Design' | 'Comp-Approve'     | ''       | 'CH6101KEA00'    |'C0805_H61'| '(SMC0805AW)'                                                        | 'NA'       | '6.3V'        | '10%'    | 'IO'       | 'CAP CHIP 10UF,6.3V (+-10%,X6S,0805)'                          | 'CHIP0805'     | ''          | ''   | '20140829'
 '1UF'      | '6.3V'  | '10%'     | 'C0402'     | 'X6S'     | 'CH5101KEB00'(!)   = 'End of Design' | 'Comp-Approve'     | ''       | 'CH5101KEB00'    |'C0402'| '(C0402-0201)'                                                       | '1UF'      | '6.3V'        | '10%'    | 'DISCRETE' | 'CAP CHIP 1U 6.3V(+-10%,X6S,0402)'                             | 'CHIP0402'     | ''          | ''   | '20140829'
 '1UF'      | '6.3V'  | '10%'     | 'C0402'     | 'EMPTY'   | 'CH5101KEB00'(!)   = 'End of Design' | 'Comp-Approve'     | ''       | 'CH5101KEB00'    |'C0402'| '(C0402-0201)'                                                       | 'NA'       | '6.3V'        | '10%'    | 'IO'       | 'CAP CHIP 1U 6.3V(+-10%,X6S,0402)'                             | 'CHIP0402'     | ''          | ''   | '20140829'
 '100UF'    | '6.3V'  | '20%'     | 'C1206'     | 'X6T'     | 'CH7101MH200'(!)   = 'End of Design' | 'Comp-Approve'     | ''       | 'CH7101MH200'    |'C1206_H66'| '(SMC1206AW)'                                                        | '100UF'    | '6.3V'        | '20%'    | 'DISCRETE' | 'CAP CHIP 100U 6.3V(+-20%,X6T,1206)H1.6'                       | 'CHIP1206'     | ''          | ''   | '20140829'
 '100UF'    | '6.3V'  | '20%'     | 'C1206'     | 'EMPTY'   | 'CH7101MH200'(!)   = 'End of Design' | 'Comp-Approve'     | ''       | 'CH7101MH200'    |'C1206_H66'| '(SMC1206AW)'                                                        | 'NA'       | '6.3V'        | '20%'    | 'IO'       | 'CAP CHIP 100U 6.3V(+-20%,X6T,1206)H1.6'                       | 'CHIP1206'     | ''          | ''   | '20140829'
 '4.7UF'    | '25V'   | '10%'     | 'C0805'     | 'X7R'     | 'TH5474K1A00'(!)   = ''              | ''                 | 'EMSSEL' | 'TH5474K1A00'    |'C0805_H61'| '(SMC0805AW)'                                                        | '4.7UF'    | '25V'         | '10%'    | 'DISCRETE' | 'CAP CHIP 4.7U 25V(+-10%,X7R,0805)EMS SEL'                     | 'CHIP0805'     | ''          | ''   | '20140912'
 '4.7UF'    | '25V'   | '10%'     | 'C0805'     | 'EMPTY'   | 'TH5474K1A00'(!)   = ''              | ''                 | 'EMSSEL' | 'TH5474K1A00'    |'C0805_H61'| '(SMC0805AW)'                                                        | 'NA'       | '25V'         | '10%'    | 'IO'       | 'CAP CHIP 4.7U 25V(+-10%,X7R,0805)EMS SEL'                     | 'CHIP0805'     | ''          | ''   | '20140912'
 '1000PF'   | '200V'  | '10%'     | 'C1206'     | 'X7R'     | 'CH210CK1200'(!)   = ''              | ''                 | ''       | 'CH210CK1200'    |'C1206_H42'| '(SMC1206AW)'                                                        | '1000PF'   | '200V'        | '10%'    | 'DISCRETE' | 'CAP CHIP 1000PF 200V(+-10%,X7R,1206)H0.8'                     | 'CHIP1206'     | ''          | ''   | '20140930'
 '1000PF'   | '200V'  | '10%'     | 'C1206'     | 'EMPTY'   | 'CH210CK1200'(!)   = ''              | ''                 | ''       | 'CH210CK1200'    |'C1206_H42'| '(SMC1206AW)'                                                        | 'NA'       | '200V'        | '10%'    | 'IO'       | 'CAP CHIP 1000PF 200V(+-10%,X7R,1206)H0.8'                     | 'CHIP1206'     | ''          | ''   | '20140930'
 '0.47UF'   | '10V'   | '10%'     | 'C0402'     | 'X7R'     | 'CH4472K1B00'(!)   = 'End of Design' | 'Comp-Approve'     | ''       | 'CH4472K1B00'    |'C0402'| '(C0402_OCTAGONXA,C0402-0201)'                                       | '0.47UF'   | '10V'         | '10%'    | 'DISCRETE' | 'CAP CHIP 0.47UF 10V(+-10%,X7R,0402)'                          | 'CHIP0402'     | ''          | ''   | '20141003'
 '0.47UF'   | '10V'   | '10%'     | 'C0402'     | 'EMPTY'   | 'CH4472K1B00'(!)   = 'End of Design' | 'Comp-Approve'     | ''       | 'CH4472K1B00'    |'C0402'| '(C0402_OCTAGONXA,C0402-0201)'                                       | 'NA'       | '10V'         | '10%'    | 'IO'       | 'CAP CHIP 0.47UF 10V(+-10%,X7R,0402)'                          | 'CHIP0402'     | ''          | ''   | '20141003'
 '0.39UF'   | '10V'   | '10%'     | 'C0603'     | 'X7R'     | 'CH4392K1900'(!)   = 'End of Design' | 'P/N Release'      | ''       | 'CH4392K1900'    |'C0603'| '(SMC0603AW)'                                                        | '0.39UF'   | '10V'         | '10%'    | 'DISCRETE' | 'CAP CHIP 0.39U 10V(+-10%,X7R,0603)'                           | 'CHIP0603'     | ''          | ''   | '20141016'
 '0.39UF'   | '10V'   | '10%'     | 'C0603'     | 'EMPTY'   | 'CH4392K1900'(!)   = 'End of Design' | 'P/N Release'      | ''       | 'CH4392K1900'    |'C0603'| '(SMC0603AW)'                                                        | 'NA'       | '10V'         | '10%'    | 'IO'       | 'CAP CHIP 0.39U 10V(+-10%,X7R,0603)'                           | 'CHIP0603'     | ''          | ''   | '20141016'
 '22UF'     | '35V'   | '20%'     | 'C0805'     | 'X5R'     | 'CH6225M9A00'(!)   = 'End of Design' | 'Comp-Release Qty' | ''       | 'CH6225M9A00'    |'C0805_H61'| '(SMC0805AW)'                                                        | '22UF'     | '35V'         | '20%'    | 'DISCRETE' | 'CAP CHIP 22UF 35V(+-20%,X5R,0805)'                            | 'CHIP0805'     | ''          | ''   | '20141016'
 '22UF'     | '35V'   | '20%'     | 'C0805'     | 'EMPTY'   | 'CH6225M9A00'(!)   = 'End of Design' | 'Comp-Release Qty' | ''       | 'CH6225M9A00'    |'C0805_H61'| '(SMC0805AW)'                                                        | 'NA'       | '35V'         | '20%'    | 'IO'       | 'CAP CHIP 22UF 35V(+-20%,X5R,0805)'                            | 'CHIP0805'     | ''          | ''   | '20141016'
 '220UF'    | '4V'    | '20%'     | 'C1206'     | 'X5R'     | 'CH722KM9200'(!)   = 'End of Design' | 'Comp-Approve'     | ''       | 'CH722KM9200'    |'C1206_H76'| '(SMC1206AW)'                                                        | '220UF'    | '4V'          | '20%'    | 'DISCRETE' | 'CAP CHIP 220UF 4V(+-20%,X5R,1206)'                            | 'CHIP1206'     | ''          | ''   | '20141103'
 '220UF'    | '4V'    | '20%'     | 'C1206'     | 'EMPTY'   | 'CH722KM9200'(!)   = 'End of Design' | 'Comp-Approve'     | ''       | 'CH722KM9200'    |'C1206_H76'| '(SMC1206AW)'                                                        | 'NA'       | '4V'          | '20%'    | 'IO'       | 'CAP CHIP 220UF 4V(+-20%,X5R,1206)'                            | 'CHIP1206'     | ''          | ''   | '20141103'
 '22UF'     | '10V'   | '10%'     | 'C0805'     | 'X6S'     | 'CH6222KEA00'(!)   = 'End of Design' | 'Comp-Release Qty' | ''       | 'CH6222KEA00'    |'C0805_H61'| '(SMC0805AW)'                                                        | '22UF'     | '10V'         | '10%'    | 'DISCRETE' | 'CAP CHIP 22U 10V(+-10%,X6S,0805)'                             | 'CHIP0805'     | ''          | ''   | '20141127'
 '22UF'     | '10V'   | '10%'     | 'C0805'     | 'EMPTY'   | 'CH6222KEA00'(!)   = 'End of Design' | 'Comp-Release Qty' | ''       | 'CH6222KEA00'    |'C0805_H61'| '(SMC0805AW)'                                                        | 'NA'       | '10V'         | '10%'    | 'IO'       | 'CAP CHIP 22U 10V(+-10%,X6S,0805)'                             | 'CHIP0805'     | ''          | ''   | '20141127'
 '22UF'     | '10V'   | '20%'     | 'C0805'     | 'X7S'     | 'CH6222M1A00'(!)   = 'End of Design' | 'Comp-Release Qty' | ''       | 'CH6222M1A00'    |'C0805_H61'| '(SMC0805AW)'                                                        | '22UF'     | '10V'         | '20%'    | 'DISCRETE' | 'CAP CHIP 22U 10V(+-20%,X7S,0805)'                             | 'CHIP0805'     | ''          | ''   | '20141127'
 '22UF'     | '10V'   | '20%'     | 'C0805'     | 'EMPTY'   | 'CH6222M1A00'(!)   = 'End of Design' | 'Comp-Release Qty' | ''       | 'CH6222M1A00'    |'C0805_H61'| '(SMC0805AW)'                                                        | 'NA'       | '10V'         | '20%'    | 'IO'       | 'CAP CHIP 22U 10V(+-20%,X7S,0805)'                             | 'CHIP0805'     | ''          | ''   | '20141127'
 '4.7UF'    | '25V'   | '10%'     | 'C0603'     | 'X6S'     | 'CH-474KE900'(!)   = ''              | 'End of Life'      | ''       | 'CH-474KE900'    |'C0603_EOL'| '(SMC0603AW)'                                                        | '4.7UF'    | '25V'         | '10%'    | 'DISCRETE' | 'CAP CHIP 4.7UF 25V(+-10%,X6S,0603)'                           | 'CHIP0603'     | ''          | ''   | '20141212'
 '4.7UF'    | '25V'   | '10%'     | 'C0603'     | 'EMPTY'   | 'CH-474KE900'(!)   = ''              | 'End of Life'      | ''       | 'CH-474KE900'    |'C0603_EOL'| '(SMC0603AW)'                                                        | 'NA'       | '25V'         | '10%'    | 'IO'       | 'CAP CHIP 4.7UF 25V(+-10%,X6S,0603)'                           | 'CHIP0603'     | ''          | ''   | '20141212'
 '2PF'      | '50V'   | '0.05PF'  | 'C0402'     | 'C0G'     | 'CH-206T0B00'(!)   = ''              | ''                 | ''       | 'CH-206T0B00'    |'C0402'| '(C0402-0201)'                                                       | '2PF'      | '50V'         | '0.05PF' | 'DISCRETE' | 'CAP CHIP 2P 50V(+-0.05PF,C0G,0402)'                           | 'CHIP0402'     | ''          | ''   | '20141225'
 '2PF'      | '50V'   | '0.05PF'  | 'C0402'     | 'EMPTY'   | 'CH-206T0B00'(!)   = ''              | ''                 | ''       | 'CH-206T0B00'    |'C0402'| '(C0402-0201)'                                                       | 'NA'       | '50V'         | '0.05PF' | 'IO'       | 'CAP CHIP 2P 50V(+-0.05PF,C0G,0402)'                           | 'CHIP0402'     | ''          | ''   | '20141225'
 '330PF'    | '50V'   | '10%'     | 'C0402'     | 'X7R'     | 'CH13306KB11'(!)   = ''              | 'End of Life'      | ''       | 'CH13306KB11'    |'C0402_EOL'| '(C0402-0201)'                                                       | '330PF'    | '50V'         | '10%'    | 'DISCRETE' | 'CAP CHIP 330P 50V(+-10%.X7R.0402)'                            | 'CHIP0402'     | ''          | ''   | '20140116'
 '330PF'    | '50V'   | '10%'     | 'C0402'     | 'EMPTY'   | 'CH13306KB11'(!)   = ''              | 'End of Life'      | ''       | 'CH13306KB11'    |'C0402_EOL'| '(C0402-0201)'                                                       | 'NA'       | '50V'         | '10%'    | 'IO'       | 'CAP CHIP 330P 50V(+-10%.X7R.0402)'                            | 'CHIP0402'     | ''          | ''   | '20140116'
 '10UF'     | '16V'   | '20%'     | 'C0603'     | 'X6S'     | 'CH6103ME902'(!)   = ''              | ''                 | ''       | 'CH6103ME902'    |'C0603'| '(SMC0603AW)'                                                        | '10UF'     | '16V'         | '20%'    | 'DISCRETE' | 'CAP CHIP 10U 16V(+-20%,X6S,0603)'                             | 'CHIP0603'     | ''          | ''   | '20140116'
 '10UF'     | '16V'   | '20%'     | 'C0603'     | 'EMPTY'   | 'CH6103ME902'(!)   = ''              | ''                 | ''       | 'CH6103ME902'    |'C0603'| '(SMC0603AW)'                                                        | 'NA'       | '16V'         | '20%'    | 'IO'       | 'CAP CHIP 10U 16V(+-20%,X6S,0603)'                             | 'CHIP0603'     | ''          | ''   | '20140116'
 '0.068UF'  | '50V'   | '10%'     | 'C0603'     | 'X7R'     | 'CH3686K1901'(!)   = 'End of Design' | 'Comp-Approve'     | ''       | 'CH3686K1901'    |'C0603'| '(SMC0603AW)'                                                        | '0.068UF'  | '50V'         | '10%'    | 'DISCRETE' | 'CAP CHIP 0.068UF 50V(10%,X7R,0603)'                           | 'CHIP0603'     | ''          | ''   | '20140119'
 '0.068UF'  | '50V'   | '10%'     | 'C0603'     | 'EMPTY'   | 'CH3686K1901'(!)   = 'End of Design' | 'Comp-Approve'     | ''       | 'CH3686K1901'    |'C0603'| '(SMC0603AW)'                                                        | 'NA'       | '50V'         | '10%'    | 'IO'       | 'CAP CHIP 0.068UF 50V(10%,X7R,0603)'                           | 'CHIP0603'     | ''          | ''   | '20140119'
 '1UF'      | '6.3V'  | '10%'     | '0402'      | 'X5R'     | 'CH5101K9B01'(!)   = 'End of Design' | 'Comp-Release Qty' | ''       | 'CH5101K9B01'    |'C0402'| '(C0402_OCTAGONXA,C0402-0201)'                                       | '1UF'      | '6.3V'        | '10%'    | 'DISCRETE' | 'CAP CHIP 1U 6.3V(+-10%,X5R,0402)'                             | 'CHIP0402'     | ''          | ''   | '20150209'
 '1UF'      | '6.3V'  | '10%'     | '0402'      | 'EMPTY'   | 'CH5101K9B01'(!)   = 'End of Design' | 'Comp-Release Qty' | ''       | 'CH5101K9B01'    |'C0402'| '(C0402_OCTAGONXA,C0402-0201)'                                       | 'NA'       | '6.3V'        | '10%'    | 'IO'       | 'CAP CHIP 1U 6.3V(+-10%,X5R,0402)'                             | 'CHIP0402'     | ''          | ''   | '20150209'
 '10UF'     | '6.3V'  | '20%'     | '0603'      | 'X7R'     | 'CH6101M1904'(!)   = 'End of Design' | 'Comp-Approve'     | ''       | 'CH6101M1904'    |'C0603'| '(SMC0603AW)'                                                        | '10UF'     | '6.3V'        | '20%'    | 'DISCRETE' | 'CAP CHIP 10U.6.3V(+-20%.X7R.0603)'                            | 'CHIP0603'     | ''          | ''   | '20100917'
 '10UF'     | '6.3V'  | '20%'     | '0603'      | 'EMPTY'   | 'CH6101M1904'(!)   = 'End of Design' | 'Comp-Approve'     | ''       | 'CH6101M1904'    |'C0603'| '(SMC0603AW)'                                                        | 'NA'       | '6.3V'        | '20%'    | 'IO'       | 'CAP CHIP 10U.6.3V(+-20%.X7R.0603)'                            | 'CHIP0603'     | ''          | ''   | '20100917'
 '4.7UF'    | '10V'   | '10%'     | '0402'      | 'X5R'     | 'CH5472K9B00'(!)   = ''              | ''                 | ''       | 'CH5472K9B00'    |'C0402'| '(C0402-0201)'                                                       | '4.7UF'    | '10V'         | '10%'    | 'DISCRETE' | 'CAP CHIP 4.7U 10V(+-10%,X5R,0402)'                            | 'CHIP0402'     | ''          | ''   | '20150226'
 '4.7UF'    | '10V'   | '10%'     | '0402'      | 'EMPTY'   | 'CH5472K9B00'(!)   = ''              | ''                 | ''       | 'CH5472K9B00'    |'C0402'| '(C0402-0201)'                                                       | 'NA'       | '10V'         | '10%'    | 'IO'       | 'CAP CHIP 4.7U 10V(+-10%,X5R,0402)'                            | 'CHIP0402'     | ''          | ''   | '20150226'
 '22UF'     | '16V'   | '10%'     | '1206'      | 'X5R'     | 'CH6223K9201'(!)   = 'End of Design' | 'Comp-Approve'     | ''       | 'CH6223K9201'    |'C1206_H76'| '(SMC1206AW)'                                                        | '22UF'     | '16V'         | '10%'    | 'DISCRETE' | 'CAP CHIP 22U 16V(+-10%,X5R,1206)H1.6'                         | 'CHIP1206'     | ''          | ''   | '20150304'
 '22UF'     | '16V'   | '10%'     | '1206'      | 'EMPTY'   | 'CH6223K9201'(!)   = 'End of Design' | 'Comp-Approve'     | ''       | 'CH6223K9201'    |'C1206_H76'| '(SMC1206AW)'                                                        | 'NA'       | '16V'         | '10%'    | 'IO'       | 'CAP CHIP 22U 16V(+-10%,X5R,1206)H1.6'                         | 'CHIP1206'     | ''          | ''   | '20150304'
 '22UF'     | '10V'   | '20%'     | 'C0805'     | 'X6S'     | 'CH6222MEA00'(!)   = ''              | ''                 | ''       | 'CH6222MEA00'    |'C0805_H61'| '(SMC0805AW)'                                                        | '22UF'     | '10V'         | '20%'    | 'DISCRETE' | 'CAP CHIP 22U 10V(+-20%,X6S,0805)'                             | 'CHIP0805'     | ''          | ''   | '20150401'
 '22UF'     | '10V'   | '20%'     | 'C0805'     | 'EMPTY'   | 'CH6222MEA00'(!)   = ''              | ''                 | ''       | 'CH6222MEA00'    |'C0805_H61'| '(SMC0805AW)'                                                        | 'NA'       | '10V'         | '20%'    | 'IO'       | 'CAP CHIP 22U 10V(+-20%,X6S,0805)'                             | 'CHIP0805'     | ''          | ''   | '20150401'
 '1UF'      | '6.3V'  | '10%'     | '0402'      | 'X7R'     | 'CH5101K1B01'(!)   = ''              | ''                 | ''       | 'CH5101K1B01'    |'C0402'| '(C0402_OCTAGONXA,C0402-0201)'                                       | '1UF'      | '6.3V'        | '10%'    | 'DISCRETE' | 'CAP CHIP 1U,6.3V(+-10%,X7R,0402)'                             | 'CHIP0402'     | ''          | ''   | '20150410'
 '1UF'      | '6.3V'  | '10%'     | '0402'      | 'EMPTY'   | 'CH5101K1B01'(!)   = ''              | ''                 | ''       | 'CH5101K1B01'    |'C0402'| '(C0402_OCTAGONXA,C0402-0201)'                                       | 'NA'       | '6.3V'        | '10%'    | 'IO'       | 'CAP CHIP 1U,6.3V(+-10%,X7R,0402)'                             | 'CHIP0402'     | ''          | ''   | '20150410'
 '0.1UF'    | '16V'   | '10%'     | '0402'      | 'X7R'     | 'TMP_QCH4103K1B09'(!) = 'End of Design' | 'Comp-Approve'     | 'SELASS' | 'CH4103K1B09'    |'C0402'| '(C0402_OCTAGONXA,C0402-0201)'                                       | '0.1UF'    | '16V'         | '10%'    | 'DISCRETE' | 'CAP CHIP 0.1U 16V(10%,X7R,0402)SEL-ASS'                       | 'CHIP0402'     | ''          | ''   | '20150413'
 '0.1UF'    | '16V'   | '10%'     | '0402'      | 'EMPTY'   | 'TMP_QCH4103K1B09'(!) = 'End of Design' | 'Comp-Approve'     | 'SELASS' | 'CH4103K1B09'    |'C0402'| '(C0402_OCTAGONXA,C0402-0201)'                                       | 'NA'       | '16V'         | '10%'    | 'IO'       | 'CAP CHIP 0.1U 16V(10%,X7R,0402)SEL-ASS'                       | 'CHIP0402'     | ''          | ''   | '20150413'
 '0.22UF'   | '6.3V'  | '10%'     | '0201'      | 'X5R'     | 'CH4221K9E00'(!)   = ''              | ''                 | ''       | 'CH4221K9E00'    |'C0201'| '(SMC0201AW)'                                                        | '0.22UF'   | '6.3V'        | '10%'    | 'DISCRETE' | 'CAP CHIP 0.22UF 6.3V(+-10%,X5R,0201)'                         | 'CHIP0201'     | ''          | ''   | '20150511'
 '0.22UF'   | '6.3V'  | '10%'     | '0201'      | 'EMPTY'   | 'CH4221K9E00'(!)   = ''              | ''                 | ''       | 'CH4221K9E00'    |'C0201'| '(SMC0201AW)'                                                        | 'NA'       | '6.3V'        | '10%'    | 'IO'       | 'CAP CHIP 0.22UF 6.3V(+-10%,X5R,0201)'                         | 'CHIP0201'     | ''          | ''   | '20150511'
 '100UF'    | '4V'    | '20%'     | 'C0805'     | 'X6S'     | 'CH710KMEA00'(!)   = ''              | ''                 | ''       | 'CH710KMEA00'    |'C0805_H61'| '(SMC0805AW)'                                                        | '100UF'    | '4V'          | '20%'    | 'DISCRETE' | 'CAP CHIP 100U 4V(+-20%,X6S,0805)'                             | 'CHIP0805'     | ''          | ''   | '20150602'
 '100UF'    | '4V'    | '20%'     | 'C0805'     | 'EMPTY'   | 'CH710KMEA00'(!)   = ''              | ''                 | ''       | 'CH710KMEA00'    |'C0805_H61'| '(SMC0805AW)'                                                        | 'NA'       | '4V'          | '20%'    | 'IO'       | 'CAP CHIP 100U 4V(+-20%,X6S,0805)'                             | 'CHIP0805'     | ''          | ''   | '20150602'
 '2.2UF'    | '10V'   | '10%'     | 'C0402'     | 'X6S'     | 'CH5222KEB01'(!)   = ''              | ''                 | ''       | 'CH5222KEB01'    |'C0402'| '(C0402_OCTAGONXA,C0402-0201)'                                       | '2.2UF'    | '10V'         | '10%'    | 'DISCRETE' | 'CAP CHIP 2.2UF 10V(+-10%,X6S,0402)'                           | 'CHIP0402'     | ''          | ''   | '20150612'
 '2.2UF'    | '10V'   | '10%'     | 'C0402'     | 'EMPTY'   | 'CH5222KEB01'(!)   = ''              | ''                 | ''       | 'CH5222KEB01'    |'C0402'| '(C0402_OCTAGONXA,C0402-0201)'                                       | 'NA'       | '10V'         | '10%'    | 'IO'       | 'CAP CHIP 2.2UF 10V(+-10%,X6S,0402)'                           | 'CHIP0402'     | ''          | ''   | '20150612'
 '470PF'    | '50V'   | '5%'      | 'C0402'     | 'NPO'     | 'CH1476J0B04'(!)   = ''              | ''                 | ''       | 'CH1476J0B04'    |'C0402'| '(C0402-0201)'                                                       | '470PF'    | '50V'         | '5%'     | 'DISCRETE' | 'CAP CHIP 470P,50V(+-5%,NPO,0402)MUR'                          | 'CHIP0402'     | ''          | ''   | '20150612'
 '470PF'    | '50V'   | '5%'      | 'C0402'     | 'EMPTY'   | 'CH1476J0B04'(!)   = ''              | ''                 | ''       | 'CH1476J0B04'    |'C0402'| '(C0402-0201)'                                                       | 'NA'       | '50V'         | '5%'     | 'IO'       | 'CAP CHIP 470P,50V(+-5%,NPO,0402)MUR'                          | 'CHIP0402'     | ''          | ''   | '20150612'
 '4700PF'   | '50V'   | '10%'     | 'C0402'     | 'X7R'     | 'CH2476K1B04'(!)   = ''              | ''                 | ''       | 'CH2476K1B04'    |'C0402'| '(C0402-0201)'                                                       | '4700PF'   | '50V'         | '10%'    | 'DISCRETE' | 'CAP CHIP 4700PF 50V(10%,X7R,0402)MUR'                         | 'CHIP0402'     | ''          | ''   | '20150612'
 '4700PF'   | '50V'   | '10%'     | 'C0402'     | 'EMPTY'   | 'CH2476K1B04'(!)   = ''              | ''                 | ''       | 'CH2476K1B04'    |'C0402'| '(C0402-0201)'                                                       | 'NA'       | '50V'         | '10%'    | 'IO'       | 'CAP CHIP 4700PF 50V(10%,X7R,0402)MUR'                         | 'CHIP0402'     | ''          | ''   | '20150612'
 '0.1UF'    | '10V'   | '10%'     | 'C0402'     | 'X7R'     | 'CH4102K1B08'(!)   = 'End of Design' | 'Comp-Approve'     | ''       | 'CH4102K1B08'    |'C0402'| '(C0402-0201)'                                                       | '0.1UF'    | '10V'         | '10%'    | 'DISCRETE' | 'CAP CHIP 0.1U 10V(+-10%,X7R,0402)MUR'                         | 'CHIP0402'     | ''          | ''   | '20150612'
 '0.1UF'    | '10V'   | '10%'     | 'C0402'     | 'EMPTY'   | 'CH4102K1B08'(!)   = 'End of Design' | 'Comp-Approve'     | ''       | 'CH4102K1B08'    |'C0402'| '(C0402-0201)'                                                       | 'NA'       | '10V'         | '10%'    | 'IO'       | 'CAP CHIP 0.1U 10V(+-10%,X7R,0402)MUR'                         | 'CHIP0402'     | ''          | ''   | '20150612'
 '0.022UF'  | '16V'   | '10%'     | 'C0402'     | 'X7R'     | 'CH3223K1B11'(!)   = ''              | ''                 | ''       | 'CH3223K1B11'    |'C0402'| '(C0402-0201)'                                                       | '0.022UF'  | '16V'         | '10%'    | 'DISCRETE' | 'CAP CHIP 0.022U 16V(+-10%,X7R,0402)SAM'                       | 'CHIP0402'     | ''          | ''   | '20150612'
 '0.022UF'  | '16V'   | '10%'     | 'C0402'     | 'EMPTY'   | 'CH3223K1B11'(!)   = ''              | ''                 | ''       | 'CH3223K1B11'    |'C0402'| '(C0402-0201)'                                                       | 'NA'       | '16V'         | '10%'    | 'IO'       | 'CAP CHIP 0.022U 16V(+-10%,X7R,0402)SAM'                       | 'CHIP0402'     | ''          | ''   | '20150612'
 '0.01UF'   | '16V'   | '10%'     | 'C0402'     | 'X7R'     | 'CH3103K1B17'(!)   = ''              | ''                 | ''       | 'CH3103K1B17'    |'C0402'| '(C0402-0201)'                                                       | '0.01UF'   | '16V'         | '10%'    | 'DISCRETE' | 'CAP CHIP 0.01U 16V,+-10%,X7R,0402)SAM'                        | 'CHIP0402'     | ''          | ''   | '20150612'
 '0.01UF'   | '16V'   | '10%'     | 'C0402'     | 'EMPTY'   | 'CH3103K1B17'(!)   = ''              | ''                 | ''       | 'CH3103K1B17'    |'C0402'| '(C0402-0201)'                                                       | 'NA'       | '16V'         | '10%'    | 'IO'       | 'CAP CHIP 0.01U 16V,+-10%,X7R,0402)SAM'                        | 'CHIP0402'     | ''          | ''   | '20150612'
 '2700PF'   | '50V'   | '10%'     | 'C0402'     | 'X7R'     | 'CH2276K1B07'(!)   = ''              | ''                 | ''       | 'CH2276K1B07'    |'C0402'| '(C0402-0201)'                                                       | '2700PF'   | '50V'         | '10%'    | 'DISCRETE' | 'CAP CHIP 2700P 50V(+-10%,X7R,0402)SAM'                        | 'CHIP0402'     | ''          | ''   | '20150612'
 '2700PF'   | '50V'   | '10%'     | 'C0402'     | 'EMPTY'   | 'CH2276K1B07'(!)   = ''              | ''                 | ''       | 'CH2276K1B07'    |'C0402'| '(C0402-0201)'                                                       | 'NA'       | '50V'         | '10%'    | 'IO'       | 'CAP CHIP 2700P 50V(+-10%,X7R,0402)SAM'                        | 'CHIP0402'     | ''          | ''   | '20150612'
 '470PF'    | '50V'   | '5%'      | 'C0402'     | 'NPO'     | 'CH1476J0B03'(!)   = ''              | ''                 | ''       | 'CH1476J0B03'    |'C0402'| '(C0402-0201)'                                                       | '470PF'    | '50V'         | '5%'     | 'DISCRETE' | 'CAP CHIP 470P,50V(+-5%,NPO,0402)SAM'                          | 'CHIP0402'     | ''          | ''   | '20150612'
 '470PF'    | '50V'   | '5%'      | 'C0402'     | 'EMPTY'   | 'CH1476J0B03'(!)   = ''              | ''                 | ''       | 'CH1476J0B03'    |'C0402'| '(C0402-0201)'                                                       | 'NA'       | '50V'         | '5%'     | 'IO'       | 'CAP CHIP 470P,50V(+-5%,NPO,0402)SAM'                          | 'CHIP0402'     | ''          | ''   | '20150612'
 '47PF'     | '50V'   | '5%'      | 'C0402'     | 'NPO'     | 'CH0476J0B11'(!)   = 'End of Design' | 'Comp-Approve'     | ''       | 'CH0476J0B11'    |'C0402'| '(C0402-0201)'                                                       | '47PF'     | '50V'         | '5%'     | 'DISCRETE' | 'CAP CHIP 47P 50V(+-5%,NPO,0402)SAM'                           | 'CHIP0402'     | ''          | ''   | '20150612'
 '47PF'     | '50V'   | '5%'      | 'C0402'     | 'EMPTY'   | 'CH0476J0B11'(!)   = 'End of Design' | 'Comp-Approve'     | ''       | 'CH0476J0B11'    |'C0402'| '(C0402-0201)'                                                       | 'NA'       | '50V'         | '5%'     | 'IO'       | 'CAP CHIP 47P 50V(+-5%,NPO,0402)SAM'                           | 'CHIP0402'     | ''          | ''   | '20150612'
 '0.22UF'   | '6.3V'  | '20%'     | 'C0201'     | 'X6S'     | 'CH4221MEE01'(!)   = ''              | ''                 | ''       | 'CH4221MEE01'    |'C0201'| '(SMC0201AW)'                                                        | '0.22UF'   | '6.3V'        | '20%'    | 'DISCRETE' | 'CAP CHIP 0.22UF 6.3V(20%,X6S,0201)'                           | 'CHIP0201'     | ''          | ''   | '20150612'
 '0.22UF'   | '6.3V'  | '20%'     | 'C0201'     | 'EMPTY'   | 'CH4221MEE01'(!)   = ''              | ''                 | ''       | 'CH4221MEE01'    |'C0201'| '(SMC0201AW)'                                                        | 'NA'       | '6.3V'        | '20%'    | 'IO'       | 'CAP CHIP 0.22UF 6.3V(20%,X6S,0201)'                           | 'CHIP0201'     | ''          | ''   | '20150612'
 '220UF'    | '4V'    | '20%'     | 'C1206'     | 'X6S'     | 'CH722KME200'(!)   = 'End of Design' | 'Comp-Approve'     | ''       | 'CH722KME200'    |'C1206_H66'| '(SMC1206AW)'                                                        | '220UF'    | '4V'          | '20%'    | 'DISCRETE' | 'CAP CHIP 220U 4V(+-20%,X6S,1206)'                             | 'CHIP1206'     | ''          | ''   | '20150612'
 '220UF'    | '4V'    | '20%'     | 'C1206'     | 'EMPTY'   | 'CH722KME200'(!)   = 'End of Design' | 'Comp-Approve'     | ''       | 'CH722KME200'    |'C1206_H66'| '(SMC1206AW)'                                                        | 'NA'       | '4V'          | '20%'    | 'IO'       | 'CAP CHIP 220U 4V(+-20%,X6S,1206)'                             | 'CHIP1206'     | ''          | ''   | '20150612'
 '2.2UF'    | '16V'   | '10%'     | 'C0603'     | 'X6S'     | 'CH5223KE902'(!)   = ''              | ''                 | ''       | 'CH5223KE902'    |'C0603'| '(SMC0603AW)'                                                        | '2.2UF'    | '16V'         | '10%'    | 'DISCRETE' | 'CAP CHIP 2.2U 16V(+-10%,X6S,0603)MUR'                         | 'CHIP0603'     | ''          | ''   | '20150612'
 '2.2UF'    | '16V'   | '10%'     | 'C0603'     | 'EMPTY'   | 'CH5223KE902'(!)   = ''              | ''                 | ''       | 'CH5223KE902'    |'C0603'| '(SMC0603AW)'                                                        | 'NA'       | '16V'         | '10%'    | 'IO'       | 'CAP CHIP 2.2U 16V(+-10%,X6S,0603)MUR'                         | 'CHIP0603'     | ''          | ''   | '20150612'
 '1UF'      | '10V'   | '10%'     | 'C0603'     | 'X7R'     | 'CH5102K1902'(!)   = 'End of Design' | 'Comp-Approve'     | ''       | 'CH5102K1902'    |'C0603'| '(SMC0603AW)'                                                        | '1UF'      | '10V'         | '10%'    | 'DISCRETE' | 'CAP CHIP 1U 10V(+-10%,X7R,0603)SAM'                           | 'CHIP0603'     | ''          | ''   | '20150612'
 '1UF'      | '10V'   | '10%'     | 'C0603'     | 'EMPTY'   | 'CH5102K1902'(!)   = 'End of Design' | 'Comp-Approve'     | ''       | 'CH5102K1902'    |'C0603'| '(SMC0603AW)'                                                        | 'NA'       | '10V'         | '10%'    | 'IO'       | 'CAP CHIP 1U 10V(+-10%,X7R,0603)SAM'                           | 'CHIP0603'     | ''          | ''   | '20150612'
 '10UF'     | '10V'   | '20%'     | 'C0603'     | 'X7R'     | 'CH6102M1900'(!)   = ''              | 'End of Life'      | ''       | 'CH6102M1900'    |'C0603_EOL'| '(SMC0603AW)'                                                        | '10UF'     | '10V'         | '20%'    | 'DISCRETE' | 'CAP CHIP 10U,10V(+-20%,X7R,0603)SAM'                          | 'CHIP0603'     | ''          | ''   | '20150612'
 '10UF'     | '10V'   | '20%'     | 'C0603'     | 'EMPTY'   | 'CH6102M1900'(!)   = ''              | 'End of Life'      | ''       | 'CH6102M1900'    |'C0603_EOL'| '(SMC0603AW)'                                                        | 'NA'       | '10V'         | '20%'    | 'IO'       | 'CAP CHIP 10U,10V(+-20%,X7R,0603)SAM'                          | 'CHIP0603'     | ''          | ''   | '20150612'
 '10UF'     | '10V'   | '20%'     | 'C0603'     | 'X7R'     | 'CH6102M1901'(!)   = ''              | 'End of Life'      | ''       | 'CH6102M1901'    |'C0603_EOL'| '(SMC0603AW)'                                                        | '10UF'     | '10V'         | '20%'    | 'DISCRETE' | 'CAP CHIP 10U,10V(+-20%,X7R,0603)MUR'                          | 'CHIP0603'     | ''          | ''   | '20150612'
 '10UF'     | '10V'   | '20%'     | 'C0603'     | 'EMPTY'   | 'CH6102M1901'(!)   = ''              | 'End of Life'      | ''       | 'CH6102M1901'    |'C0603_EOL'| '(SMC0603AW)'                                                        | 'NA'       | '10V'         | '20%'    | 'IO'       | 'CAP CHIP 10U,10V(+-20%,X7R,0603)MUR'                          | 'CHIP0603'     | ''          | ''   | '20150612'
 '22UF'     | '4V'    | '20%'     | 'C0603'     | 'X6S'     | 'CH622KME905'(!)   = ''              | ''                 | ''       | 'CH622KME905'    |'C0603'| '(SMC0603AW)'                                                        | '22UF'     | '4V'          | '20%'    | 'DISCRETE' | 'CAP CHIP 22UF 4V(+-20%,X6S,0603)MUR'                          | 'CHIP0603'     | ''          | ''   | '20150612'
 '22UF'     | '4V'    | '20%'     | 'C0603'     | 'EMPTY'   | 'CH622KME905'(!)   = ''              | ''                 | ''       | 'CH622KME905'    |'C0603'| '(SMC0603AW)'                                                        | 'NA'       | '4V'          | '20%'    | 'IO'       | 'CAP CHIP 22UF 4V(+-20%,X6S,0603)MUR'                          | 'CHIP0603'     | ''          | ''   | '20150612'
 '1UF'      | '25V'   | '10%'     | 'C0402'     | 'X7R'     | 'CH-104K6B00'(!)   = 'End of Design' | 'End of Life'      | ''       | 'CH-104K6B00'    |'C0402_EOL'| '(C0402-0201)'                                                       | '1UF'      | '25V'         | '10%'    | 'DISCRETE' | 'CAP CHIP 1U 25V (+-10%,X7S,0402)'                             | 'CHIP0402'     | ''          | ''   | '20150612'
 '1UF'      | '25V'   | '10%'     | 'C0402'     | 'EMPTY'   | 'CH-104K6B00'(!)   = 'End of Design' | 'End of Life'      | ''       | 'CH-104K6B00'    |'C0402_EOL'| '(C0402-0201)'                                                       | 'NA'       | '25V'         | '10%'    | 'IO'       | 'CAP CHIP 1U 25V (+-10%,X7S,0402)'                             | 'CHIP0402'     | ''          | ''   | '20150612'
 '2.2UF'    | '10V'   | '10%'     | 'C0402'     | 'X7S'     | 'CH5222K6B00'(!)   = 'End of Design' | 'Comp-Approve'     | ''       | 'CH5222K6B00'    |'C0402'| '(C0402-0201)'                                                       | '2.2UF'    | '10V'         | '10%'    | 'DISCRETE' | 'CAP CHIP 2.2UF 10V(10%,X7S,0402)'                             | 'CHIP0402'     | ''          | ''   | '20150612'
 '2.2UF'    | '10V'   | '10%'     | 'C0402'     | 'EMPTY'   | 'CH5222K6B00'(!)   = 'End of Design' | 'Comp-Approve'     | ''       | 'CH5222K6B00'    |'C0402'| '(C0402-0201)'                                                       | 'NA'       | '10V'         | '10%'    | 'IO'       | 'CAP CHIP 2.2UF 10V(10%,X7S,0402)'                             | 'CHIP0402'     | ''          | ''   | '20150612'
 '0.22UF'   | '10V'   | '10%'     | 'C0402'     | 'X7R'     | 'CH4222K1B00'(!)   = 'End of Design' | 'Comp-Release Qty' | ''       | 'CH4222K1B00'    |'C0402'| '(C0402-0201)'                                                       | '0.22UF'   | '10V'         | '10%'    | 'DISCRETE' | 'CAP CHIP 0.22U 10V(+-10%,X7R,0402)'                           | 'CHIP0402'     | ''          | ''   | '20150612'
 '0.22UF'   | '10V'   | '10%'     | 'C0402'     | 'EMPTY'   | 'CH4222K1B00'(!)   = 'End of Design' | 'Comp-Release Qty' | ''       | 'CH4222K1B00'    |'C0402'| '(C0402-0201)'                                                       | 'NA'       | '10V'         | '10%'    | 'IO'       | 'CAP CHIP 0.22U 10V(+-10%,X7R,0402)'                           | 'CHIP0402'     | ''          | ''   | '20150612'
 '15PF'     | '50V'   | '5%'      | 'C0402'     | 'C0G'     | 'CH0156J0B07'(!)   = ''              | ''                 | ''       | 'CH0156J0B07'    |'C0402'| '(C0402-0201)'                                                       | '15PF'     | '50V'         | '5%'     | 'DISCRETE' | 'CAP CHIP 15P 50V(+-5% C0G 0402)MUR'                           | 'CHIP0402'     | ''          | ''   | '20150614'
 '15PF'     | '50V'   | '5%'      | 'C0402'     | 'EMPTY'   | 'CH0156J0B07'(!)   = ''              | ''                 | ''       | 'CH0156J0B07'    |'C0402'| '(C0402-0201)'                                                       | 'NA'       | '50V'         | '5%'     | 'IO'       | 'CAP CHIP 15P 50V(+-5% C0G 0402)MUR'                           | 'CHIP0402'     | ''          | ''   | '20150614'
 '18PF'     | '50V'   | '5%'      | 'C0402'     | 'C0G'     | 'CH0186J0B05'(!)   = ''              | ''                 | ''       | 'CH0186J0B05'    |'C0402'| '(C0402-0201)'                                                       | '18PF'     | '50V'         | '5%'     | 'DISCRETE' | 'CAP CHIP 18P 50V(+-5% C0G 0402)MUR'                           | 'CHIP0402'     | ''          | ''   | '20150614'
 '18PF'     | '50V'   | '5%'      | 'C0402'     | 'EMPTY'   | 'CH0186J0B05'(!)   = ''              | ''                 | ''       | 'CH0186J0B05'    |'C0402'| '(C0402-0201)'                                                       | 'NA'       | '50V'         | '5%'     | 'IO'       | 'CAP CHIP 18P 50V(+-5% C0G 0402)MUR'                           | 'CHIP0402'     | ''          | ''   | '20150614'
 '22PF'     | '50V'   | '5%'      | 'C0402'     | 'NPO'     | 'CH0226J0B16'(!)   = ''              | ''                 | ''       | 'CH0226J0B16'    |'C0402'| '(C0402-0201)'                                                       | '22PF'     | '50V'         | '5%'     | 'DISCRETE' | 'CAP CHIP 22P 50V(+-5%,NPO,0402)MUR'                           | 'CHIP0402'     | ''          | ''   | '20150614'
 '22PF'     | '50V'   | '5%'      | 'C0402'     | 'EMPTY'   | 'CH0226J0B16'(!)   = ''              | ''                 | ''       | 'CH0226J0B16'    |'C0402'| '(C0402-0201)'                                                       | 'NA'       | '50V'         | '5%'     | 'IO'       | 'CAP CHIP 22P 50V(+-5%,NPO,0402)MUR'                           | 'CHIP0402'     | ''          | ''   | '20150614'
 '100PF'    | '50V'   | '5%'      | 'C0402'     | 'NPO'     | 'CH1106J0B16'(!)   = ''              | ''                 | ''       | 'CH1106J0B16'    |'C0402'| '(C0402-0201)'                                                       | '100PF'    | '50V'         | '5%'     | 'DISCRETE' | 'CAP CHIP 100P 50V(+-5%,NPO,0402)MUR'                          | 'CHIP0402'     | ''          | ''   | '20150614'
 '100PF'    | '50V'   | '5%'      | 'C0402'     | 'EMPTY'   | 'CH1106J0B16'(!)   = ''              | ''                 | ''       | 'CH1106J0B16'    |'C0402'| '(C0402-0201)'                                                       | 'NA'       | '50V'         | '5%'     | 'IO'       | 'CAP CHIP 100P 50V(+-5%,NPO,0402)MUR'                          | 'CHIP0402'     | ''          | ''   | '20150614'
 '470PF'    | '50V'   | '10%'     | 'C0402'     | 'X7R'     | 'CH1476K1B11'(!)   = ''              | ''                 | ''       | 'CH1476K1B11'    |'C0402'| '(C0402-0201)'                                                       | '470PF'    | '50V'         | '10%'    | 'DISCRETE' | 'CAP CHIP 470P 50V(+-10%,X7R,0402)MUR'                         | 'CHIP0402'     | ''          | ''   | '20150614'
 '470PF'    | '50V'   | '10%'     | 'C0402'     | 'EMPTY'   | 'CH1476K1B11'(!)   = ''              | ''                 | ''       | 'CH1476K1B11'    |'C0402'| '(C0402-0201)'                                                       | 'NA'       | '50V'         | '10%'    | 'IO'       | 'CAP CHIP 470P 50V(+-10%,X7R,0402)MUR'                         | 'CHIP0402'     | ''          | ''   | '20150614'
 '1000PF'   | '50V'   | '5%'      | 'C0402'     | 'X7R'     | 'CH2106J1B04'(!)   = ''              | ''                 | ''       | 'CH2106J1B04'    |'C0402'| '(C0402-0201)'                                                       | '1000PF'   | '50V'         | '5%'     | 'DISCRETE' | 'CAP CHIP 1000P 50V(+-5%,X7R,0402)MUR'                         | 'CHIP0402'     | ''          | ''   | '20150614'
 '1000PF'   | '50V'   | '5%'      | 'C0402'     | 'EMPTY'   | 'CH2106J1B04'(!)   = ''              | ''                 | ''       | 'CH2106J1B04'    |'C0402'| '(C0402-0201)'                                                       | 'NA'       | '50V'         | '5%'     | 'IO'       | 'CAP CHIP 1000P 50V(+-5%,X7R,0402)MUR'                         | 'CHIP0402'     | ''          | ''   | '20150614'
 '1000PF'   | '16V'   | '10%'     | 'C0402'     | 'X7R'     | 'CH2103K1B03'(!)   = ''              | ''                 | ''       | 'CH2103K1B03'    |'C0402'| '(C0402_OCTAGONXA,C0402-0201)'                                       | '1000PF'   | '16V'         | '10%'    | 'DISCRETE' | 'CAP CHIP 1000PF 16V (+-10%,X7R,0402)MUR'                      | 'CHIP0402'     | ''          | ''   | '20150614'
 '1000PF'   | '16V'   | '10%'     | 'C0402'     | 'EMPTY'   | 'CH2103K1B03'(!)   = ''              | ''                 | ''       | 'CH2103K1B03'    |'C0402'| '(C0402_OCTAGONXA,C0402-0201)'                                       | 'NA'       | '16V'         | '10%'    | 'IO'       | 'CAP CHIP 1000PF 16V (+-10%,X7R,0402)MUR'                      | 'CHIP0402'     | ''          | ''   | '20150614'
 '1500PF'   | '50V'   | '10%'     | 'C0402'     | 'X7R'     | 'CH2156K1B08'(!)   = ''              | ''                 | ''       | 'CH2156K1B08'    |'C0402'| '(C0402-0201)'                                                       | '1500PF'   | '50V'         | '10%'    | 'DISCRETE' | 'CAP CHIP1500PF 50V(+-10%,X7R,0402)MUR'                        | 'CHIP0402'     | ''          | ''   | '20150614'
 '1500PF'   | '50V'   | '10%'     | 'C0402'     | 'EMPTY'   | 'CH2156K1B08'(!)   = ''              | ''                 | ''       | 'CH2156K1B08'    |'C0402'| '(C0402-0201)'                                                       | 'NA'       | '50V'         | '10%'    | 'IO'       | 'CAP CHIP1500PF 50V(+-10%,X7R,0402)MUR'                        | 'CHIP0402'     | ''          | ''   | '20150614'
 '2200PF'   | '50V'   | '10%'     | 'C0402'     | 'X7R'     | 'CH2226K1B06'(!)   = ''              | ''                 | ''       | 'CH2226K1B06'    |'C0402'| '(C0402-0201)'                                                       | '2200PF'   | '50V'         | '10%'    | 'DISCRETE' | 'CAP CHIP 2200P 50V(+-10%,X7R,0402)MUR'                        | 'CHIP0402'     | ''          | ''   | '20150614'
 '2200PF'   | '50V'   | '10%'     | 'C0402'     | 'EMPTY'   | 'CH2226K1B06'(!)   = ''              | ''                 | ''       | 'CH2226K1B06'    |'C0402'| '(C0402-0201)'                                                       | 'NA'       | '50V'         | '10%'    | 'IO'       | 'CAP CHIP 2200P 50V(+-10%,X7R,0402)MUR'                        | 'CHIP0402'     | ''          | ''   | '20150614'
 '4700P'    | '25V'   | '10%'     | 'C0402'     | 'X7R'     | 'CH2474K1B08'(!)   = ''              | ''                 | ''       | 'CH2474K1B08'    |'C0402'| '(C0402-0201)'                                                       | '4700P'    | '25V'         | '10%'    | 'DISCRETE' | 'CAP CHIP 4700P 25V(+-10%,X7R,0402)MUR'                        | 'CHIP0402'     | ''          | ''   | '20150614'
 '4700P'    | '25V'   | '10%'     | 'C0402'     | 'EMPTY'   | 'CH2474K1B08'(!)   = ''              | ''                 | ''       | 'CH2474K1B08'    |'C0402'| '(C0402-0201)'                                                       | 'NA'       | '25V'         | '10%'    | 'IO'       | 'CAP CHIP 4700P 25V(+-10%,X7R,0402)MUR'                        | 'CHIP0402'     | ''          | ''   | '20150614'
 '0.01UF'   | '25V'   | '10%'     | 'C0402'     | 'X7R'     | 'CH3104K1B11'(!)   = ''              | ''                 | ''       | 'CH3104K1B11'    |'C0402'| '(C0402-0201)'                                                       | '0.01UF'   | '25V'         | '10%'    | 'DISCRETE' | 'CAP CHIP 0.01U 25V(+-10%,X7R,0402)MUR'                        | 'CHIP0402'     | ''          | ''   | '20150614'
 '0.01UF'   | '25V'   | '10%'     | 'C0402'     | 'EMPTY'   | 'CH3104K1B11'(!)   = ''              | ''                 | ''       | 'CH3104K1B11'    |'C0402'| '(C0402-0201)'                                                       | 'NA'       | '25V'         | '10%'    | 'IO'       | 'CAP CHIP 0.01U 25V(+-10%,X7R,0402)MUR'                        | 'CHIP0402'     | ''          | ''   | '20150614'
 '0.015UF'  | '16V'   | '10%'     | 'C0402'     | 'X7R'     | 'CH3153K1B03'(!)   = ''              | ''                 | ''       | 'CH3153K1B03'    |'C0402'| '(C0402-0201)'                                                       | '0.015UF'  | '16V'         | '10%'    | 'DISCRETE' | 'CAP CHIP 0.015U 16V(+-10%.X7R.0402)MUR'                       | 'CHIP0402'     | ''          | ''   | '20150614'
 '0.015UF'  | '16V'   | '10%'     | 'C0402'     | 'EMPTY'   | 'CH3153K1B03'(!)   = ''              | ''                 | ''       | 'CH3153K1B03'    |'C0402'| '(C0402-0201)'                                                       | 'NA'       | '16V'         | '10%'    | 'IO'       | 'CAP CHIP 0.015U 16V(+-10%.X7R.0402)MUR'                       | 'CHIP0402'     | ''          | ''   | '20150614'
 '0.047UF'  | '10V'   | '10%'     | 'C0402'     | 'X7R'     | 'CH3472K1B04'(!)   = 'End of Design' | 'Comp-Approve'     | ''       | 'CH3472K1B04'    |'C0402'| '(C0402-0201)'                                                       | '0.047UF'  | '10V'         | '10%'    | 'DISCRETE' | 'CAP CHIP 0.047U 10V(+-10% X7R 0402)MUR'                       | 'CHIP0402'     | ''          | ''   | '20150614'
 '0.047UF'  | '10V'   | '10%'     | 'C0402'     | 'EMPTY'   | 'CH3472K1B04'(!)   = 'End of Design' | 'Comp-Approve'     | ''       | 'CH3472K1B04'    |'C0402'| '(C0402-0201)'                                                       | 'NA'       | '10V'         | '10%'    | 'IO'       | 'CAP CHIP 0.047U 10V(+-10% X7R 0402)MUR'                       | 'CHIP0402'     | ''          | ''   | '20150614'
 '0.047UF'  | '25V'   | '10%'     | 'C0402'     | 'X7R'     | 'CH3474K1B03'(!)   = ''              | ''                 | ''       | 'CH3474K1B03'    |'C0402'| '(C0402-0201)'                                                       | '0.047UF'  | '25V'         | '10%'    | 'DISCRETE' | 'CAP CHIP 0.047U 25V(+-10% X7R 0402)MUR'                       | 'CHIP0402'     | ''          | ''   | '20150614'
 '0.047UF'  | '25V'   | '10%'     | 'C0402'     | 'EMPTY'   | 'CH3474K1B03'(!)   = ''              | ''                 | ''       | 'CH3474K1B03'    |'C0402'| '(C0402-0201)'                                                       | 'NA'       | '25V'         | '10%'    | 'IO'       | 'CAP CHIP 0.047U 25V(+-10% X7R 0402)MUR'                       | 'CHIP0402'     | ''          | ''   | '20150614'
 '0.068UF'  | '16V'   | '10%'     | 'C0402'     | 'X7R'     | 'CH3683K1B02'(!)   = ''              | ''                 | ''       | 'CH3683K1B02'    |'C0402'| '(C0402-0201)'                                                       | '0.068UF'  | '16V'         | '10%'    | 'DISCRETE' | 'CAP CHIP 0.068UF 16V(+-10%,X7R 0402)MUR'                      | 'CHIP0402'     | ''          | ''   | '20150614'
 '0.068UF'  | '16V'   | '10%'     | 'C0402'     | 'EMPTY'   | 'CH3683K1B02'(!)   = ''              | ''                 | ''       | 'CH3683K1B02'    |'C0402'| '(C0402-0201)'                                                       | 'NA'       | '16V'         | '10%'    | 'IO'       | 'CAP CHIP 0.068UF 16V(+-10%,X7R 0402)MUR'                      | 'CHIP0402'     | ''          | ''   | '20150614'
 '0.1UF'    | '25V'   | '10%'     | 'C0402'     | 'X7R'     | 'CH4104K1B03'(!)   = 'End of Design' | 'Comp-Approve'     | ''       | 'CH4104K1B03'    |'C0402'| '(C0402_OCTAGONXA,C0402-0201,C0402_OCTAGONXA_BOUND22)'               | '0.1UF'    | '25V'         | '10%'    | 'DISCRETE' | 'CAP CHIP 0.1U 25V(+-10%,X7R,0402)MUR'                         | 'CHIP0402'     | ''          | ''   | '20150615'
 '0.1UF'    | '25V'   | '10%'     | 'C0402'     | 'EMPTY'   | 'CH4104K1B03'(!)   = 'End of Design' | 'Comp-Approve'     | ''       | 'CH4104K1B03'    |'C0402'| '(C0402_OCTAGONXA,C0402-0201,C0402_OCTAGONXA_BOUND22)'               | 'NA'       | '25V'         | '10%'    | 'IO'       | 'CAP CHIP 0.1U 25V(+-10%,X7R,0402)MUR'                         | 'CHIP0402'     | ''          | ''   | '20150615'
 '1UF'      | '16V'   | '10%'     | 'C0402'     | 'X6S'     | 'CH5103KEB03'(!)   = ''              | ''                 | ''       | 'CH5103KEB03'    |'C0402'| '(C0402_OCTAGONXA,C0402-0201)'                                       | '1UF'      | '16V'         | '10%'    | 'DISCRETE' | 'CAP CHIP 1UF 16V(10%,X6S,0402)MUR'                            | 'CHIP0402'     | ''          | ''   | '20150615'
 '1UF'      | '16V'   | '10%'     | 'C0402'     | 'EMPTY'   | 'CH5103KEB03'(!)   = ''              | ''                 | ''       | 'CH5103KEB03'    |'C0402'| '(C0402_OCTAGONXA,C0402-0201)'                                       | 'NA'       | '16V'         | '10%'    | 'IO'       | 'CAP CHIP 1UF 16V(10%,X6S,0402)MUR'                            | 'CHIP0402'     | ''          | ''   | '20150615'
 '0.47UF'   | '16V'   | '10%'     | 'C0603'     | 'X7R'     | 'CH4473K1904'(!)   = ''              | ''                 | ''       | 'CH4473K1904'    |'C0603'| '(SMC0603AW)'                                                        | '0.47UF'   | '16V'         | '10%'    | 'DISCRETE' | 'CAP CHIP 0.47U 16V (+-10%,X7R,0603)MUR'                       | 'CHIP0603'     | ''          | ''   | '20150615'
 '0.47UF'   | '16V'   | '10%'     | 'C0603'     | 'EMPTY'   | 'CH4473K1904'(!)   = ''              | ''                 | ''       | 'CH4473K1904'    |'C0603'| '(SMC0603AW)'                                                        | 'NA'       | '16V'         | '10%'    | 'IO'       | 'CAP CHIP 0.47U 16V (+-10%,X7R,0603)MUR'                       | 'CHIP0603'     | ''          | ''   | '20150615'
 '0.47UF'   | '25V'   | '10%'     | 'C0603'     | 'X7R'     | 'CH4474K1902'(!)   = 'End of Design' | 'Comp-Approve'     | ''       | 'CH4474K1902'    |'C0603'| '(SMC0603AW)'                                                        | '0.47UF'   | '25V'         | '10%'    | 'DISCRETE' | 'CAP CHIP 0.47UF 25V(+-10%,X7R,0603)MUR'                       | 'CHIP0603'     | ''          | ''   | '20150615'
 '0.47UF'   | '25V'   | '10%'     | 'C0603'     | 'EMPTY'   | 'CH4474K1902'(!)   = 'End of Design' | 'Comp-Approve'     | ''       | 'CH4474K1902'    |'C0603'| '(SMC0603AW)'                                                        | 'NA'       | '25V'         | '10%'    | 'IO'       | 'CAP CHIP 0.47UF 25V(+-10%,X7R,0603)MUR'                       | 'CHIP0603'     | ''          | ''   | '20150615'
 '4.7UF'    | '25V'   | '10%'     | 'C0603'     | 'X6S'     | 'CH5474KE902'(!)   = ''              | ''                 | ''       | 'CH5474KE902'    |'C0603'| '(SMC0603AW)'                                                        | '4.7UF'    | '25V'         | '10%'    | 'DISCRETE' | 'CAP CHIP 4.7UF 25V(+-10%,X6S,0603)MUR'                        | 'CHIP0603'     | ''          | ''   | '20150615'
 '4.7UF'    | '25V'   | '10%'     | 'C0603'     | 'EMPTY'   | 'CH5474KE902'(!)   = ''              | ''                 | ''       | 'CH5474KE902'    |'C0603'| '(SMC0603AW)'                                                        | 'NA'       | '25V'         | '10%'    | 'IO'       | 'CAP CHIP 4.7UF 25V(+-10%,X6S,0603)MUR'                        | 'CHIP0603'     | ''          | ''   | '20150615'
 '1UF'      | '25V'   | '10%'     | 'C0603'     | 'X7R'     | 'CH5104K1903'(!)   = 'End of Design' | 'Comp-Approve'     | ''       | 'CH5104K1903'    |'C0603'| '(SMC0603AW)'                                                        | '1UF'      | '25V'         | '10%'    | 'DISCRETE' | 'CAP CHIP 1U 25V(+-10%.X7R.0603)MUR'                           | 'CHIP0603'     | ''          | ''   | '20150615'
 '1UF'      | '25V'   | '10%'     | 'C0603'     | 'EMPTY'   | 'CH5104K1903'(!)   = 'End of Design' | 'Comp-Approve'     | ''       | 'CH5104K1903'    |'C0603'| '(SMC0603AW)'                                                        | 'NA'       | '25V'         | '10%'    | 'IO'       | 'CAP CHIP 1U 25V(+-10%.X7R.0603)MUR'                           | 'CHIP0603'     | ''          | ''   | '20150615'
 '2.2UF'    | '10V'   | '10%'     | 'C0603'     | 'X7R'     | 'CH5222K1904'(!)   = ''              | ''                 | ''       | 'CH5222K1904'    |'C0603'| '(SMC0603AW)'                                                        | '2.2UF'    | '10V'         | '10%'    | 'DISCRETE' | 'CAP CHIP 2.2UF 10V(+-10%,X7R,0603)MUR'                        | 'CHIP0603'     | ''          | ''   | '20150615'
 '2.2UF'    | '10V'   | '10%'     | 'C0603'     | 'EMPTY'   | 'CH5222K1904'(!)   = ''              | ''                 | ''       | 'CH5222K1904'    |'C0603'| '(SMC0603AW)'                                                        | 'NA'       | '10V'         | '10%'    | 'IO'       | 'CAP CHIP 2.2UF 10V(+-10%,X7R,0603)MUR'                        | 'CHIP0603'     | ''          | ''   | '20150615'
 '4.7UF'    | '6.3V'  | '10%'     | 'C0603'     | 'X6S'     | 'CH5471KE903'(!)   = 'End of Design' | 'Comp-Approve'     | ''       | 'CH5471KE903'    |'C0603'| '(SMC0603AW)'                                                        | '4.7UF'    | '6.3V'        | '10%'    | 'DISCRETE' | 'CAP CHIP 4.7U 6.3V(+-10%,X6S,0603)MUR'                        | 'CHIP0603'     | ''          | ''   | '20150615'
 '4.7UF'    | '6.3V'  | '10%'     | 'C0603'     | 'EMPTY'   | 'CH5471KE903'(!)   = 'End of Design' | 'Comp-Approve'     | ''       | 'CH5471KE903'    |'C0603'| '(SMC0603AW)'                                                        | 'NA'       | '6.3V'        | '10%'    | 'IO'       | 'CAP CHIP 4.7U 6.3V(+-10%,X6S,0603)MUR'                        | 'CHIP0603'     | ''          | ''   | '20150615'
 '10UF'     | '6.3V'  | '20%'     | 'C0603'     | 'X6S'     | 'CH6101ME902'(!)   = ''              | ''                 | ''       | 'CH6101ME902'    |'C0603'| '(SMC0603AW)'                                                        | '10UF'     | '6.3V'        | '20%'    | 'DISCRETE' | 'CAP CHIP 10U 6.3V(+-20%,X6S,0603)MUR'                         | 'CHIP0603'     | ''          | ''   | '20150615'
 '10UF'     | '6.3V'  | '20%'     | 'C0603'     | 'EMPTY'   | 'CH6101ME902'(!)   = ''              | ''                 | ''       | 'CH6101ME902'    |'C0603'| '(SMC0603AW)'                                                        | 'NA'       | '6.3V'        | '20%'    | 'IO'       | 'CAP CHIP 10U 6.3V(+-20%,X6S,0603)MUR'                         | 'CHIP0603'     | ''          | ''   | '20150615'
 '10UF'     | '4V'    | '20%'     | 'C0603'     | 'X6S'     | 'CH610KME905'(!)   = 'End of Design' | 'Comp-Approve'     | ''       | 'CH610KME905'    |'C0603'| '(SMC0603AW)'                                                        | '10UF'     | '4V'          | '20%'    | 'DISCRETE' | 'CAP CHIP 10U 4V(+-20%,X6S,0603)MUR'                           | 'CHIP0603'     | ''          | ''   | '20150615'
 '10UF'     | '4V'    | '20%'     | 'C0603'     | 'EMPTY'   | 'CH610KME905'(!)   = 'End of Design' | 'Comp-Approve'     | ''       | 'CH610KME905'    |'C0603'| '(SMC0603AW)'                                                        | 'NA'       | '4V'          | '20%'    | 'IO'       | 'CAP CHIP 10U 4V(+-20%,X6S,0603)MUR'                           | 'CHIP0603'     | ''          | ''   | '20150615'
 '0.1UF'    | '25V'   | '10%'     | 'C0603'     | 'X7R'     | 'CH4104K1909'(!)   = 'End of Design' | 'Comp-Approve'     | ''       | 'CH4104K1909'    |'C0603'| '(SMC0603AW)'                                                        | '0.1UF'    | '25V'         | '10%'    | 'DISCRETE' | 'CAP CHIP 0.1UF 25V(+-10%,X7R,0603)MUR'                        | 'CHIP0603'     | ''          | ''   | '20150615'
 '0.1UF'    | '25V'   | '10%'     | 'C0603'     | 'EMPTY'   | 'CH4104K1909'(!)   = 'End of Design' | 'Comp-Approve'     | ''       | 'CH4104K1909'    |'C0603'| '(SMC0603AW)'                                                        | 'NA'       | '25V'         | '10%'    | 'IO'       | 'CAP CHIP 0.1UF 25V(+-10%,X7R,0603)MUR'                        | 'CHIP0603'     | ''          | ''   | '20150615'
 '10UF'     | '6.3V'  | '20%'     | 'C0805'     | 'X6S'     | 'CH6101MEA00'(!)   = 'End of Design' | 'Comp-Approve'     | ''       | 'CH6101MEA00'    |'C0805_H61'| '(SMC0805AW)'                                                        | '10UF'     | '6.3V'        | '20%'    | 'DISCRETE' | 'CAP CHIP 10UF 6.3V(+-20%,X6S,0805)MUR'                        | 'CHIP0805'     | ''          | ''   | '20150615'
 '10UF'     | '6.3V'  | '20%'     | 'C0805'     | 'EMPTY'   | 'CH6101MEA00'(!)   = 'End of Design' | 'Comp-Approve'     | ''       | 'CH6101MEA00'    |'C0805_H61'| '(SMC0805AW)'                                                        | 'NA'       | '6.3V'        | '20%'    | 'IO'       | 'CAP CHIP 10UF 6.3V(+-20%,X6S,0805)MUR'                        | 'CHIP0805'     | ''          | ''   | '20150615'
 '100UF'    | '4V'    | '20%'     | 'C0805'     | 'X6S'     | 'CH710KMEA01'(!)   = ''              | ''                 | ''       | 'CH710KMEA01'    |'C0805_H61'| '(SMC0805AW)'                                                        | '100UF'    | '4V'          | '20%'    | 'DISCRETE' | 'CAP CHIP 100U 4V(+-20%,X6S,0805)MUR'                          | 'CHIP0805'     | ''          | ''   | '20150615'
 '100UF'    | '4V'    | '20%'     | 'C0805'     | 'EMPTY'   | 'CH710KMEA01'(!)   = ''              | ''                 | ''       | 'CH710KMEA01'    |'C0805_H61'| '(SMC0805AW)'                                                        | 'NA'       | '4V'          | '20%'    | 'IO'       | 'CAP CHIP 100U 4V(+-20%,X6S,0805)MUR'                          | 'CHIP0805'     | ''          | ''   | '20150615'
 '22UF'     | '10V'   | '20%'     | 'C0805'     | 'X6S'     | 'CH6222MEA01'(!)   = ''              | ''                 | ''       | 'CH6222MEA01'    |'C0805_H61'| '(SMC0805AW)'                                                        | '22UF'     | '10V'         | '20%'    | 'DISCRETE' | 'CAP CHIP 22U 10V(+-20%,X6S,0805)MUR'                          | 'CHIP0805'     | ''          | ''   | '20150615'
 '22UF'     | '10V'   | '20%'     | 'C0805'     | 'EMPTY'   | 'CH6222MEA01'(!)   = ''              | ''                 | ''       | 'CH6222MEA01'    |'C0805_H61'| '(SMC0805AW)'                                                        | 'NA'       | '10V'         | '20%'    | 'IO'       | 'CAP CHIP 22U 10V(+-20%,X6S,0805)MUR'                          | 'CHIP0805'     | ''          | ''   | '20150615'
 '10UF'     | '10V'   | '10%'     | 'C0805'     | 'X7R'     | 'CH6102K1A02'(!)   = ''              | ''                 | ''       | 'CH6102K1A02'    |'C0805_H61'| '(SMC0805AW)'                                                        | '10UF'     | '10V'         | '10%'    | 'DISCRETE' | 'CAP CHIP10UF 10V(+-10%,X7R,0805)MUR'                          | 'CHIP0805'     | ''          | ''   | '20150615'
 '10UF'     | '10V'   | '10%'     | 'C0805'     | 'EMPTY'   | 'CH6102K1A02'(!)   = ''              | ''                 | ''       | 'CH6102K1A02'    |'C0805_H61'| '(SMC0805AW)'                                                        | 'NA'       | '10V'         | '10%'    | 'IO'       | 'CAP CHIP10UF 10V(+-10%,X7R,0805)MUR'                          | 'CHIP0805'     | ''          | ''   | '20150615'
 '0.1UF'    | '100V'  | '10%'     | 'C0805'     | 'X7R'     | 'CH4108K1A01'(!)   = ''              | ''                 | ''       | 'CH4108K1A01'    |'C0805_H61'| '(SMC0805AW)'                                                        | '0.1UF'    | '100V'        | '10%'    | 'DISCRETE' | 'CAP CHIP 0.1UF 100V(+-10%,X7R,0805)MUR'                       | 'CHIP0805'     | ''          | ''   | '20150615'
 '0.1UF'    | '100V'  | '10%'     | 'C0805'     | 'EMPTY'   | 'CH4108K1A01'(!)   = ''              | ''                 | ''       | 'CH4108K1A01'    |'C0805_H61'| '(SMC0805AW)'                                                        | 'NA'       | '100V'        | '10%'    | 'IO'       | 'CAP CHIP 0.1UF 100V(+-10%,X7R,0805)MUR'                       | 'CHIP0805'     | ''          | ''   | '20150615'
 '4.7UF'    | '16V'   | '10%'     | 'C0805'     | 'X7R'     | 'CH5473K1A01'(!)   = 'End of Design' | 'Comp-Approve'     | ''       | 'CH5473K1A01'    |'C0805_H61'| '(SMC0805AW)'                                                        | '4.7UF'    | '16V'         | '10%'    | 'DISCRETE' | 'CAP CHIP 4.7UF 16V(+-10%,X7R,0805)MUR'                        | 'CHIP0805'     | ''          | ''   | '20150615'
 '4.7UF'    | '16V'   | '10%'     | 'C0805'     | 'EMPTY'   | 'CH5473K1A01'(!)   = 'End of Design' | 'Comp-Approve'     | ''       | 'CH5473K1A01'    |'C0805_H61'| '(SMC0805AW)'                                                        | 'NA'       | '16V'         | '10%'    | 'IO'       | 'CAP CHIP 4.7UF 16V(+-10%,X7R,0805)MUR'                        | 'CHIP0805'     | ''          | ''   | '20150615'
 '10UF'     | '25V'   | '10%'     | 'C0805'     | 'X6S'     | 'CH6104KEA03'(!)   = ''              | ''                 | ''       | 'CH6104KEA03'    |'C0805_H61'| '(SMC0805AW)'                                                        | '10UF'     | '25V'         | '10%'    | 'DISCRETE' | 'CAP CHIP 10U 25V(+-10%,X6S,0805)MUR'                          | 'CHIP0805'     | ''          | ''   | '20150615'
 '10UF'     | '25V'   | '10%'     | 'C0805'     | 'EMPTY'   | 'CH6104KEA03'(!)   = ''              | ''                 | ''       | 'CH6104KEA03'    |'C0805_H61'| '(SMC0805AW)'                                                        | 'NA'       | '25V'         | '10%'    | 'IO'       | 'CAP CHIP 10U 25V(+-10%,X6S,0805)MUR'                          | 'CHIP0805'     | ''          | ''   | '20150615'
 '22UF'     | '6.3V'  | '20%'     | 'C0805'     | 'X6S'     | 'CH6221MEA04'(!)   = 'End of Design' | 'Comp-Approve'     | ''       | 'CH6221MEA04'    |'C0805_H61'| '(SMC0805AW)'                                                        | '22UF'     | '6.3V'        | '20%'    | 'DISCRETE' | 'CAP CHIP 22U 6.3V(+-20%,X6S,0805)MUR'                         | 'CHIP0805'     | ''          | ''   | '20150615'
 '22UF'     | '6.3V'  | '20%'     | 'C0805'     | 'EMPTY'   | 'CH6221MEA04'(!)   = 'End of Design' | 'Comp-Approve'     | ''       | 'CH6221MEA04'    |'C0805_H61'| '(SMC0805AW)'                                                        | 'NA'       | '6.3V'        | '20%'    | 'IO'       | 'CAP CHIP 22U 6.3V(+-20%,X6S,0805)MUR'                         | 'CHIP0805'     | ''          | ''   | '20150615'
 '22UF'     | '4V'    | '20%'     | 'C0805'     | 'X6S'     | 'CH622KMEA03'(!)   = ''              | ''                 | ''       | 'CH622KMEA03'    |'C0805_H61'| '(SMC0805AW)'                                                        | '22UF'     | '4V'          | '20%'    | 'DISCRETE' | 'CAP CHIP 22U 4V(+-20%,X6S,0805)MUR'                           | 'CHIP0805'     | ''          | ''   | '20150615'
 '22UF'     | '4V'    | '20%'     | 'C0805'     | 'EMPTY'   | 'CH622KMEA03'(!)   = ''              | ''                 | ''       | 'CH622KMEA03'    |'C0805_H61'| '(SMC0805AW)'                                                        | 'NA'       | '4V'          | '20%'    | 'IO'       | 'CAP CHIP 22U 4V(+-20%,X6S,0805)MUR'                           | 'CHIP0805'     | ''          | ''   | '20150615'
 '2.2UF'    | '100V'  | '10%'     | 'C1206'     | 'X7R'     | 'CH5228K1207'(!)   = ''              | ''                 | ''       | 'CH5228K1207'    |'C1206_H66'| '(SMC1206AW)'                                                        | '2.2UF'    | '100V'        | '10%'    | 'DISCRETE' | 'CAP CHIP 2.2UF 100V(+-10%,X7R,1206)MUR'                       | 'CHIP1206'     | ''          | ''   | '20150615'
 '2.2UF'    | '100V'  | '10%'     | 'C1206'     | 'EMPTY'   | 'CH5228K1207'(!)   = ''              | ''                 | ''       | 'CH5228K1207'    |'C1206_H66'| '(SMC1206AW)'                                                        | 'NA'       | '100V'        | '10%'    | 'IO'       | 'CAP CHIP 2.2UF 100V(+-10%,X7R,1206)MUR'                       | 'CHIP1206'     | ''          | ''   | '20150615'
 '10UF'     | '25V'   | '10%'     | 'C1206'     | 'X7R'     | 'CH6104K1203'(!)   = 'End of Design' | 'Comp-Approve'     | ''       | 'CH6104K1203'    |'C1206_H66'| '(SMC1206AW)'                                                        | '10UF'     | '25V'         | '10%'    | 'DISCRETE' | 'CAP CHIP 10U 25V(+-10%,X7R,1206)MUR'                          | 'CHIP1206'     | ''          | ''   | '20150615'
 '10UF'     | '25V'   | '10%'     | 'C1206'     | 'EMPTY'   | 'CH6104K1203'(!)   = 'End of Design' | 'Comp-Approve'     | ''       | 'CH6104K1203'    |'C1206_H66'| '(SMC1206AW)'                                                        | 'NA'       | '25V'         | '10%'    | 'IO'       | 'CAP CHIP 10U 25V(+-10%,X7R,1206)MUR'                          | 'CHIP1206'     | ''          | ''   | '20150615'
 '1UF'      | '100V'  | '10%'     | 'C1206'     | 'X7R'     | 'CH5108K1201'(!)   = ''              | ''                 | ''       | 'CH5108K1201'    |'C1206_H66'| '(SMC1206AW)'                                                        | '1UF'      | '100V'        | '10%'    | 'DISCRETE' | 'CAP CHIP 1U 100V(10%.1206.X7R)MUR'                            | 'CHIP1206'     | ''          | ''   | '20150615'
 '1UF'      | '100V'  | '10%'     | 'C1206'     | 'EMPTY'   | 'CH5108K1201'(!)   = ''              | ''                 | ''       | 'CH5108K1201'    |'C1206_H66'| '(SMC1206AW)'                                                        | 'NA'       | '100V'        | '10%'    | 'IO'       | 'CAP CHIP 1U 100V(10%.1206.X7R)MUR'                            | 'CHIP1206'     | ''          | ''   | '20150615'
 '10UF'     | '25V'   | '10%'     | 'C1206'     | 'X7R'     | 'CH6104K1204'(!)   = 'End of Design' | 'Comp-Approve'     | ''       | 'CH6104K1204'    |'C1206_H66'| '(SMC1206AW)'                                                        | '10UF'     | '25V'         | '10%'    | 'DISCRETE' | 'CAP CHIP 10U,25V(+-10%,X7R,1206)SAM'                          | 'CHIP1206'     | ''          | ''   | '20150616'
 '10UF'     | '25V'   | '10%'     | 'C1206'     | 'EMPTY'   | 'CH6104K1204'(!)   = 'End of Design' | 'Comp-Approve'     | ''       | 'CH6104K1204'    |'C1206_H66'| '(SMC1206AW)'                                                        | 'NA'       | '25V'         | '10%'    | 'IO'       | 'CAP CHIP 10U,25V(+-10%,X7R,1206)SAM'                          | 'CHIP1206'     | ''          | ''   | '20150616'
 '10UF'     | '6.3V'  | '10%'     | 'C0805'     | 'X6S'     | 'CH6101KEA01'(!)   = ''              | ''                 | ''       | 'CH6101KEA01'    |'C0805_H61'| '(SMC0805AW)'                                                        | '10UF'     | '6.3V'        | '10%'    | 'DISCRETE' | 'CAP CHIP 10UF,6.3V (+-10%,X6S,0805)SAM'                       | 'CHIP0805'     | ''          | ''   | '20150616'
 '10UF'     | '6.3V'  | '10%'     | 'C0805'     | 'EMPTY'   | 'CH6101KEA01'(!)   = ''              | ''                 | ''       | 'CH6101KEA01'    |'C0805_H61'| '(SMC0805AW)'                                                        | 'NA'       | '6.3V'        | '10%'    | 'IO'       | 'CAP CHIP 10UF,6.3V (+-10%,X6S,0805)SAM'                       | 'CHIP0805'     | ''          | ''   | '20150616'
 '10UF'     | '16V'   | '10%'     | 'C0805'     | 'X7R'     | 'CH6103K1A01'(!)   = ''              | ''                 | ''       | 'CH6103K1A01'    |'C0805_H61'| '(SMC0805AW)'                                                        | '10UF'     | '16V'         | '10%'    | 'DISCRETE' | 'CAP CHIP 10UF 16V(+-10%,X7R,0805)SAM'                         | 'CHIP0805'     | ''          | ''   | '20150616'
 '10UF'     | '16V'   | '10%'     | 'C0805'     | 'EMPTY'   | 'CH6103K1A01'(!)   = ''              | ''                 | ''       | 'CH6103K1A01'    |'C0805_H61'| '(SMC0805AW)'                                                        | 'NA'       | '16V'         | '10%'    | 'IO'       | 'CAP CHIP 10UF 16V(+-10%,X7R,0805)SAM'                         | 'CHIP0805'     | ''          | ''   | '20150616'
 '0.01UF'   | '50V'   | '10%'     | 'C0402'     | 'X7R'     | 'CH31006KB00'(!)   = ''              | ''                 | ''       | 'CH31006KB00'    |'C0402'| '(C0402_OCTAGONXA,C0402-0201)'                                       | '0.01UF'   | '50V'         | '10%'    | 'DISCRETE' | 'CAP CHIP 0.01U 50V(+-10%,X7R,0402)MUR'                        | 'CHIP0402'     | ''          | ''   | '20150616'
 '0.01UF'   | '50V'   | '10%'     | 'C0402'     | 'EMPTY'   | 'CH31006KB00'(!)   = ''              | ''                 | ''       | 'CH31006KB00'    |'C0402'| '(C0402_OCTAGONXA,C0402-0201)'                                       | 'NA'       | '50V'         | '10%'    | 'IO'       | 'CAP CHIP 0.01U 50V(+-10%,X7R,0402)MUR'                        | 'CHIP0402'     | ''          | ''   | '20150616'
 '0.22UF'   | '16V'   | '10%'     | 'C0402'     | 'X7R'     | 'CH4223K1B04'(!)   = 'End of Design' | 'Comp-Approve'     | ''       | 'CH4223K1B04'    |'C0402'| '(C0402-0201)'                                                       | '0.22UF'   | '16V'         | '10%'    | 'DISCRETE' | 'CAP CHIP 0.22U 16V(10%,X7R,0402)MUR'                          | 'CHIP0402'     | ''          | ''   | '20150616'
 '0.22UF'   | '16V'   | '10%'     | 'C0402'     | 'EMPTY'   | 'CH4223K1B04'(!)   = 'End of Design' | 'Comp-Approve'     | ''       | 'CH4223K1B04'    |'C0402'| '(C0402-0201)'                                                       | 'NA'       | '16V'         | '10%'    | 'IO'       | 'CAP CHIP 0.22U 16V(10%,X7R,0402)MUR'                          | 'CHIP0402'     | ''          | ''   | '20150616'
 '3300PF'   | '50V'   | '10%'     | 'C0402'     | 'X7R'     | 'CH2336K1B06'(!)   = ''              | ''                 | ''       | 'CH2336K1B06'    |'C0402'| '(C0402-0201)'                                                       | '3300PF'   | '50V'         | '10%'    | 'DISCRETE' | 'CAP CHIP 3300P 50V(+-10%,X7R,0402)MUR'                        | 'CHIP0402'     | ''          | ''   | '20150617'
 '3300PF'   | '50V'   | '10%'     | 'C0402'     | 'EMPTY'   | 'CH2336K1B06'(!)   = ''              | ''                 | ''       | 'CH2336K1B06'    |'C0402'| '(C0402-0201)'                                                       | 'NA'       | '50V'         | '10%'    | 'IO'       | 'CAP CHIP 3300P 50V(+-10%,X7R,0402)MUR'                        | 'CHIP0402'     | ''          | ''   | '20150617'
 '10PF'     | '50V'   | '2%'      | 'C0402'     | 'NPO'     | 'CH0106G0B03'(!)   = ''              | ''                 | ''       | 'CH0106G0B03'    |'C0402'| '(C0402-0201)'                                                       | '10PF'     | '50V'         | '2%'     | 'DISCRETE' | 'CAP CHIP 10P 50V(+-2%,NPO,0402)MUR'                           | 'CHIP0402'     | ''          | ''   | '20150622'
 '10PF'     | '50V'   | '2%'      | 'C0402'     | 'EMPTY'   | 'CH0106G0B03'(!)   = ''              | ''                 | ''       | 'CH0106G0B03'    |'C0402'| '(C0402-0201)'                                                       | 'NA'       | '50V'         | '2%'     | 'IO'       | 'CAP CHIP 10P 50V(+-2%,NPO,0402)MUR'                           | 'CHIP0402'     | ''          | ''   | '20150622'
 '820PF'    | '50V'   | '10%'     | 'C0402'     | 'X7R'     | 'CH1826K1B07'(!)   = ''              | ''                 | ''       | 'CH1826K1B07'    |'C0402'| '(C0402-0201)'                                                       | '820PF'    | '50V'         | '10%'    | 'DISCRETE' | 'CAP CHIP 820P 50V(+-10%,X7R,0402)MUR'                         | 'CHIP0402'     | ''          | ''   | '20150622'
 '820PF'    | '50V'   | '10%'     | 'C0402'     | 'EMPTY'   | 'CH1826K1B07'(!)   = ''              | ''                 | ''       | 'CH1826K1B07'    |'C0402'| '(C0402-0201)'                                                       | 'NA'       | '50V'         | '10%'    | 'IO'       | 'CAP CHIP 820P 50V(+-10%,X7R,0402)MUR'                         | 'CHIP0402'     | ''          | ''   | '20150622'
 '33PF'     | '50V'   | '5%'      | 'C0402'     | 'NPO'     | 'CH0336J0B11'(!)   = ''              | ''                 | ''       | 'CH0336J0B11'    |'C0402'| '(C0402-0201)'                                                       | '33PF'     | '50V'         | '5%'     | 'DISCRETE' | 'CAP CHIP 33P 50V(+-5%,NPO,0402)SAM'                           | 'CHIP0402'     | ''          | ''   | '20150622'
 '33PF'     | '50V'   | '5%'      | 'C0402'     | 'EMPTY'   | 'CH0336J0B11'(!)   = ''              | ''                 | ''       | 'CH0336J0B11'    |'C0402'| '(C0402-0201)'                                                       | 'NA'       | '50V'         | '5%'     | 'IO'       | 'CAP CHIP 33P 50V(+-5%,NPO,0402)SAM'                           | 'CHIP0402'     | ''          | ''   | '20150622'
 '0.1UF'    | '100V'  | '10%'     | 'C1206'     | 'X7R'     | 'CH4108K1205'(!)   = ''              | ''                 | ''       | 'CH4108K1205'    |'C1206_H42'| '(SMC1206AW)'                                                        | '0.1UF'    | '100V'        | '10%'    | 'DISCRETE' | 'CAP CHIP 0.1U 100V(+-10%,X7R,1206)MUR'                        | 'CHIP1206'     | ''          | ''   | '20150622'
 '0.1UF'    | '100V'  | '10%'     | 'C1206'     | 'EMPTY'   | 'CH4108K1205'(!)   = ''              | ''                 | ''       | 'CH4108K1205'    |'C1206_H42'| '(SMC1206AW)'                                                        | 'NA'       | '100V'        | '10%'    | 'IO'       | 'CAP CHIP 0.1U 100V(+-10%,X7R,1206)MUR'                        | 'CHIP1206'     | ''          | ''   | '20150622'
 '22UF'     | '4V'    | '20%'     | 'C0402'     | 'X5R'     | 'CH622KM9B03'(!)   = ''              | ''                 | ''       | 'CH622KM9B03'    |'C0402'| '(C0402-0201)'                                                       | '22UF'     | '4V'          | '20%'    | 'DISCRETE' | 'CAP CHIP 22UF 4V (+-20%, X5R,0402)MUR'                        | 'CHIP0402'     | ''          | ''   | '20150625'
 '22UF'     | '4V'    | '20%'     | 'C0402'     | 'EMPTY'   | 'CH622KM9B03'(!)   = ''              | ''                 | ''       | 'CH622KM9B03'    |'C0402'| '(C0402-0201)'                                                       | 'NA'       | '4V'          | '20%'    | 'IO'       | 'CAP CHIP 22UF 4V (+-20%, X5R,0402)MUR'                        | 'CHIP0402'     | ''          | ''   | '20150625'
 '47UF'     | '4V'    | '20%'     | '0805'      | 'X6S'     | 'CH647KMEA00'(!)   = ''              | ''                 | ''       | 'CH647KMEA00'    |'C0805_H57'| '(C0805_BHS)'                                                        | '47UF'     | '4V'          | '20%'    | 'DISCRETE' | 'CAP CHIP 47U 4V(+-20%,X6S,0805)'                              | 'CHIP0805'     | ''          | ''   | '20150706'
 '47UF'     | '4V'    | '20%'     | '0805'      | 'EMPTY'   | 'CH647KMEA00'(!)   = ''              | ''                 | ''       | 'CH647KMEA00'    |'C0805_H57'| '(C0805_BHS)'                                                        | 'NA'       | '4V'          | '20%'    | 'IO'       | 'CAP CHIP 47U 4V(+-20%,X6S,0805)'                              | 'CHIP0805'     | ''          | ''   | '20150706'
 '1UF'      | '4V'    | '20%'     | '0201'      | 'X6S'     | 'CH-10KMEE00'(!)   = 'End of Design' | 'Comp-Approve'     | ''       | 'CH-10KMEE00'    |'C0201'| '(SMC0201AW)'                                                        | '1UF'      | '4V'          | '20%'    | 'DISCRETE' | 'CAP CHIP 1U 4V(+-20%,X6S,0201)'                               | 'CHIP0201'     | ''          | ''   | '20150713'
 '1UF'      | '4V'    | '20%'     | '0201'      | 'EMPTY'   | 'CH-10KMEE00'(!)   = 'End of Design' | 'Comp-Approve'     | ''       | 'CH-10KMEE00'    |'C0201'| '(SMC0201AW)'                                                        | 'NA'       | '4V'          | '20%'    | 'IO'       | 'CAP CHIP 1U 4V(+-20%,X6S,0201)'                               | 'CHIP0201'     | ''          | ''   | '20150713'
 '10UF'     | '10V'   | '20%'     | 'C0603'     | 'X6S'     | 'CH6102ME902'(!)   = ''              | ''                 | ''       | 'CH6102ME902'    |'C0603'| '(SMC0603AW)'                                                        | '10UF'     | '10V'         | '20%'    | 'DISCRETE' | 'CAP CHIP 10U,10V(+-20%,X6S,0603)TAY'                          | 'CHIP0603'     | ''          | ''   | '20150716'
 '10UF'     | '10V'   | '20%'     | 'C0603'     | 'EMPTY'   | 'CH6102ME902'(!)   = ''              | ''                 | ''       | 'CH6102ME902'    |'C0603'| '(SMC0603AW)'                                                        | 'NA'       | '10V'         | '20%'    | 'IO'       | 'CAP CHIP 10U,10V(+-20%,X6S,0603)TAY'                          | 'CHIP0603'     | ''          | ''   | '20150716'
 '0.047UF'  | '100V'  | '10%'     | 'C0805'     | 'X7R'     | 'CH3478K1A00'(!)   = ''              | ''                 | ''       | 'CH3478K1A00'    |'C0805_H57'| '(SMC0805AW)'                                                        | '0.047UF'  | '100V'        | '10%'    | 'DISCRETE' | 'CAP CHIP 0.047UF 100V(+-10%,X7R,0805)'                        | 'CHIP0805'     | ''          | ''   | '20150803'
 '0.047UF'  | '100V'  | '10%'     | 'C0805'     | 'EMPTY'   | 'CH3478K1A00'(!)   = ''              | ''                 | ''       | 'CH3478K1A00'    |'C0805_H57'| '(SMC0805AW)'                                                        | 'NA'       | '100V'        | '10%'    | 'IO'       | 'CAP CHIP 0.047UF 100V(+-10%,X7R,0805)'                        | 'CHIP0805'     | ''          | ''   | '20150803'
 '0.033UF'  | '16V'   | '10%'     | 'C0402'     | 'X7R'     | 'CH3333K1B06'(!)   = ''              | ''                 | ''       | 'CH3333K1B06'    |'C0402'| '(C0402-0201)'                                                       | '0.033UF'  | '16V'         | '10%'    | 'DISCRETE' | 'CAP CHIP 0.033U 16V(+-10%.X7R.0402)MUR'                       | 'CHIP0402'     | ''          | ''   | '20150825'
 '0.033UF'  | '16V'   | '10%'     | 'C0402'     | 'EMPTY'   | 'CH3333K1B06'(!)   = ''              | ''                 | ''       | 'CH3333K1B06'    |'C0402'| '(C0402-0201)'                                                       | 'NA'       | '16V'         | '10%'    | 'IO'       | 'CAP CHIP 0.033U 16V(+-10%.X7R.0402)MUR'                       | 'CHIP0402'     | ''          | ''   | '20150825'
 '330PF'    | '50V'   | '10%'     | 'C0402'     | 'X7R'     | 'CH1336K1B06'(!)   = ''              | ''                 | ''       | 'CH1336K1B06'    |'C0402'| '(C0402-0201)'                                                       | '330PF'    | '50V'         | '10%'    | 'DISCRETE' | 'CAP CHIP 330P 50V(+-10%,X7R,0402)MUR'                         | 'CHIP0402'     | ''          | ''   | '20150902'
 '330PF'    | '50V'   | '10%'     | 'C0402'     | 'EMPTY'   | 'CH1336K1B06'(!)   = ''              | ''                 | ''       | 'CH1336K1B06'    |'C0402'| '(C0402-0201)'                                                       | 'NA'       | '50V'         | '10%'    | 'IO'       | 'CAP CHIP 330P 50V(+-10%,X7R,0402)MUR'                         | 'CHIP0402'     | ''          | ''   | '20150902'
 '0.1UF'    | '16V'   | '10%'     | 'C0402'     | 'X7R'     | 'CH4103K1B08'(!)   = ''              | ''                 | ''       | 'CH4103K1B08'    |'C0402'| '(C0402_OCTAGONXA,C0402_OCTAGON,C0402-0201)'                         | '0.1UF'    | '16V'         | '10%'    | 'DISCRETE' | 'CHIP0402'                                                     | 'CHIP0402'     | ''          | ''   | '20150911'
 '0.1UF'    | '16V'   | '10%'     | 'C0402'     | 'EMPTY'   | 'CH4103K1B08'(!)   = ''              | ''                 | ''       | 'CH4103K1B08'    |'C0402'| '(C0402_OCTAGONXA,C0402_OCTAGON,C0402-0201)'                         | 'NA'       | '16V'         | '10%'    | 'IO'       | 'CHIP0402'                                                     | 'CHIP0402'     | ''          | ''   | '20150911'
 '1UF'      | '6.3V'  | '10%'     | 'C0402'     | 'X7R'     | 'CH5101K1B05'(!)   = ''              | ''                 | ''       | 'CH5101K1B05'    |'C0402'| '(C0402_OCTAGONXA,C0402_OCTAGON,C0402-0201,C0402_OCTAGONXA_BOUND22)' | '1UF'      | '6.3V'        | '10%'    | 'DISCRETE' | 'CAP CHIP 1U,6.3V(+-10%,X7R,0402)MUR'                          | 'CHIP0402'     | ''          | ''   | '20150911'
 '1UF'      | '6.3V'  | '10%'     | 'C0402'     | 'EMPTY'   | 'CH5101K1B05'(!)   = ''              | ''                 | ''       | 'CH5101K1B05'    |'C0402'| '(C0402_OCTAGONXA,C0402_OCTAGON,C0402-0201,C0402_OCTAGONXA_BOUND22)' | 'NA'       | '6.3V'        | '10%'    | 'IO'       | 'CAP CHIP 1U,6.3V(+-10%,X7R,0402)MUR'                          | 'CHIP0402'     | ''          | ''   | '20150911'
 '10UF'     | '4V'    | '20%'     | 'C0603'     | 'X6S'     | 'CH610KME902'(!)   = 'End of Design' | 'Comp-Approve'     | ''       | 'CH610KME902'    |'C0603'| '(SMC0603AW)'                                                        | '10UF'     | '4V'          | '20%'    | 'DISCRETE' | 'CAP CHIP 10U 4V(+-20%,X6S,0603)'                              | 'CHIP0603'     | ''          | ''   | '20151006'
 '10UF'     | '4V'    | '20%'     | 'C0603'     | 'EMPTY'   | 'CH610KME902'(!)   = 'End of Design' | 'Comp-Approve'     | ''       | 'CH610KME902'    |'C0603'| '(SMC0603AW)'                                                        | 'NA'       | '4V'          | '20%'    | 'IO'       | 'CAP CHIP 10U 4V(+-20%,X6S,0603)'                              | 'CHIP0603'     | ''          | ''   | '20151006'
 '0.01UF'   | '16V'   | '10%'     | 'C0201'     | 'X7R'     | 'CH3103K1E01'(!)   = ''              | ''                 | ''       | 'CH3103K1E01'    |'C0201'| '(SMC0201AW)'                                                        | '0.01UF'   | '16V'         | '10%'    | 'DISCRETE' | 'CAP CHIP 0.01U 16V(+-10%.X7R.0201)TAY'                        | 'CHIP0201'     | ''          | ''   | '20151022'
 '0.01UF'   | '16V'   | '10%'     | 'C0201'     | 'EMPTY'   | 'CH3103K1E01'(!)   = ''              | ''                 | ''       | 'CH3103K1E01'    |'C0201'| '(SMC0201AW)'                                                        | 'NA'       | '16V'         | '10%'    | 'IO'       | 'CAP CHIP 0.01U 16V(+-10%.X7R.0201)TAY'                        | 'CHIP0201'     | ''          | ''   | '20151022'
 '100UF'    | '6.3V'  | '20%'     | 'C1206'     | 'X6T'     | 'CH7101MH201'(!)   = ''              | ''                 | ''       | 'CH7101MH201'    |'C1206_H66'| '(SMC1206AW)'                                                        | '100UF'    | '6.3V'        | '20%'    | 'DISCRETE' | 'CAP CHIP 100U 6.3V(+-20%,X6T,1206)MUR'                        | 'CHIP1206'     | ''          | ''   | '20151022'
 '100UF'    | '6.3V'  | '20%'     | 'C1206'     | 'EMPTY'   | 'CH7101MH201'(!)   = ''              | ''                 | ''       | 'CH7101MH201'    |'C1206_H66'| '(SMC1206AW)'                                                        | 'NA'       | '6.3V'        | '20%'    | 'IO'       | 'CAP CHIP 100U 6.3V(+-20%,X6T,1206)MUR'                        | 'CHIP1206'     | ''          | ''   | '20151022'
 '2.2UF'    | '10V'   | '10%'     | 'C0402'     | 'X6S'     | 'CH5222KEB02'(!)   = ''              | ''                 | ''       | 'CH5222KEB02'    |'C0402_H28'| '(C0402-0201_H28,C0402_OCTAGONXA)'                                   | '2.2UF'    | '10V'         | '10%'    | 'DISCRETE' | 'CAP CHIP 2.2UF 10V(+-10%,X6S,0402)MUR'                        | 'CHIP0402'     | ''          | ''   | '20151022'
 '2.2UF'    | '10V'   | '10%'     | 'C0402'     | 'EMPTY'   | 'CH5222KEB02'(!)   = ''              | ''                 | ''       | 'CH5222KEB02'    |'C0402_H28'| '(C0402-0201_H28,C0402_OCTAGONXA)'                                   | 'NA'       | '10V'         | '10%'    | 'IO'       | 'CAP CHIP 2.2UF 10V(+-10%,X6S,0402)MUR'                        | 'CHIP0402'     | ''          | ''   | '20151022'
 '2.2UF'    | '100V'  | '10%'     | 'C1206'     | 'X7R'     | 'CH5228K1208'(!)   = ''              | ''                 | ''       | 'CH5228K1208'    |'C1206_H66'| '(SMC1206AW)'                                                        | '2.2UF'    | '100V'        | '10%'    | 'DISCRETE' | 'CAP CHIP 2.2UF 100V(+-10%,X7R,1206)SAM'                       | 'CHIP1206'     | ''          | ''   | '20151022'
 '2.2UF'    | '100V'  | '10%'     | 'C1206'     | 'EMPTY'   | 'CH5228K1208'(!)   = ''              | ''                 | ''       | 'CH5228K1208'    |'C1206_H66'| '(SMC1206AW)'                                                        | 'NA'       | '100V'        | '10%'    | 'IO'       | 'CAP CHIP 2.2UF 100V(+-10%,X7R,1206)SAM'                       | 'CHIP1206'     | ''          | ''   | '20151022'
 '47UF'     | '4V'    | '20%'     | 'C0805'     | 'X6S'     | 'CH647KMEA06'(!)   = ''              | ''                 | ''       | 'CH647KMEA06'    |'C0805_H57'| '(SMC0805AW)'                                                        | '47UF'     | '4V'          | '20%'    | 'DISCRETE' | 'CAP CHIP 47U 4V(+-20%.X6S.0805)SAM'                           | 'CHIP0805'     | ''          | ''   | '20151022'
 '47UF'     | '4V'    | '20%'     | 'C0805'     | 'EMPTY'   | 'CH647KMEA06'(!)   = ''              | ''                 | ''       | 'CH647KMEA06'    |'C0805_H57'| '(SMC0805AW)'                                                        | 'NA'       | '4V'          | '20%'    | 'IO'       | 'CAP CHIP 47U 4V(+-20%.X6S.0805)SAM'                           | 'CHIP0805'     | ''          | ''   | '20151022'
 '12PF'     | '50V'   | '2%'      | 'C0402'     | 'C0G'     | 'CH0126G0B07'(!)   = ''              | ''                 | ''       | 'CH0126G0B07'    |'C0402'| '(C0402-0201)'                                                       | '12P'      | '50V'         | '2%'     | 'DISCRETE' | 'CAP CHIP 12P 50V(+-2%,C0G,0402)SAM'                           | 'CHIP0402'     | ''          | ''   | '20151022'
 '12PF'     | '50V'   | '2%'      | 'C0402'     | 'EMPTY'   | 'CH0126G0B07'(!)   = ''              | ''                 | ''       | 'CH0126G0B07'    |'C0402'| '(C0402-0201)'                                                       | 'NA'       | '50V'         | '2%'     | 'IO'       | 'CAP CHIP 12P 50V(+-2%,C0G,0402)SAM'                           | 'CHIP0402'     | ''          | ''   | '20151022'
 '1UF'      | '25V'   | '10%'     | 'C0402'     | 'X6S'     | 'CH5104KEB04'(!)   = ''              | ''                 | ''       | 'CH5104KEB04'    |'C0402'| '(C0402-0201)'                                                       | '1UF'      | '25V'         | '10%'    | 'DISCRETE' | 'CAP CHIP 1UF 25V(+-10%,X6S,0402)SAM'                          | 'CHIP0402'     | ''          | ''   | '20151022'
 '1UF'      | '25V'   | '10%'     | 'C0402'     | 'EMPTY'   | 'CH5104KEB04'(!)   = ''              | ''                 | ''       | 'CH5104KEB04'    |'C0402'| '(C0402-0201)'                                                       | 'NA'       | '25V'         | '10%'    | 'IO'       | 'CAP CHIP 1UF 25V(+-10%,X6S,0402)SAM'                          | 'CHIP0402'     | ''          | ''   | '20151022'
 '12PF'     | '50V'   | '2%'      | 'C0402'     | 'C0G'     | 'CH0126G0B06'(!)   = ''              | ''                 | ''       | 'CH0126G0B06'    |'C0402'| '(C0402-0201)'                                                       | '12PF'     | '50V'         | '2%'     | 'DISCRETE' | 'CAP CHIP 12P 50V(+-2%,C0G,0402)MUR'                           | 'CHIP0402'     | ''          | ''   | '20151029'
 '12PF'     | '50V'   | '2%'      | 'C0402'     | 'EMPTY'   | 'CH0126G0B06'(!)   = ''              | ''                 | ''       | 'CH0126G0B06'    |'C0402'| '(C0402-0201)'                                                       | 'NA'       | '50V'         | '2%'     | 'IO'       | 'CAP CHIP 12P 50V(+-2%,C0G,0402)MUR'                           | 'CHIP0402'     | ''          | ''   | '20151029'
 '0.01UF'   | '1KV'   | '10%'     | 'C1206'     | 'X7R'     | 'CH310FK1202'(!)   = ''              | ''                 | ''       | 'CH310FK1202'    |'C1206_H76'| '(SMC1206AW)'                                                        | '0.01UF'   | '1KV'         | '10%'    | 'DISCRETE' | 'CAP CHIP 0.01U 1KV(+-10%,X7R,1206)MUR'                        | 'CHIP1206'     | ''          | ''   | '20151029'
 '0.01UF'   | '1KV'   | '10%'     | 'C1206'     | 'EMPTY'   | 'CH310FK1202'(!)   = ''              | ''                 | ''       | 'CH310FK1202'    |'C1206_H76'| '(SMC1206AW)'                                                        | 'NA'       | '1KV'         | '10%'    | 'IO'       | 'CAP CHIP 0.01U 1KV(+-10%,X7R,1206)MUR'                        | 'CHIP1206'     | ''          | ''   | '20151029'
 '22UF'     | '25V'   | '20%'     | 'C1206'     | 'X7S'     | 'CH6224M6200'(!)   = 'End of Design' | 'Comp-Approve'     | ''       | 'CH6224M6200'    |'C1206_H76'| '(SMC1206AW)'                                                        | '22UF'     | '25V'         | '20%'    | 'DISCRETE' | 'CAP CHIP 22UF 25V(+-20%,X7S,1206)'                            | 'CHIP1206'     | ''          | ''   | '20151110'
 '22UF'     | '25V'   | '20%'     | 'C1206'     | 'EMPTY'   | 'CH6224M6200'(!)   = 'End of Design' | 'Comp-Approve'     | ''       | 'CH6224M6200'    |'C1206_H76'| '(SMC1206AW)'                                                        | 'NA'       | '25V'         | '20%'    | 'IO'       | 'CAP CHIP 22UF 25V(+-20%,X7S,1206)'                            | 'CHIP1206'     | ''          | ''   | '20151110'
 '1000PF'   | '50V'   | '10%'     | 'C0402'     | 'X7R'     | 'CH2106K1B20'(!)   = ''              | ''                 | ''       | 'CH2106K1B20'    |'C0402'| '(C0402-0201)'                                                       | '1000PF'   | '50V'         | '10%'    | 'DISCRETE' | 'CAP CHIP 1000P 50V(+-10%,X7R,0402)MUR'                        | 'CHIP0402'     | ''          | ''   | '20151112'
 '1000PF'   | '50V'   | '10%'     | 'C0402'     | 'EMPTY'   | 'CH2106K1B20'(!)   = ''              | ''                 | ''       | 'CH2106K1B20'    |'C0402'| '(C0402-0201)'                                                       | 'NA'       | '50V'         | '10%'    | 'IO'       | 'CAP CHIP 1000P 50V(+-10%,X7R,0402)MUR'                        | 'CHIP0402'     | ''          | ''   | '20151112'
 '47UF'     | '6.3V'  | '20%'     | 'C1206'     | 'X6S'     | 'CH6471ME201'(!)   = ''              | ''                 | ''       | 'CH6471ME201'    |'C1206_H76'| '(SMC1206AW)'                                                        | '47UF'     | '6.3V'        | '20%'    | 'DISCRETE' | 'CAP CHIP 47U 6.3V(+-20%,X6S,1206)MUR'                         | 'CHIP1206'     | ''          | ''   | '20151112'
 '47UF'     | '6.3V'  | '20%'     | 'C1206'     | 'EMPTY'   | 'CH6471ME201'(!)   = ''              | ''                 | ''       | 'CH6471ME201'    |'C1206_H76'| '(SMC1206AW)'                                                        | 'NA'       | '6.3V'        | '20%'    | 'IO'       | 'CAP CHIP 47U 6.3V(+-20%,X6S,1206)MUR'                         | 'CHIP1206'     | ''          | ''   | '20151112'
 '47UF'     | '6.3V'  | '20%'     | 'C1206'     | 'X6S'     | 'CH6471ME200'(!)   = 'End of Design' | 'Comp-Approve'     | ''       | 'CH6471ME200'    |'C1206_H76'| '(SMC1206AW)'                                                        | '47UF'     | '6.3V'        | '20%'    | 'DISCRETE' | 'CAP CHIP 47U 6.3V(+-20%,X6S,1206)'                            | 'CHIP1206'     | ''          | ''   | '20151112'
 '47UF'     | '6.3V'  | '20%'     | 'C1206'     | 'EMPTY'   | 'CH6471ME200'(!)   = 'End of Design' | 'Comp-Approve'     | ''       | 'CH6471ME200'    |'C1206_H76'| '(SMC1206AW)'                                                        | 'NA'       | '6.3V'        | '20%'    | 'IO'       | 'CAP CHIP 47U 6.3V(+-20%,X6S,1206)'                            | 'CHIP1206'     | ''          | ''   | '20151112'
 '0.1UF'    | '50V'   | '10%'     | 'C0603'     | 'X7R'     | 'CH4106K1910'(!)   = 'End of Design' | 'Comp-Approve'     | ''       | 'CH4106K1910'    |'C0603'| '(SMC0603AW)'                                                        | '0.1UF'    | '50V'         | '10%'    | 'DISCRETE' | 'CAP CHIP 0.1U 50V(+-10%,X7R,0603)MUR'                         | 'CHIP0603'     | ''          | ''   | '20151120'
 '0.1UF'    | '50V'   | '10%'     | 'C0603'     | 'EMPTY'   | 'CH4106K1910'(!)   = 'End of Design' | 'Comp-Approve'     | ''       | 'CH4106K1910'    |'C0603'| '(SMC0603AW)'                                                        | 'NA'       | '50V'         | '10%'    | 'IO'       | 'CAP CHIP 0.1U 50V(+-10%,X7R,0603)MUR'                         | 'CHIP0603'     | ''          | ''   | '20151120'
 '270PF'    | '25V'   | '5%'      | 'C0402'     | 'NPO'     | 'CH1274J0B01'(!)   = ''              | ''                 | ''       | 'CH1274J0B01'    |'C0402'| '(C0402-0201)'                                                       | '270PF'    | '25V'         | '5%'     | 'DISCRETE' | 'CAP CHIP 270P 25V(+-5%,NPO,0402)MUR'                          | 'CHIP0402'     | ''          | ''   | '20151201'
 '270PF'    | '25V'   | '5%'      | 'C0402'     | 'EMPTY'   | 'CH1274J0B01'(!)   = ''              | ''                 | ''       | 'CH1274J0B01'    |'C0402'| '(C0402-0201)'                                                       | 'NA'       | '25V'         | '5%'     | 'IO'       | 'CAP CHIP 270P 25V(+-5%,NPO,0402)MUR'                          | 'CHIP0402'     | ''          | ''   | '20151201'
 '1UF'      | '25V'   | '10%'     | 'C0805'     | 'X7R'     | 'CH5104K1A06'(!)   = ''              | ''                 | ''       | 'CH5104K1A06'    |'C0805_H57'| '(SMC0805AW)'                                                        | '1UF'      | '25V'         | '10%'    | 'DISCRETE' | 'CAP CHIP 1U 25V(+-10%.X7R.0805)MUR'                           | 'CHIP0805'     | ''          | ''   | '20151209'
 '1UF'      | '25V'   | '10%'     | 'C0805'     | 'EMPTY'   | 'CH5104K1A06'(!)   = ''              | ''                 | ''       | 'CH5104K1A06'    |'C0805_H57'| '(SMC0805AW)'                                                        | 'NA'       | '25V'         | '10%'    | 'IO'       | 'CAP CHIP 1U 25V(+-10%.X7R.0805)MUR'                           | 'CHIP0805'     | ''          | ''   | '20151209'
 '10PF'     | '3KV'   | '5%'      | 'C1808'     | 'NPO'     | 'CH010GJ0I08'(!)   = ''              | ''                 | ''       | 'CH010GJ0I08'    |'C1808_H71'| '(SMC1808AW)'                                                        | '10PF'     | '3KV'         | '5%'     | 'DISCRETE' | 'CAP CHIP 10P 3KV(+-5%,NPO,1808)EP'                            | 'CHIP1808'     | ''          | ''   | '20151211'
 '10PF'     | '3KV'   | '5%'      | 'C1808'     | 'EMPTY'   | 'CH010GJ0I08'(!)   = ''              | ''                 | ''       | 'CH010GJ0I08'    |'C1808_H71'| '(SMC1808AW)'                                                        | 'NA'       | '3KV'         | '5%'     | 'IO'       | 'CAP CHIP 10P 3KV(+-5%,NPO,1808)EP'                            | 'CHIP1808'     | ''          | ''   | '20151211'
 '4.7UF'    | '6.3V'  | '20%'     | '0402'      | 'X6S'     | 'CH5471MEB01'(!)   = ''              | ''                 | ''       | 'CH5471MEB01'    |'C0402'| '(C0402_OCTAGON,C0402_OCTAGONXA,C0402-0201)'                         | '4.7UF'    | '6.3V'        | '20%'    | 'DISCRETE' | 'CAP CHIP 4.7UF 6.3V(+-20%,X6S,0402)'                          | 'CHIP0402'     | ''          | ''   | '20151211'
 '4.7UF'    | '6.3V'  | '20%'     | '0402'      | 'EMPTY'   | 'CH5471MEB01'(!)   = ''              | ''                 | ''       | 'CH5471MEB01'    |'C0402'| '(C0402_OCTAGON,C0402_OCTAGONXA,C0402-0201)'                         | 'NA'       | '6.3V'        | '20%'    | 'IO'       | 'CAP CHIP 4.7UF 6.3V(+-20%,X6S,0402)'                          | 'CHIP0402'     | ''          | ''   | '20151211'
 '0.039UF'  | '50V'   | '10%'     | 'C0603'     | 'X7R'     | 'CH3396K1901'(!)   = 'End of Design' | 'Comp-Approve'     | ''       | 'CH3396K1901'    |'C0603'| '(SMC0603AW)'                                                        | '0.039UF'  | '50V'         | '10%'    | 'DISCRETE' | 'CAP CHIP 0.039U 50V(+-10%,X7R,0603)MUR'                       | 'CHIP0603'     | ''          | ''   | '20151229'
 '0.039UF'  | '50V'   | '10%'     | 'C0603'     | 'EMPTY'   | 'CH3396K1901'(!)   = 'End of Design' | 'Comp-Approve'     | ''       | 'CH3396K1901'    |'C0603'| '(SMC0603AW)'                                                        | 'NA'       | '50V'         | '10%'    | 'IO'       | 'CAP CHIP 0.039U 50V(+-10%,X7R,0603)MUR'                       | 'CHIP0603'     | ''          | ''   | '20151229'
 '0.1UF'    | '10V'   | '10%'     | 'C0402'     | 'X7R'     | 'CH3104K1B15'(!)   = ''              | 'End of Life'      | ''       | 'CH3104K1B15'    |'C0402_EOL'| '(C0402-0201)'                                                       | '0.1UF'    | '10V'         | '10%'    | 'DISCRETE' | 'CAP CHIP 0.1U 10V(+-10%,X7R,0402)AEC'                         | 'CHIP0402'     | ''          | ''   | '20151231'
 '0.1UF'    | '10V'   | '10%'     | 'C0402'     | 'EMPTY'   | 'CH3104K1B15'(!)   = ''              | 'End of Life'      | ''       | 'CH3104K1B15'    |'C0402_EOL'| '(C0402-0201)'                                                       | 'NA'       | '10V'         | '10%'    | 'IO'       | 'CAP CHIP 0.1U 10V(+-10%,X7R,0402)AEC'                         | 'CHIP0402'     | ''          | ''   | '20151231'
 '0.1UF'    | '16V'   | '10%'     | 'C0402'     | 'X7R'     | 'CH4103K1B21'(!)   = ''              | ''                 | ''       | 'CH4103K1B21'    |'C0402'| '(C0402-0201)'                                                       | '0.1UF'    | '16V'         | '10%'    | 'DISCRETE' | 'CAP CHIP 0.1U 16V(+-10%,X7R,0402)AEC'                         | 'CHIP0402'     | ''          | ''   | '20151231'
 '0.1UF'    | '16V'   | '10%'     | 'C0402'     | 'EMPTY'   | 'CH4103K1B21'(!)   = ''              | ''                 | ''       | 'CH4103K1B21'    |'C0402'| '(C0402-0201)'                                                       | 'NA'       | '16V'         | '10%'    | 'IO'       | 'CAP CHIP 0.1U 16V(+-10%,X7R,0402)AEC'                         | 'CHIP0402'     | ''          | ''   | '20151231'
 '0.1UF'    | '25V'   | '10%'     | 'C0603'     | 'X7R'     | 'CH4104K1914'(!)   = ''              | ''                 | ''       | 'CH4104K1914'    |'C0603'| '(SMC0603AW)'                                                        | '0.1UF'    | '25V'         | '10%'    | 'DISCRETE' | 'CAP CHIP 0.1U 25V(+-10%,X7R,0603)AEC'                         | 'CHIP0603'     | ''          | ''   | '20151231'
 '0.1UF'    | '25V'   | '10%'     | 'C0603'     | 'EMPTY'   | 'CH4104K1914'(!)   = ''              | ''                 | ''       | 'CH4104K1914'    |'C0603'| '(SMC0603AW)'                                                        | 'NA'       | '25V'         | '10%'    | 'IO'       | 'CAP CHIP 0.1U 25V(+-10%,X7R,0603)AEC'                         | 'CHIP0603'     | ''          | ''   | '20151231'
 '1000PF'   | '50V'   | '5%'      | 'C0402'     | 'X7R'     | 'CH2106J1B06'(!)   = ''              | ''                 | ''       | 'CH2106J1B06'    |'C0402'| '(C0402-0201)'                                                       | '1000PF'   | '50V'         | '5%'     | 'DISCRETE' | 'CAP CHIP 1000P 50V(+-5%,X7R,0402)AEC'                         | 'CHIP0402'     | ''          | ''   | '20151231'
 '1000PF'   | '50V'   | '5%'      | 'C0402'     | 'EMPTY'   | 'CH2106J1B06'(!)   = ''              | ''                 | ''       | 'CH2106J1B06'    |'C0402'| '(C0402-0201)'                                                       | 'NA'       | '50V'         | '5%'     | 'IO'       | 'CAP CHIP 1000P 50V(+-5%,X7R,0402)AEC'                         | 'CHIP0402'     | ''          | ''   | '20151231'
 '100PF'    | '50V'   | '5%'      | 'C0402'     | 'NPO'     | 'CH1106J0B18'(!)   = ''              | ''                 | ''       | 'CH1106J0B18'    |'C0402'| '(C0402-0201)'                                                       | '100PF'    | '50V'         | '5%'     | 'DISCRETE' | 'CAP CHIP 100P 50V(+-5%,NPO,0402)AEC'                          | 'CHIP0402'     | ''          | ''   | '20151231'
 '100PF'    | '50V'   | '5%'      | 'C0402'     | 'EMPTY'   | 'CH1106J0B18'(!)   = ''              | ''                 | ''       | 'CH1106J0B18'    |'C0402'| '(C0402-0201)'                                                       | 'NA'       | '50V'         | '5%'     | 'IO'       | 'CAP CHIP 100P 50V(+-5%,NPO,0402)AEC'                          | 'CHIP0402'     | ''          | ''   | '20151231'
 '15PF'     | '50V'   | '5%'      | 'C0402'     | 'NPO'     | 'CH0156J0B11'(!)   = ''              | ''                 | ''       | 'CH0156J0B11'    |'C0402'| '(C0402-0201)'                                                       | '15PF'     | '50V'         | '5%'     | 'DISCRETE' | 'CAP CHIP 15P 50V(+-5%,NPO,0402)AEC'                           | 'CHIP0402'     | ''          | ''   | '20151231'
 '15PF'     | '50V'   | '5%'      | 'C0402'     | 'EMPTY'   | 'CH0156J0B11'(!)   = ''              | ''                 | ''       | 'CH0156J0B11'    |'C0402'| '(C0402-0201)'                                                       | 'NA'       | '50V'         | '5%'     | 'IO'       | 'CAP CHIP 15P 50V(+-5%,NPO,0402)AEC'                           | 'CHIP0402'     | ''          | ''   | '20151231'
 '18PF'     | '50V'   | '5%'      | 'C0402'     | 'NPO'     | 'CH0186J0B07'(!)   = ''              | ''                 | ''       | 'CH0186J0B07'    |'C0402'| '(C0402-0201)'                                                       | '18PF'     | '50V'         | '5%'     | 'DISCRETE' | 'CAP CHIP 18P 50V(+-5%,NPO,0402)AEC'                           | 'CHIP0402'     | ''          | ''   | '20151231'
 '18PF'     | '50V'   | '5%'      | 'C0402'     | 'EMPTY'   | 'CH0186J0B07'(!)   = ''              | ''                 | ''       | 'CH0186J0B07'    |'C0402'| '(C0402-0201)'                                                       | 'NA'       | '50V'         | '5%'     | 'IO'       | 'CAP CHIP 18P 50V(+-5%,NPO,0402)AEC'                           | 'CHIP0402'     | ''          | ''   | '20151231'
 '2200PF'   | '50V'   | '10%'     | 'C0402'     | 'X7R'     | 'CH2226K1B13'(!)   = ''              | ''                 | ''       | 'CH2226K1B13'    |'C0402'| '(C0402-0201)'                                                       | '2200PF'   | '50V'         | '10%'    | 'DISCRETE' | 'CAP CHIP 2200P 50V(+-10%,X7R,0402)AEC'                        | 'CHIP0402'     | ''          | ''   | '20151231'
 '2200PF'   | '50V'   | '10%'     | 'C0402'     | 'EMPTY'   | 'CH2226K1B13'(!)   = ''              | ''                 | ''       | 'CH2226K1B13'    |'C0402'| '(C0402-0201)'                                                       | 'NA'       | '50V'         | '10%'    | 'IO'       | 'CAP CHIP 2200P 50V(+-10%,X7R,0402)AEC'                        | 'CHIP0402'     | ''          | ''   | '20151231'
 '22PF'     | '50V'   | '5%'      | 'C0402'     | 'NPO'     | 'CH0226J0B20'(!)   = ''              | ''                 | ''       | 'CH0226J0B20'    |'C0402'| '(C0402-0201)'                                                       | '22PF'     | '50V'         | '5%'     | 'DISCRETE' | 'CAP CHIP 22P 50V(+-5%,NPO,0402)AEC'                           | 'CHIP0402'     | ''          | ''   | '20151231'
 '22PF'     | '50V'   | '5%'      | 'C0402'     | 'EMPTY'   | 'CH0226J0B20'(!)   = ''              | ''                 | ''       | 'CH0226J0B20'    |'C0402'| '(C0402-0201)'                                                       | 'NA'       | '50V'         | '5%'     | 'IO'       | 'CAP CHIP 22P 50V(+-5%,NPO,0402)AEC'                           | 'CHIP0402'     | ''          | ''   | '20151231'
 '3300PF'   | '50V'   | '10%'     | 'C0402'     | 'X7R'     | 'CH2336K1B09'(!)   = ''              | ''                 | ''       | 'CH2336K1B09'    |'C0402'| '(C0402-0201)'                                                       | '3300PF'   | '50V'         | '10%'    | 'DISCRETE' | 'CAP CHIP 3300P 50V(+-10%,X7R,0402)AEC'                        | 'CHIP0402'     | ''          | ''   | '20151231'
 '3300PF'   | '50V'   | '10%'     | 'C0402'     | 'EMPTY'   | 'CH2336K1B09'(!)   = ''              | ''                 | ''       | 'CH2336K1B09'    |'C0402'| '(C0402-0201)'                                                       | 'NA'       | '50V'         | '10%'    | 'IO'       | 'CAP CHIP 3300P 50V(+-10%,X7R,0402)AEC'                        | 'CHIP0402'     | ''          | ''   | '20151231'
 '0.01UF'   | '16V'   | '10%'     | 'C0402'     | 'X7R'     | 'CH3103K1B22'(!)   = ''              | ''                 | ''       | 'CH3103K1B22'    |'C0402'| '(C0402-0201)'                                                       | '0.01UF'   | '16V'         | '10%'    | 'DISCRETE' | 'CAP CHIP 0.01U 16V(+-10%,X7R,0402)AEC'                        | 'CHIP0402'     | ''          | ''   | '20151231'
 '0.01UF'   | '16V'   | '10%'     | 'C0402'     | 'EMPTY'   | 'CH3103K1B22'(!)   = ''              | ''                 | ''       | 'CH3103K1B22'    |'C0402'| '(C0402-0201)'                                                       | 'NA'       | '16V'         | '10%'    | 'IO'       | 'CAP CHIP 0.01U 16V(+-10%,X7R,0402)AEC'                        | 'CHIP0402'     | ''          | ''   | '20151231'
 '0.01UF'   | '25V'   | '10%'     | 'C0402'     | 'X7R'     | 'CH3104K1B14'(!)   = ''              | ''                 | ''       | 'CH3104K1B14'    |'C0402'| '(C0402-0201)'                                                       | '0.01UF'   | '25V'         | '10%'    | 'DISCRETE' | 'CAP CHIP 0.01U 25V(+-10%,X7R,0402)AEC'                        | 'CHIP0402'     | ''          | ''   | '20151231'
 '0.01UF'   | '25V'   | '10%'     | 'C0402'     | 'EMPTY'   | 'CH3104K1B14'(!)   = ''              | ''                 | ''       | 'CH3104K1B14'    |'C0402'| '(C0402-0201)'                                                       | 'NA'       | '25V'         | '10%'    | 'IO'       | 'CAP CHIP 0.01U 25V(+-10%,X7R,0402)AEC'                        | 'CHIP0402'     | ''          | ''   | '20151231'
 '0.1UF'    | '25V'   | '10%'     | 'C0402'     | 'X7R'     | 'CH4104K1B05'(!)   = ''              | ''                 | ''       | 'CH4104K1B05'    |'C0402'| '(C0402-0201)'                                                       | '0.1UF'    | '25V'         | '10%'    | 'DISCRETE' | 'CAP CHIP 0.1U 25V(+-10%,X7R,0402)AEC'                         | 'CHIP0402'     | ''          | ''   | '20160104'
 '0.1UF'    | '25V'   | '10%'     | 'C0402'     | 'EMPTY'   | 'CH4104K1B05'(!)   = ''              | ''                 | ''       | 'CH4104K1B05'    |'C0402'| '(C0402-0201)'                                                       | 'NA'       | '25V'         | '10%'    | 'IO'       | 'CAP CHIP 0.1U 25V(+-10%,X7R,0402)AEC'                         | 'CHIP0402'     | ''          | ''   | '20160104'
 '0.47UF'   | '10V'   | '10%'     | 'C0402'     | 'X7S'     | 'CH4472K6B00'(!)   = ''              | ''                 | ''       | 'CH4472K6B00'    |'C0402'| '(C0402-0201)'                                                       | '0.47UF'   | '10V'         | '10%'    | 'DISCRETE' | 'CAP CHIP 0.47U 10V(+10%,X7S,0402)AEC'                         | 'CHIP0402'     | ''          | ''   | '20160104'
 '0.47UF'   | '10V'   | '10%'     | 'C0402'     | 'EMPTY'   | 'CH4472K6B00'(!)   = ''              | ''                 | ''       | 'CH4472K6B00'    |'C0402'| '(C0402-0201)'                                                       | 'NA'       | '10V'         | '10%'    | 'IO'       | 'CAP CHIP 0.47U 10V(+10%,X7S,0402)AEC'                         | 'CHIP0402'     | ''          | ''   | '20160104'
 '1000PF'   | '50V'   | '10%'     | 'C0402'     | 'X7R'     | 'CH2106K1B24'(!)   = ''              | ''                 | ''       | 'CH2106K1B24'    |'C0402'| '(C0402-0201)'                                                       | '1000PF'   | '50V'         | '10%'    | 'DISCRETE' | 'CAP CHIP 1000P 50V(+10%,X7R,0402)AEC'                         | 'CHIP0402'     | ''          | ''   | '20160104'
 '1000PF'   | '50V'   | '10%'     | 'C0402'     | 'EMPTY'   | 'CH2106K1B24'(!)   = ''              | ''                 | ''       | 'CH2106K1B24'    |'C0402'| '(C0402-0201)'                                                       | 'NA'       | '50V'         | '10%'    | 'IO'       | 'CAP CHIP 1000P 50V(+10%,X7R,0402)AEC'                         | 'CHIP0402'     | ''          | ''   | '20160104'
 '10UF'     | '10V'   | '20%'     | 'C0603'     | 'X6S'     | 'CH6102ME903'(!)   = ''              | ''                 | ''       | 'CH6102ME903'    |'C0603'| '(SMC0603AW)'                                                        | '10UF'     | '10V'         | '20%'    | 'DISCRETE' | 'CAP CHIP 10U 10V(+-20%,X6S,0603)AEC'                          | 'CHIP0603'     | ''          | ''   | '20160104'
 '10UF'     | '10V'   | '20%'     | 'C0603'     | 'EMPTY'   | 'CH6102ME903'(!)   = ''              | ''                 | ''       | 'CH6102ME903'    |'C0603'| '(SMC0603AW)'                                                        | 'NA'       | '10V'         | '20%'    | 'IO'       | 'CAP CHIP 10U 10V(+-20%,X6S,0603)AEC'                          | 'CHIP0603'     | ''          | ''   | '20160104'
 '10UF'     | '4V'    | '20%'     | 'C0603'     | 'X6S'     | 'CH610KME907'(!)   = ''              | ''                 | ''       | 'CH610KME907'    |'C0603'| '(SMC0603AW)'                                                        | '10UF'     | '4V'          | '20%'    | 'DISCRETE' | 'CAP CHIP 10U 4V(+-20%,X6S,0603)AEC'                           | 'CHIP0603'     | ''          | ''   | '20160104'
 '10UF'     | '4V'    | '20%'     | 'C0603'     | 'EMPTY'   | 'CH610KME907'(!)   = ''              | ''                 | ''       | 'CH610KME907'    |'C0603'| '(SMC0603AW)'                                                        | 'NA'       | '4V'          | '20%'    | 'IO'       | 'CAP CHIP 10U 4V(+-20%,X6S,0603)AEC'                           | 'CHIP0603'     | ''          | ''   | '20160104'
 '1UF'      | '16V'   | '10%'     | 'C0603'     | 'X7R'     | 'CH5103K1912'(!)   = ''              | ''                 | ''       | 'CH5103K1912'    |'C0603'| '(SMC0603AW)'                                                        | '1UF'      | '16V'         | '10%'    | 'DISCRETE' | 'CAP CHIP 1U 16V(+-10%,X7R,0603)AEC'                           | 'CHIP0603'     | ''          | ''   | '20160104'
 '1UF'      | '16V'   | '10%'     | 'C0603'     | 'EMPTY'   | 'CH5103K1912'(!)   = ''              | ''                 | ''       | 'CH5103K1912'    |'C0603'| '(SMC0603AW)'                                                        | 'NA'       | '16V'         | '10%'    | 'IO'       | 'CAP CHIP 1U 16V(+-10%,X7R,0603)AEC'                           | 'CHIP0603'     | ''          | ''   | '20160104'
 '1UF'      | '16V'   | '10%'     | 'C0402'     | 'X6S'     | 'CH5103KEB05'(!)   = ''              | ''                 | ''       | 'CH5103KEB05'    |'C0402'| '(C0402-0201)'                                                       | '1UF'      | '16V'         | '10%'    | 'DISCRETE' | 'CAP CHIP 1U 16V(10%,X6S,0402)AEC'                             | 'CHIP0402'     | ''          | ''   | '20160104'
 '1UF'      | '16V'   | '10%'     | 'C0402'     | 'EMPTY'   | 'CH5103KEB05'(!)   = ''              | ''                 | ''       | 'CH5103KEB05'    |'C0402'| '(C0402-0201)'                                                       | 'NA'       | '16V'         | '10%'    | 'IO'       | 'CAP CHIP 1U 16V(10%,X6S,0402)AEC'                             | 'CHIP0402'     | ''          | ''   | '20160104'
 '1UF'      | '25V'   | '10%'     | 'C0402'     | 'X6S'     | 'CH5104KEB05'(!)   = ''              | ''                 | ''       | 'CH5104KEB05'    |'C0402'| '(C0402-0201)'                                                       | '1UF'      | '25V'         | '10%'    | 'DISCRETE' | 'CAP CHIP 1U 25V(+-10%,X6S,0402)AEC'                           | 'CHIP0402'     | ''          | ''   | '20160104'
 '1UF'      | '25V'   | '10%'     | 'C0402'     | 'EMPTY'   | 'CH5104KEB05'(!)   = ''              | ''                 | ''       | 'CH5104KEB05'    |'C0402'| '(C0402-0201)'                                                       | 'NA'       | '25V'         | '10%'    | 'IO'       | 'CAP CHIP 1U 25V(+-10%,X6S,0402)AEC'                           | 'CHIP0402'     | ''          | ''   | '20160104'
 '1UF'      | '6.3V'  | '10%'     | 'C0402'     | 'X7R'     | 'CH5101K1B08'(!)   = ''              | ''                 | ''       | 'CH5101K1B08'    |'C0402'| '(C0402-0201)'                                                       | '1UF'      | '6.3V'        | '10%'    | 'DISCRETE' | 'CAP CHIP 1U 6.3V(+-10%,X7R,0402)AEC'                          | 'CHIP0402'     | ''          | ''   | '20160104'
 '1UF'      | '6.3V'  | '10%'     | 'C0402'     | 'EMPTY'   | 'CH5101K1B08'(!)   = ''              | ''                 | ''       | 'CH5101K1B08'    |'C0402'| '(C0402-0201)'                                                       | 'NA'       | '6.3V'        | '10%'    | 'IO'       | 'CAP CHIP 1U 6.3V(+-10%,X7R,0402)AEC'                          | 'CHIP0402'     | ''          | ''   | '20160104'
 '2.2UF'    | '10V'   | '10%'     | 'C0402'     | 'X6S'     | 'CH5222KEB03'(!)   = ''              | ''                 | ''       | 'CH5222KEB03'    |'C0402'| '(C0402-0201)'                                                       | '2.2UF'    | '10V'         | '10%'    | 'DISCRETE' | 'CAP CHIP 2.2U 10V(+-10%,X6S,0402)AEC'                         | 'CHIP0402'     | ''          | ''   | '20160104'
 '2.2UF'    | '10V'   | '10%'     | 'C0402'     | 'EMPTY'   | 'CH5222KEB03'(!)   = ''              | ''                 | ''       | 'CH5222KEB03'    |'C0402'| '(C0402-0201)'                                                       | 'NA'       | '10V'         | '10%'    | 'IO'       | 'CAP CHIP 2.2U 10V(+-10%,X6S,0402)AEC'                         | 'CHIP0402'     | ''          | ''   | '20160104'
 '10UF'     | '16V'   | '10%'     | 'C0805'     | 'X7S'     | 'CH6103K6A00'(!)   = ''              | ''                 | ''       | 'CH6103K6A00'    |'C0805_H57'| '(SMC0805AW)'                                                        | '10UF'     | '16V'         | '10%'    | 'DISCRETE' | 'CAP CHIP 10U 16V(+-10%,X7S,0805)AEC'                          | 'CHIP0805'     | ''          | ''   | '20160106'
 '10UF'     | '16V'   | '10%'     | 'C0805'     | 'EMPTY'   | 'CH6103K6A00'(!)   = ''              | ''                 | ''       | 'CH6103K6A00'    |'C0805_H57'| '(SMC0805AW)'                                                        | 'NA'       | '16V'         | '10%'    | 'IO'       | 'CAP CHIP 10U 16V(+-10%,X7S,0805)AEC'                          | 'CHIP0805'     | ''          | ''   | '20160106'
 '10UF'     | '6.3V'  | '10%'     | 'C0805'     | 'X7R'     | 'CH6101K1A01'(!)   = ''              | ''                 | ''       | 'CH6101K1A01'    |'C0805_H57'| '(SMC0805AW)'                                                        | '10UF'     | '6.3V'        | '10%'    | 'DISCRETE' | 'CAP CHIP 10U 6.3V(+-10%,X7R,0805)AEC'                         | 'CHIP0805'     | ''          | ''   | '20160106'
 '10UF'     | '6.3V'  | '10%'     | 'C0805'     | 'EMPTY'   | 'CH6101K1A01'(!)   = ''              | ''                 | ''       | 'CH6101K1A01'    |'C0805_H57'| '(SMC0805AW)'                                                        | 'NA'       | '6.3V'        | '10%'    | 'IO'       | 'CAP CHIP 10U 6.3V(+-10%,X7R,0805)AEC'                         | 'CHIP0805'     | ''          | ''   | '20160106'
 '2.2UF'    | '10V'   | '10%'     | 'C0805'     | 'X7R'     | 'CH5222K1A01'(!)   = 'End of Design' | 'Comp-Approve'     | ''       | 'CH5222K1A01'    |'C0805_H57'| '(SMC0805AW)'                                                        | '2.2UF'    | '10V'         | '10%'    | 'DISCRETE' | 'CAP CHIP 2.2U 10V(+-10%,X7R,0805)AEC'                         | 'CHIP0805'     | ''          | ''   | '20160106'
 '2.2UF'    | '10V'   | '10%'     | 'C0805'     | 'EMPTY'   | 'CH5222K1A01'(!)   = 'End of Design' | 'Comp-Approve'     | ''       | 'CH5222K1A01'    |'C0805_H57'| '(SMC0805AW)'                                                        | 'NA'       | '10V'         | '10%'    | 'IO'       | 'CAP CHIP 2.2U 10V(+-10%,X7R,0805)AEC'                         | 'CHIP0805'     | ''          | ''   | '20160106'
 '22UF'     | '10V'   | '20%'     | 'C0805'     | 'X6S'     | 'CH6222MEA03'(!)   = ''              | ''                 | ''       | 'CH6222MEA03'    |'C0805_H57'| '(SMC0805AW)'                                                        | '22UF'     | '10V'         | '20%'    | 'DISCRETE' | 'CAP CHIP 22U 10V(+-20%,X6S,0805)AEC'                          | 'CHIP0805'     | ''          | ''   | '20160106'
 '22UF'     | '10V'   | '20%'     | 'C0805'     | 'EMPTY'   | 'CH6222MEA03'(!)   = ''              | ''                 | ''       | 'CH6222MEA03'    |'C0805_H57'| '(SMC0805AW)'                                                        | 'NA'       | '10V'         | '20%'    | 'IO'       | 'CAP CHIP 22U 10V(+-20%,X6S,0805)AEC'                          | 'CHIP0805'     | ''          | ''   | '20160106'
 '4.7UF'    | '16V'   | '10%'     | 'C0805'     | 'X7R'     | 'CH5473K1A03'(!)   = 'End of Design' | 'Comp-Approve'     | ''       | 'CH5473K1A03'    |'C0805_H57'| '(SMC0805AW)'                                                        | '4.7UF'    | '16V'         | '10%'    | 'DISCRETE' | 'CAP CHIP 4.7UF 16V(+-10%,X7R,0805)AEC'                        | 'CHIP0805'     | ''          | ''   | '20160106'
 '4.7UF'    | '16V'   | '10%'     | 'C0805'     | 'EMPTY'   | 'CH5473K1A03'(!)   = 'End of Design' | 'Comp-Approve'     | ''       | 'CH5473K1A03'    |'C0805_H57'| '(SMC0805AW)'                                                        | 'NA'       | '16V'         | '10%'    | 'IO'       | 'CAP CHIP 4.7UF 16V(+-10%,X7R,0805)AEC'                        | 'CHIP0805'     | ''          | ''   | '20160106'
 '47UF'     | '4V'    | '20%'     | 'C0805'     | 'X6S'     | 'CH647KMEA07'(!)   = ''              | ''                 | ''       | 'CH647KMEA07'    |'C0805_H57'| '(SMC0805AW)'                                                        | '47UF'     | '4V'          | '20%'    | 'DISCRETE' | 'CAP CHIP 47U 4V(+-20%,X6S,0805)AEC'                           | 'CHIP0805'     | ''          | ''   | '20160106'
 '47UF'     | '4V'    | '20%'     | 'C0805'     | 'EMPTY'   | 'CH647KMEA07'(!)   = ''              | ''                 | ''       | 'CH647KMEA07'    |'C0805_H57'| '(SMC0805AW)'                                                        | 'NA'       | '4V'          | '20%'    | 'IO'       | 'CAP CHIP 47U 4V(+-20%,X6S,0805)AEC'                           | 'CHIP0805'     | ''          | ''   | '20160106'
 '22UF'     | '6.3V'  | '20%'     | 'C0805'     | 'X7T'     | 'CH6221MJA00'(!)   = ''              | ''                 | ''       | 'CH6221MJA00'    |'C0805_H57'| '(SMC0805AW)'                                                        | '22UF'     | '6.3V'        | '20%'    | 'DISCRETE' | 'CAP CHIP 22U 6.3V(+-20%,X7T,0805)AEC'                         | 'CHIP0805'     | ''          | ''   | '20160106'
 '22UF'     | '6.3V'  | '20%'     | 'C0805'     | 'EMPTY'   | 'CH6221MJA00'(!)   = ''              | ''                 | ''       | 'CH6221MJA00'    |'C0805_H57'| '(SMC0805AW)'                                                        | 'NA'       | '6.3V'        | '20%'    | 'IO'       | 'CAP CHIP 22U 6.3V(+-20%,X7T,0805)AEC'                         | 'CHIP0805'     | ''          | ''   | '20160106'
 '4.7UF'    | '6.3V'  | '10%'     | 'C0603'     | 'X6S'     | 'CH5471KE905'(!)   = ''              | ''                 | ''       | 'CH5471KE905'    |'C0603'| '(SMC0603AW)'                                                        | '4.7UF'    | '6.3V'        | '10%'    | 'DISCRETE' | 'CAP CHIP 4.7U 6.3V(+-10%,X6S,0603)AEC'                        | 'CHIP0603'     | ''          | ''   | '20160106'
 '4.7UF'    | '6.3V'  | '10%'     | 'C0603'     | 'EMPTY'   | 'CH5471KE905'(!)   = ''              | ''                 | ''       | 'CH5471KE905'    |'C0603'| '(SMC0603AW)'                                                        | 'NA'       | '6.3V'        | '10%'    | 'IO'       | 'CAP CHIP 4.7U 6.3V(+-10%,X6S,0603)AEC'                        | 'CHIP0603'     | ''          | ''   | '20160106'
 '470PF'    | '50V'   | '10%'     | 'C0402'     | 'X7R'     | 'CH1476K1B13'(!)   = ''              | ''                 | ''       | 'CH1476K1B13'    |'C0402'| '(C0402-0201)'                                                       | '470PF'    | '50V'         | '10%'    | 'DISCRETE' | 'CAP CHIP 470P 50V(+10%,X7R,0402)AEC'                          | 'CHIP0402'     | ''          | ''   | '20160106'
 '470PF'    | '50V'   | '10%'     | 'C0402'     | 'EMPTY'   | 'CH1476K1B13'(!)   = ''              | ''                 | ''       | 'CH1476K1B13'    |'C0402'| '(C0402-0201)'                                                       | 'NA'       | '50V'         | '10%'    | 'IO'       | 'CAP CHIP 470P 50V(+10%,X7R,0402)AEC'                          | 'CHIP0402'     | ''          | ''   | '20160106'
 '47PF'     | '50V'   | '5%'      | 'C0402'     | 'C0G'     | 'CH0476J0B13'(!)   = ''              | ''                 | ''       | 'CH0476J0B13'    |'C0402'| '(C0402-0201)'                                                       | '47PF'     | '50V'         | '5%'     | 'DISCRETE' | 'CAP CHIP 47P 50V(+5%,C0G,0402)AEC'                            | 'CHIP0402'     | ''          | ''   | '20160106'
 '47PF'     | '50V'   | '5%'      | 'C0402'     | 'EMPTY'   | 'CH0476J0B13'(!)   = ''              | ''                 | ''       | 'CH0476J0B13'    |'C0402'| '(C0402-0201)'                                                       | 'NA'       | '50V'         | '5%'     | 'IO'       | 'CAP CHIP 47P 50V(+5%,C0G,0402)AEC'                            | 'CHIP0402'     | ''          | ''   | '20160106'
 '10UF'     | '6.3V'  | '20%'     | 'C0402'     | 'X6S'     | 'CH6101MEB03'(!)   = ''              | ''                 | ''       | 'CH6101MEB03'    |'C0402'| '(C0402_OCTAGONXA,C0402-0201)'                                       | '10UF'     | '6.3V'        | '20%'    | 'DISCRETE' | 'CAP CHIP 10UF 6.3V(+-20%,X6S,0402)MUR'                        | 'CHIP0402'     | ''          | ''   | '20160111'
 '10UF'     | '6.3V'  | '20%'     | 'C0402'     | 'EMPTY'   | 'CH6101MEB03'(!)   = ''              | ''                 | ''       | 'CH6101MEB03'    |'C0402'| '(C0402_OCTAGONXA,C0402-0201)'                                       | 'NA'       | '6.3V'        | '20%'    | 'IO'       | 'CAP CHIP 10UF 6.3V(+-20%,X6S,0402)MUR'                        | 'CHIP0402'     | ''          | ''   | '20160111'
 '47UF'     | '6.3V'  | '20%'     | 'C1206'     | 'X6S'     | 'CH6471ME203'(!)   = ''              | ''                 | ''       | 'CH6471ME203'    |'C1206_H76'| '(SMC1206AW)'                                                        | '47UF'     | '6.3V'        | '20%'    | 'DISCRETE' | 'CAP CHIP 47U 6.3V(+-20%,X6S,1206)AEC'                         | 'CHIP1206'     | ''          | ''   | '20160111'
 '47UF'     | '6.3V'  | '20%'     | 'C1206'     | 'EMPTY'   | 'CH6471ME203'(!)   = ''              | ''                 | ''       | 'CH6471ME203'    |'C1206_H76'| '(SMC1206AW)'                                                        | 'NA'       | '6.3V'        | '20%'    | 'IO'       | 'CAP CHIP 47U 6.3V(+-20%,X6S,1206)AEC'                         | 'CHIP1206'     | ''          | ''   | '20160111'
 '22UF'     | '25V'   | '10%'     | 'C1206'     | 'X5R'     | 'CH6224K9203'(!)   = ''              | ''                 | ''       | 'CH6224K9203'    |'C1206_H76'| '(SMC1206AW)'                                                        | '22UF'     | '25V'         | '10%'    | 'DISCRETE' | 'CAP CHIP 22U 25V(+-10%,X5R,1206)AEC'                          | 'CHIP1206'     | ''          | ''   | '20160111'
 '22UF'     | '25V'   | '10%'     | 'C1206'     | 'EMPTY'   | 'CH6224K9203'(!)   = ''              | ''                 | ''       | 'CH6224K9203'    |'C1206_H76'| '(SMC1206AW)'                                                        | 'NA'       | '25V'         | '10%'    | 'IO'       | 'CAP CHIP 22U 25V(+-10%,X5R,1206)AEC'                          | 'CHIP1206'     | ''          | ''   | '20160111'
 '10UF'     | '25V'   | '10%'     | 'C1206'     | 'X7S'     | 'CH6104K6200'(!)   = ''              | ''                 | ''       | 'CH6104K6200'    |'C1206_H76'| '(SMC1206AW)'                                                        | '10UF'     | '25V'         | '10%'    | 'DISCRETE' | 'CAP CHIP 10U 25V(+-10%,X7S,1206)AEC'                          | 'CHIP1206'     | ''          | ''   | '20160111'
 '10UF'     | '25V'   | '10%'     | 'C1206'     | 'EMPTY'   | 'CH6104K6200'(!)   = ''              | ''                 | ''       | 'CH6104K6200'    |'C1206_H76'| '(SMC1206AW)'                                                        | 'NA'       | '25V'         | '10%'    | 'IO'       | 'CAP CHIP 10U 25V(+-10%,X7S,1206)AEC'                          | 'CHIP1206'     | ''          | ''   | '20160111'
 '10UF'     | '16V'   | '10%'     | 'C1206'     | 'X7R'     | 'CH6103K1202'(!)   = ''              | ''                 | ''       | 'CH6103K1202'    |'C1206_H76'| '(SMC1206AW)'                                                        | '10UF'     | '16V'         | '10%'    | 'DISCRETE' | 'CAP CHIP 10U 16V(+-10%,X7R,1206)AEC'                          | 'CHIP1206'     | ''          | ''   | '20160111'
 '10UF'     | '16V'   | '10%'     | 'C1206'     | 'EMPTY'   | 'CH6103K1202'(!)   = ''              | ''                 | ''       | 'CH6103K1202'    |'C1206_H76'| '(SMC1206AW)'                                                        | 'NA'       | '16V'         | '10%'    | 'IO'       | 'CAP CHIP 10U 16V(+-10%,X7R,1206)AEC'                          | 'CHIP1206'     | ''          | ''   | '20160111'
 '0.01UF'   | '50V'   | '5%'      | 'C0603'     | 'X7R'     | 'CH3106J1900'(!)   = 'End of Design' | 'Comp-Approve'     | ''       | 'CH3106J1900'    |'C0603'| '(SMC0603AW)'                                                        | '0.01UF'   | '50V'         | '10%'    | 'DISCRETE' | 'CAP CHIP 0.01U 50V(+-5%,X7R,0603)MUR'                         | 'CHIP0603'     | ''          | ''   | '20161113'
 '0.01UF'   | '50V'   | '5%'      | 'C0603'     | 'EMPTY'   | 'CH3106J1900'(!)   = 'End of Design' | 'Comp-Approve'     | ''       | 'CH3106J1900'    |'C0603'| '(SMC0603AW)'                                                        | 'NA'       | '50V'         | '10%'    | 'IO'       | 'CAP CHIP 0.01U 50V(+-5%,X7R,0603)MUR'                         | 'CHIP0603'     | ''          | ''   | '20161113'
 '0.1UF'    | '25V'   | '10%'     | '0402'      | 'X7R'     | 'CH4104K1B00'(!)   = ''              | ''                 | ''       | 'CH4104K1B00'    |'C0402'| '(C0402_OCTAGONXA,C0402-0201)'                                       | '0.1UF'    | '25V'         | '10%'    | 'DISCRETE' | 'CAP CHIP 0.1U 25V(+-10%,X7R,0402)'                            | 'CHIP0402'     | ''          | ''   | '20160113'
 '0.1UF'    | '25V'   | '10%'     | '0402'      | 'EMPTY'   | 'CH4104K1B00'(!)   = ''              | ''                 | ''       | 'CH4104K1B00'    |'C0402'| '(C0402_OCTAGONXA,C0402-0201)'                                       | 'NA'       | '25V'         | '10%'    | 'IO'       | 'CAP CHIP 0.1U 25V(+-10%,X7R,0402)'                            | 'CHIP0402'     | ''          | ''   | '20160113'
 '0.033UF'  | '50V'   | '10%'     | 'C0603'     | 'X7R'     | 'CH3336K1905'(!)   = 'End of Design' | 'Comp-Approve'     | ''       | 'CH3336K1905'    |'C0603'| '(SMC0603AW)'                                                        | '0.033UF'  | '50V'         | '10%'    | 'DISCRETE' | 'CAP CHIP 0.033U 50V(+-10%,X7R,0603)MUR'                       | 'CHIP0603'     | ''          | ''   | '20160114'
 '0.033UF'  | '50V'   | '10%'     | 'C0603'     | 'EMPTY'   | 'CH3336K1905'(!)   = 'End of Design' | 'Comp-Approve'     | ''       | 'CH3336K1905'    |'C0603'| '(SMC0603AW)'                                                        | 'NA'       | '50V'         | '10%'    | 'IO'       | 'CAP CHIP 0.033U 50V(+-10%,X7R,0603)MUR'                       | 'CHIP0603'     | ''          | ''   | '20160114'
 '8200PF'   | '25V'   | '10%'     | 'C0402'     | 'X7R'     | 'CH2824K1B04'(!)   = ''              | ''                 | ''       | 'CH2824K1B04'    |'C0402'| '(C0402-0201)'                                                       | '8200PF'   | '25V'         | '10%'    | 'DISCRETE' | 'CAP CHIP 8200P 25V (+-10%.X7R.0402)MUR'                       | 'CHIP0402'     | ''          | ''   | '20160115'
 '8200PF'   | '25V'   | '10%'     | 'C0402'     | 'EMPTY'   | 'CH2824K1B04'(!)   = ''              | ''                 | ''       | 'CH2824K1B04'    |'C0402'| '(C0402-0201)'                                                       | 'NA'       | '25V'         | '10%'    | 'IO'       | 'CAP CHIP 8200P 25V (+-10%.X7R.0402)MUR'                       | 'CHIP0402'     | ''          | ''   | '20160115'
 '22UF'     | '25V'   | '20%'     | 'C1206'     | 'X7S'     | 'CH6224M6201'(!)   = ''              | ''                 | ''       | 'CH6224M6201'    |'C1206_H76'| '(SMC1206AW)'                                                        | '22UF'     | '25V'         | '20%'    | 'DISCRETE' | 'CAP CHIP 22UF 25V(+-20%,X7S,1206)MUR'                         | 'CHIP1206'     | ''          | ''   | '20160115'
 '22UF'     | '25V'   | '20%'     | 'C1206'     | 'EMPTY'   | 'CH6224M6201'(!)   = ''              | ''                 | ''       | 'CH6224M6201'    |'C1206_H76'| '(SMC1206AW)'                                                        | 'NA'       | '25V'         | '20%'    | 'IO'       | 'CAP CHIP 22UF 25V(+-20%,X7S,1206)MUR'                         | 'CHIP1206'     | ''          | ''   | '20160115'
 '6800PF'   | '50V'   | '10%'     | 'C0402'     | 'X7R'     | 'CH2686K1B03'(!)   = ''              | ''                 | ''       | 'CH2686K1B03'    |'C0402'| '(C0402-0201)'                                                       | '6800PF'   | '50V'         | '10%'    | 'DISCRETE' | 'CAP CHIP 6800P 50V(+-10%,X7R,0402)MUR'                        | 'CHIP0402'     | ''          | ''   | '20160118'
 '6800PF'   | '50V'   | '10%'     | 'C0402'     | 'EMPTY'   | 'CH2686K1B03'(!)   = ''              | ''                 | ''       | 'CH2686K1B03'    |'C0402'| '(C0402-0201)'                                                       | 'NA'       | '50V'         | '10%'    | 'IO'       | 'CAP CHIP 6800P 50V(+-10%,X7R,0402)MUR'                        | 'CHIP0402'     | ''          | ''   | '20160118'
 '10UF'     | '10V'   | '20%'     | 'C0402'     | 'X5R'     | 'CH6102M9B00'(!)   = ''              | ''                 | ''       | 'CH6102M9B00'    |'C0402'| '(C0402-0201)'                                                       | '10UF'     | '10V'         | '20%'    | 'DISCRETE' | 'CAP CHIP 10U 10V (+-20%, X5R, 0402)'                          | 'CHIP0402'     | ''          | ''   | '20160118'
 '10UF'     | '10V'   | '20%'     | 'C0402'     | 'EMPTY'   | 'CH6102M9B00'(!)   = ''              | ''                 | ''       | 'CH6102M9B00'    |'C0402'| '(C0402-0201)'                                                       | 'NA'       | '10V'         | '20%'    | 'IO'       | 'CAP CHIP 10U 10V (+-20%, X5R, 0402)'                          | 'CHIP0402'     | ''          | ''   | '20160118'
 '22UF'     | '16V'   | '20%'     | 'C0805'     | 'X6S'     | 'CH6223MEA00'(!)   = ''              | ''                 | ''       | 'CH6223MEA00'    |'C0805_H57'| '(SMC0805AW)'                                                        | '22UF'     | '16V'         | '20%'    | 'DISCRETE' | 'CAP CHIP 22U 16V(+-20%,X6S,0805)'                             | 'CHIP0805'     | ''          | ''   | '2016019' 
 '22UF'     | '16V'   | '20%'     | 'C0805'     | 'EMPTY'   | 'CH6223MEA00'(!)   = ''              | ''                 | ''       | 'CH6223MEA00'    |'C0805_H57'| '(SMC0805AW)'                                                        | 'NA'       | '16V'         | '20%'    | 'IO'       | 'CAP CHIP 22U 16V(+-20%,X6S,0805)'                             | 'CHIP0805'     | ''          | ''   | '2016019' 
 '47NF'     | '100V'  | '10%'     | 'C1206'     | 'X7R'     | 'CH3478K1200'(!)   = ''              | ''                 | ''       | 'CH3478K1200'    |'C1206_H56'| '(SMC1206AW)'                                                        | '47NF'     | '100V'        | '10%'    | 'DISCRETE' | 'CAP CHIP 47N 100V (+-10%,X7R,1206)MUR'                        | 'CHIP1206'     | ''          | ''   | '20160219'
 '47NF'     | '100V'  | '10%'     | 'C1206'     | 'EMPTY'   | 'CH3478K1200'(!)   = ''              | ''                 | ''       | 'CH3478K1200'    |'C1206_H56'| '(SMC1206AW)'                                                        | 'NA'       | '100V'        | '10%'    | 'IO'       | 'CAP CHIP 47N 100V (+-10%,X7R,1206)MUR'                        | 'CHIP1206'     | ''          | ''   | '20160219'
 '22UF'     | '10V'   | '20%'     | 'C0805'     | 'X5R'     | 'CH6222M9A02'(!)   = 'End of Design' | 'Comp-Approve'     | ''       | 'CH6222M9A02'    |'C0805_H61'| '(SMC0805AW)'                                                        | '22UF'     | '10V'         | '20%'    | 'DISCRETE' | 'CAP CHIP 22U 10V(+-20%,X5R,0805)'                             | 'CHIP0805'     | ''          | ''   | '20160226'
 '22UF'     | '10V'   | '20%'     | 'C0805'     | 'EMPTY'   | 'CH6222M9A02'(!)   = 'End of Design' | 'Comp-Approve'     | ''       | 'CH6222M9A02'    |'C0805_H61'| '(SMC0805AW)'                                                        | 'NA'       | '10V'         | '20%'    | 'IO'       | 'CAP CHIP 22U 10V(+-20%,X5R,0805)'                             | 'CHIP0805'     | ''          | ''   | '20160226'
 '33000PF'  | '50V'   | '5%'      | 'C0805'     | 'U2J'     | 'CH3336JFA00'(!)   = ''              | ''                 | ''       | 'CH3336JFA00'    |'C0805_H43'| '(SMC0805AW)'                                                        | '33000PF'  | '50V'         | '5%'     | 'DISCRETE' | 'CAP CHIP 33000P 50V(+-5%,U2J,0805)'                           | 'CHIP0805'     | ''          | ''   | '20160310'
 '33000PF'  | '50V'   | '5%'      | 'C0805'     | 'EMPTY'   | 'CH3336JFA00'(!)   = ''              | ''                 | ''       | 'CH3336JFA00'    |'C0805_H43'| '(SMC0805AW)'                                                        | 'NA'       | '50V'         | '5%'     | 'IO'       | 'CAP CHIP 33000P 50V(+-5%,U2J,0805)'                           | 'CHIP0805'     | ''          | ''   | '20160310'
 '39000PF'  | '50V'   | '5%'      | 'C0805'     | 'U2J'     | 'CH3396JFA00'(!)   = ''              | ''                 | ''       | 'CH3396JFA00'    |'C0805_H57'| '(SMC0805AW)'                                                        | '39000PF'  | '50V'         | '5%'     | 'DISCRETE' | 'CAP CHIP 39000P 50V(+-5%,U2J,0805)'                           | 'CHIP0805'     | ''          | ''   | '20160310'
 '39000PF'  | '50V'   | '5%'      | 'C0805'     | 'EMPTY'   | 'CH3396JFA00'(!)   = ''              | ''                 | ''       | 'CH3396JFA00'    |'C0805_H57'| '(SMC0805AW)'                                                        | 'NA'       | '50V'         | '5%'     | 'IO'       | 'CAP CHIP 39000P 50V(+-5%,U2J,0805)'                           | 'CHIP0805'     | ''          | ''   | '20160310'
 '220PF'    | '50V'   | '5%'      | 'C0402'     | 'C0G'     | 'CH12206JB00'(!)   = ''              | ''                 | ''       | 'CH12206JB00'    |'C0402'| '(C0402-0201)'                                                       | '220PF'    | '50V'         | '5%'     | 'DISCRETE' | 'CAP CHIP 220P 50V(+-5%.COG.0402)'                             | 'CHIP0402'     | ''          | ''   | '20160314'
 '220PF'    | '50V'   | '5%'      | 'C0402'     | 'EMPTY'   | 'CH12206JB00'(!)   = ''              | ''                 | ''       | 'CH12206JB00'    |'C0402'| '(C0402-0201)'                                                       | 'NA'       | '50V'         | '5%'     | 'IO'       | 'CAP CHIP 220P 50V(+-5%.COG.0402)'                             | 'CHIP0402'     | ''          | ''   | '20160314'
 '560PF'    | '50V'   | '5%'      | 'C0402'     | 'C0G'     | 'CH1566J0B00'(!)   = ''              | ''                 | ''       | 'CH1566J0B00'    |'C0402'| '(C0402-0201)'                                                       | '560PF'    | '50V'         | '5%'     | 'DISCRETE' | 'CAP CHIP 560P 50V(+-5%,C0G,0402)'                             | 'CHIP0402'     | ''          | ''   | '20160314'
 '560PF'    | '50V'   | '5%'      | 'C0402'     | 'EMPTY'   | 'CH1566J0B00'(!)   = ''              | ''                 | ''       | 'CH1566J0B00'    |'C0402'| '(C0402-0201)'                                                       | 'NA'       | '50V'         | '5%'     | 'IO'       | 'CAP CHIP 560P 50V(+-5%,C0G,0402)'                             | 'CHIP0402'     | ''          | ''   | '20160314'
 '1200PF'   | '50V'   | '10%'     | 'C0402'     | 'X7R'     | 'CH2126K1B05'(!)   = ''              | ''                 | ''       | 'CH2126K1B05'    |'C0402'| '(C0402-0201)'                                                       | '1200PF'   | '50V'         | '10%'    | 'DISCRETE' | 'CAP CHIP 1200P 50V(+-10%.X7R.0402)'                           | 'CHIP0402'     | ''          | ''   | '20160322'
 '1200PF'   | '50V'   | '10%'     | 'C0402'     | 'EMPTY'   | 'CH2126K1B05'(!)   = ''              | ''                 | ''       | 'CH2126K1B05'    |'C0402'| '(C0402-0201)'                                                       | 'NA'       | '50V'         | '10%'    | 'IO'       | 'CAP CHIP 1200P 50V(+-10%.X7R.0402)'                           | 'CHIP0402'     | ''          | ''   | '20160322'
 '0.01UF'   | '100V'  | '5%'      | 'C1206'     | 'C0G'     | 'CH3108J0200'(!)   = ''              | ''                 | ''       | 'CH3108J0200'    |'C1206_H42'| '(SMC1206AW)'                                                        | '0.01UF'   | '100V'        | '5%'     | 'DISCRETE' | 'CAP CHIP 0.01U 100V(+-5%,C0G,1206)MUR'                        | 'CHIP1206'     | ''          | ''   | '20160324'
 '0.01UF'   | '100V'  | '5%'      | 'C1206'     | 'EMPTY'   | 'CH3108J0200'(!)   = ''              | ''                 | ''       | 'CH3108J0200'    |'C1206_H42'| '(SMC1206AW)'                                                        | 'NA'       | '100V'        | '5%'     | 'IO'       | 'CAP CHIP 0.01U 100V(+-5%,C0G,1206)MUR'                        | 'CHIP1206'     | ''          | ''   | '20160324'
 '27PF'     | '50V'   | '5%'      | 'C0402'     | 'C0G'     | 'CH0276J0B07'(!)   = ''              | ''                 | ''       | 'CH0276J0B07'    |'C0402'| '(C0402-0201)'                                                       | '27PF'     | '50V'         | '5%'     | 'DISCRETE' | 'CAP CHIP 27P 50V(+-5%,C0G,0402)AEC'                           | 'CHIP0402'     | ''          | ''   | '20160328'
 '27PF'     | '50V'   | '5%'      | 'C0402'     | 'EMPTY'   | 'CH0276J0B07'(!)   = ''              | ''                 | ''       | 'CH0276J0B07'    |'C0402'| '(C0402-0201)'                                                       | 'NA'       | '50V'         | '5%'     | 'IO'       | 'CAP CHIP 27P 50V(+-5%,C0G,0402)AEC'                           | 'CHIP0402'     | ''          | ''   | '20160328'
 '1UF'      | '10V'   | '10%'     | 'C0402'     | 'X7S'     | 'CH5102K6B01'(!)   = ''              | ''                 | ''       | 'CH5102K6B01'    |'C0402'| '(C0402-0201)'                                                       | '1UF'      | '10V'         | '10%'    | 'DISCRETE' | 'CAP CHIP 1U 10V(10%,X7S,0402)AEC'                             | 'CHIP0402'     | ''          | ''   | '20160328'
 '1UF'      | '10V'   | '10%'     | 'C0402'     | 'EMPTY'   | 'CH5102K6B01'(!)   = ''              | ''                 | ''       | 'CH5102K6B01'    |'C0402'| '(C0402-0201)'                                                       | 'NA'       | '10V'         | '10%'    | 'IO'       | 'CAP CHIP 1U 10V(10%,X7S,0402)AEC'                             | 'CHIP0402'     | ''          | ''   | '20160328'
 '0.22UF'   | '16V'   | '10%'     | 'C0402'     | 'X7R'     | 'CH4223K1B07'(!)   = ''              | ''                 | ''       | 'CH4223K1B07'    |'C0402'| '(C0402-0201)'                                                       | '0.22UF'   | '16V'         | '10%'    | 'DISCRETE' | 'CAP CHIP 0.22U 16V(10%,X7R,0402)MUR_AEC'                      | 'CHIP0402'     | ''          | ''   | '20160518'
 '0.22UF'   | '16V'   | '10%'     | 'C0402'     | 'EMPTY'   | 'CH4223K1B07'(!)   = ''              | ''                 | ''       | 'CH4223K1B07'    |'C0402'| '(C0402-0201)'                                                       | 'NA'       | '16V'         | '10%'    | 'IO'       | 'CAP CHIP 0.22U 16V(10%,X7R,0402)MUR_AEC'                      | 'CHIP0402'     | ''          | ''   | '20160518'
 '0.01UF'   | '50V'   | '10%'     | 'C0402'     | 'X7R'     | 'CH3106K1B09'(!)   = ''              | ''                 | ''       | 'CH3106K1B09'    |'C0402'| '(C0402-0201)'                                                       | '0.01UF'   | '50V'         | '10%'    | 'DISCRETE' | 'CAP CHIP 0.01U 50V(10%,X7R,0402)MUR_AEC'                      | 'CHIP0402'     | ''          | ''   | '20160518'
 '0.01UF'   | '50V'   | '10%'     | 'C0402'     | 'EMPTY'   | 'CH3106K1B09'(!)   = ''              | ''                 | ''       | 'CH3106K1B09'    |'C0402'| '(C0402-0201)'                                                       | 'NA'       | '50V'         | '10%'    | 'IO'       | 'CAP CHIP 0.01U 50V(10%,X7R,0402)MUR_AEC'                      | 'CHIP0402'     | ''          | ''   | '20160518'
 '330PF'    | '50V'   | '10%'     | 'C0402'     | 'X7R'     | 'CH1336K1B08'(!)   = ''              | ''                 | ''       | 'CH1336K1B08'    |'C0402'| '(C0402-0201)'                                                       | '330PF'    | '50V'         | '10%'    | 'DISCRETE' | 'CAP CHIP 330P 50V(10%,X7R,0402)MUR_AEC'                       | 'CHIP0402'     | ''          | ''   | '20160520'
 '330PF'    | '50V'   | '10%'     | 'C0402'     | 'EMPTY'   | 'CH1336K1B08'(!)   = ''              | ''                 | ''       | 'CH1336K1B08'    |'C0402'| '(C0402-0201)'                                                       | 'NA'       | '50V'         | '10%'    | 'IO'       | 'CAP CHIP 330P 50V(10%,X7R,0402)MUR_AEC'                       | 'CHIP0402'     | ''          | ''   | '20160520'
 '0.1UF'    | '16V'   | '10%'     | 'C0402'     | 'X7R'     | 'CH4103K1B22'(!)   = 'End of Design' | 'Comp-Approve'     | ''       | 'CH4103K1B22'    |'C0402'| '(C0402_OCTAGONXA,C0402-0201)'                                       | '0.1UF'    | '16V'         | '10%'    | 'DISCRETE' | 'CAP CHIP 0.1U 16V(10%,X7R,0402)MUR_AEC'                       | 'CHIP0402'     | ''          | ''   | '20160520'
 '0.1UF'    | '16V'   | '10%'     | 'C0402'     | 'EMPTY'   | 'CH4103K1B22'(!)   = 'End of Design' | 'Comp-Approve'     | ''       | 'CH4103K1B22'    |'C0402'| '(C0402_OCTAGONXA,C0402-0201)'                                       | 'NA'       | '16V'         | '10%'    | 'IO'       | 'CAP CHIP 0.1U 16V(10%,X7R,0402)MUR_AEC'                       | 'CHIP0402'     | ''          | ''   | '20160520'
 '2.2UF'    | '10V'   | '10%'     | 'C0402'     | 'X6S'     | 'CH5222KEB05'(!)   = ''              | ''                 | ''       | 'CH5222KEB05'    |'C0402'| '(C0402_OCTAGONXA,C0402-0201)'                                       | '2.2UF'    | '10V'         | '10%'    | 'DISCRETE' | 'CAP CHIP 2.2U 10V(10%,X6S,0402)MUR_AEC'                       | 'CHIP0402'     | ''          | ''   | '20160520'
 '2.2UF'    | '10V'   | '10%'     | 'C0402'     | 'EMPTY'   | 'CH5222KEB05'(!)   = ''              | ''                 | ''       | 'CH5222KEB05'    |'C0402'| '(C0402_OCTAGONXA,C0402-0201)'                                       | 'NA'       | '10V'         | '10%'    | 'IO'       | 'CAP CHIP 2.2U 10V(10%,X6S,0402)MUR_AEC'                       | 'CHIP0402'     | ''          | ''   | '20160520'
 '1UF'      | '6.3V'  | '10%'     | 'C0402'     | 'X7R'     | 'CH5101K1B09'(!)   = ''              | ''                 | ''       | 'CH5101K1B09'    |'C0402'| '(C0402_OCTAGONXA,C0402-0201)'                                       | '1UF'      | '6.3V'        | '10%'    | 'DISCRETE' | 'CAP CHIP 1U 6.3V(10%,X7R,0402)MUR_AEC'                        | 'CHIP0402'     | ''          | ''   | '20160520'
 '1UF'      | '6.3V'  | '10%'     | 'C0402'     | 'EMPTY'   | 'CH5101K1B09'(!)   = ''              | ''                 | ''       | 'CH5101K1B09'    |'C0402'| '(C0402_OCTAGONXA,C0402-0201)'                                       | 'NA'       | '6.3V'        | '10%'    | 'IO'       | 'CAP CHIP 1U 6.3V(10%,X7R,0402)MUR_AEC'                        | 'CHIP0402'     | ''          | ''   | '20160520'
 '0.022UF'  | '25V'   | '10%'     | 'C0402'     | 'X7R'     | 'CH3224K1B03'(!)   = ''              | ''                 | ''       | 'CH3224K1B03'    |'C0402'| '(C0402_OCTAGONXA,C0402-0201)'                                       | '0.022UF'  | '25V'         | '10%'    | 'DISCRETE' | 'CAP CHIP 0.022U 25V(+-10%,X7R,0402)MUR'                       | 'CHIP0402'     | ''          | ''   | '20160520'
 '0.022UF'  | '25V'   | '10%'     | 'C0402'     | 'EMPTY'   | 'CH3224K1B03'(!)   = ''              | ''                 | ''       | 'CH3224K1B03'    |'C0402'| '(C0402_OCTAGONXA,C0402-0201)'                                       | 'NA'       | '25V'         | '10%'    | 'IO'       | 'CAP CHIP 0.022U 25V(+-10%,X7R,0402)MUR'                       | 'CHIP0402'     | ''          | ''   | '20160520'
 '0.047UF'  | '25V'   | '10%'     | 'C0402'     | 'X7R'     | 'CH3474K1B07'(!)   = ''              | ''                 | ''       | 'CH3474K1B07'    |'C0402'| '(C0402_OCTAGONXA,C0402-0201)'                                       | '0.047UF'  | '25V'         | '10%'    | 'DISCRETE' | 'CAP CHIP 0.047U 25V(+10% X7R 0402)AEC'                        | 'CHIP0402'     | ''          | ''   | '20160520'
 '0.047UF'  | '25V'   | '10%'     | 'C0402'     | 'EMPTY'   | 'CH3474K1B07'(!)   = ''              | ''                 | ''       | 'CH3474K1B07'    |'C0402'| '(C0402_OCTAGONXA,C0402-0201)'                                       | 'NA'       | '25V'         | '10%'    | 'IO'       | 'CAP CHIP 0.047U 25V(+10% X7R 0402)AEC'                        | 'CHIP0402'     | ''          | ''   | '20160520'
 '10PF'     | '50V'   | '2%'      | 'C0402'     | 'NPO'     | 'CH0106G0B04'(!)   = ''              | ''                 | ''       | 'CH0106G0B04'    |'C0402'| '(C0402_OCTAGONXA,C0402-0201)'                                       | '10PF'     | '50V'         | '2%'     | 'DISCRETE' | 'CAP CHIP 10P 50V(+-2%,NPO,0402)AEC'                           | 'CHIP0402'     | ''          | ''   | '20160520'
 '10PF'     | '50V'   | '2%'      | 'C0402'     | 'EMPTY'   | 'CH0106G0B04'(!)   = ''              | ''                 | ''       | 'CH0106G0B04'    |'C0402'| '(C0402_OCTAGONXA,C0402-0201)'                                       | 'NA'       | '50V'         | '2%'     | 'IO'       | 'CAP CHIP 10P 50V(+-2%,NPO,0402)AEC'                           | 'CHIP0402'     | ''          | ''   | '20160520'
 '0.01UF'   | '50V'   | '10%'     | 'C0402'     | 'X7R'     | 'CH3106K1B08'(!)   = ''              | ''                 | ''       | 'CH3106K1B08'    |'C0402'| '(C0402_OCTAGONXA,C0402-0201)'                                       | '0.01UF'   | '50V'         | '10%'    | 'DISCRETE' | 'CAP CHIP 0.01U 50V(+-10%,X7R,0402)AEC'                        | 'CHIP0402'     | ''          | ''   | '20160520'
 '0.01UF'   | '50V'   | '10%'     | 'C0402'     | 'EMPTY'   | 'CH3106K1B08'(!)   = ''              | ''                 | ''       | 'CH3106K1B08'    |'C0402'| '(C0402_OCTAGONXA,C0402-0201)'                                       | 'NA'       | '50V'         | '10%'    | 'IO'       | 'CAP CHIP 0.01U 50V(+-10%,X7R,0402)AEC'                        | 'CHIP0402'     | ''          | ''   | '20160520'
 '4700PF'   | '25V'   | '10%'     | 'C0402'     | 'X7R'     | 'CH2474K1B10'(!)   = ''              | ''                 | ''       | 'CH2474K1B10'    |'C0402'| '(C0402_OCTAGONXA,C0402-0201)'                                       | '4700PF'   | '25V'         | '10%'    | 'DISCRETE' | 'CAP CHIP 4700P 25V(+-10%,X7R,0402)AEC'                        | 'CHIP0402'     | ''          | ''   | '20160520'
 '4700PF'   | '25V'   | '10%'     | 'C0402'     | 'EMPTY'   | 'CH2474K1B10'(!)   = ''              | ''                 | ''       | 'CH2474K1B10'    |'C0402'| '(C0402_OCTAGONXA,C0402-0201)'                                       | 'NA'       | '25V'         | '10%'    | 'IO'       | 'CAP CHIP 4700P 25V(+-10%,X7R,0402)AEC'                        | 'CHIP0402'     | ''          | ''   | '20160520'
 '4.7UF'    | '6.3V'  | '20%'     | 'C0402'     | 'X6S'     | 'CH5471MEB02'(!)   = ''              | ''                 | ''       | 'CH5471MEB02'    |'C0402'| '(C0402_OCTAGON,C0402_OCTAGONXA,C0402-0201,C0402_OCTAGONXA_BOUND22)' | '4.7UF'    | '6.3V'        | '20%'    | 'DISCRETE' | 'CAP CHIP 4.7UF 6.3V(+-20%,X6S,0402)MUR'                       | 'CHIP0402'     | ''          | ''   | '20160520'
 '4.7UF'    | '6.3V'  | '20%'     | 'C0402'     | 'EMPTY'   | 'CH5471MEB02'(!)   = ''              | ''                 | ''       | 'CH5471MEB02'    |'C0402'| '(C0402_OCTAGON,C0402_OCTAGONXA,C0402-0201,C0402_OCTAGONXA_BOUND22)' | 'NA'       | '6.3V'        | '20%'    | 'IO'       | 'CAP CHIP 4.7UF 6.3V(+-20%,X6S,0402)MUR'                       | 'CHIP0402'     | ''          | ''   | '20160520'
 '0.01UF'   | '16V'   | '10%'     | 'C0402'     | 'X7R'     | 'CH3103K1B16'(!)   = ''              | ''                 | ''       | 'CH3103K1B16'    |'C0402'| '(C0402_OCTAGONXA,C0402-0201)'                                       | '0.01UF'   | '16V'         | '10%'    | 'DISCRETE' | 'CAP CHIP 0.01U 16V(10%,X7R,0402)MUR'                          | 'CHIP0402'     | ''          | ''   | '20160520'
 '0.01UF'   | '16V'   | '10%'     | 'C0402'     | 'EMPTY'   | 'CH3103K1B16'(!)   = ''              | ''                 | ''       | 'CH3103K1B16'    |'C0402'| '(C0402_OCTAGONXA,C0402-0201)'                                       | 'NA'       | '16V'         | '10%'    | 'IO'       | 'CAP CHIP 0.01U 16V(10%,X7R,0402)MUR'                          | 'CHIP0402'     | ''          | ''   | '20160520'
 '0.22UF'   | '16V'   | '10%'     | 'C0402'     | 'X7R'     | 'CH4223K1B06'(!)   = ''              | ''                 | ''       | 'CH4223K1B06'    |'C0402'| '(C0402_OCTAGONXA,C0402-0201)'                                       | '0.22UF'   | '16V'         | '10%'    | 'DISCRETE' | 'CAP CHIP 0.22U 16V(10%,X7R,0402)AEC'                          | 'CHIP0402'     | ''          | ''   | '20160520'
 '0.22UF'   | '16V'   | '10%'     | 'C0402'     | 'EMPTY'   | 'CH4223K1B06'(!)   = ''              | ''                 | ''       | 'CH4223K1B06'    |'C0402'| '(C0402_OCTAGONXA,C0402-0201)'                                       | 'NA'       | '16V'         | '10%'    | 'IO'       | 'CAP CHIP 0.22U 16V(10%,X7R,0402)AEC'                          | 'CHIP0402'     | ''          | ''   | '20160520'
 '0.01UF'   | '25V'   | '10%'     | 'C0402'     | 'X7R'     | 'CH3104K1B16'(!)   = ''              | ''                 | ''       | 'CH3104K1B16'    |'C0402'| '(C0402-0201)'                                                       | '0.01UF'   | '25V'         | '10%'    | 'DISCRETE' | 'CAP CHIP 0.01U 25V(10%,X7R,0402)MUR_AEC'                      | 'CHIP0402'     | ''          | ''   | '20160525'
 '0.01UF'   | '25V'   | '10%'     | 'C0402'     | 'EMPTY'   | 'CH3104K1B16'(!)   = ''              | ''                 | ''       | 'CH3104K1B16'    |'C0402'| '(C0402-0201)'                                                       | 'NA'       | '25V'         | '10%'    | 'IO'       | 'CAP CHIP 0.01U 25V(10%,X7R,0402)MUR_AEC'                      | 'CHIP0402'     | ''          | ''   | '20160525'
 '0.047UF'  | '25V'   | '10%'     | 'C0402'     | 'X7R'     | 'CH3474K1B08'(!)   = ''              | ''                 | ''       | 'CH3474K1B08'    |'C0402'| '(C0402-0201)'                                                       | '0.047UF'  | '25V'         | '10%'    | 'DISCRETE' | 'CAP CHIP 0.047U 25V(10% X7R 0402)MUR_AEC'                     | 'CHIP0402'     | ''          | ''   | '20160525'
 '0.047UF'  | '25V'   | '10%'     | 'C0402'     | 'EMPTY'   | 'CH3474K1B08'(!)   = ''              | ''                 | ''       | 'CH3474K1B08'    |'C0402'| '(C0402-0201)'                                                       | 'NA'       | '25V'         | '10%'    | 'IO'       | 'CAP CHIP 0.047U 25V(10% X7R 0402)MUR_AEC'                     | 'CHIP0402'     | ''          | ''   | '20160525'
 '0.1UF'    | '10V'   | '10%'     | 'C0402'     | 'X7R'     | 'CH4102K1B12'(!)   = ''              | ''                 | ''       | 'CH4102K1B12'    |'C0402'| '(C0402-0201)'                                                       | '0.1UF'    | '10V'         | '10%'    | 'DISCRETE' | 'CAP CHIP 0.1U 10V(10%,X7R,0402)MUR_AEC'                       | 'CHIP0402'     | ''          | ''   | '20160525'
 '0.1UF'    | '10V'   | '10%'     | 'C0402'     | 'EMPTY'   | 'CH4102K1B12'(!)   = ''              | ''                 | ''       | 'CH4102K1B12'    |'C0402'| '(C0402-0201)'                                                       | 'NA'       | '10V'         | '10%'    | 'IO'       | 'CAP CHIP 0.1U 10V(10%,X7R,0402)MUR_AEC'                       | 'CHIP0402'     | ''          | ''   | '20160525'
 '0.1UF'    | '25V'   | '10%'     | 'C0402'     | 'X7R'     | 'CH4104K1B07'(!)   = ''              | ''                 | ''       | 'CH4104K1B07'    |'C0402'| '(C0402-0201)'                                                       | '0.1UF'    | '25V'         | '10%'    | 'DISCRETE' | 'CAP CHIP 0.1U 25V(10%,X7R,0402)MUR_AEC'                       | 'CHIP0402'     | ''          | ''   | '20160525'
 '0.1UF'    | '25V'   | '10%'     | 'C0402'     | 'EMPTY'   | 'CH4104K1B07'(!)   = ''              | ''                 | ''       | 'CH4104K1B07'    |'C0402'| '(C0402-0201)'                                                       | 'NA'       | '25V'         | '10%'    | 'IO'       | 'CAP CHIP 0.1U 25V(10%,X7R,0402)MUR_AEC'                       | 'CHIP0402'     | ''          | ''   | '20160525'
 '0.1UF'    | '25V'   | '10%'     | 'C0603'     | 'X7R'     | 'CH4104K1915'(!)   = 'End of Design' | 'Comp-Approve'     | ''       | 'CH4104K1915'    |'C0603'| '(SMC0603AW)'                                                        | '0.1UF'    | '25V'         | '10%'    | 'DISCRETE' | 'CAP CHIP 0.1U 25V(10%,X7R,0603)MUR_AEC'                       | 'CHIP0603'     | ''          | ''   | '20160525'
 '0.1UF'    | '25V'   | '10%'     | 'C0603'     | 'EMPTY'   | 'CH4104K1915'(!)   = 'End of Design' | 'Comp-Approve'     | ''       | 'CH4104K1915'    |'C0603'| '(SMC0603AW)'                                                        | 'NA'       | '25V'         | '10%'    | 'IO'       | 'CAP CHIP 0.1U 25V(10%,X7R,0603)MUR_AEC'                       | 'CHIP0603'     | ''          | ''   | '20160525'
 '0.47UF'   | '10V'   | '10%'     | 'C0402'     | 'X7S'     | 'CH4472K6B01'(!)   = ''              | ''                 | ''       | 'CH4472K6B01'    |'C0402'| '(C0402-0201)'                                                       | '0.47UF'   | '10V'         | '10%'    | 'DISCRETE' | 'CAP CHIP 0.47U 10V(10%,X7S,0402)MUR_AEC'                      | 'CHIP0402'     | ''          | ''   | '20160525'
 '0.47UF'   | '10V'   | '10%'     | 'C0402'     | 'EMPTY'   | 'CH4472K6B01'(!)   = ''              | ''                 | ''       | 'CH4472K6B01'    |'C0402'| '(C0402-0201)'                                                       | 'NA'       | '10V'         | '10%'    | 'IO'       | 'CAP CHIP 0.47U 10V(10%,X7S,0402)MUR_AEC'                      | 'CHIP0402'     | ''          | ''   | '20160525'
 '1000PF'   | '50V'   | '10%'     | 'C0402'     | 'X7R'     | 'CH2106K1B25'(!)   = ''              | ''                 | ''       | 'CH2106K1B25'    |'C0402'| '(C0402-0201)'                                                       | '1000PF'   | '50V'         | '10%'    | 'DISCRETE' | 'CAP CHIP 1000P 50V(10%,X7R,0402)MUR_AEC'                      | 'CHIP0402'     | ''          | ''   | '20160525'
 '1000PF'   | '50V'   | '10%'     | 'C0402'     | 'EMPTY'   | 'CH2106K1B25'(!)   = ''              | ''                 | ''       | 'CH2106K1B25'    |'C0402'| '(C0402-0201)'                                                       | 'NA'       | '50V'         | '10%'    | 'IO'       | 'CAP CHIP 1000P 50V(10%,X7R,0402)MUR_AEC'                      | 'CHIP0402'     | ''          | ''   | '20160525'
 '1000PF'   | '50V'   | '5%'      | 'C0402'     | 'X7R'     | 'CH2106J1B07'(!)   = ''              | ''                 | ''       | 'CH2106J1B07'    |'C0402'| '(C0402-0201)'                                                       | '1000PF'   | '50V'         | '5%'     | 'DISCRETE' | 'CAP CHIP 1000P 50V(5%,X7R,0402)MUR_AEC'                       | 'CHIP0402'     | ''          | ''   | '20160525'
 '1000PF'   | '50V'   | '5%'      | 'C0402'     | 'EMPTY'   | 'CH2106J1B07'(!)   = ''              | ''                 | ''       | 'CH2106J1B07'    |'C0402'| '(C0402-0201)'                                                       | 'NA'       | '50V'         | '5%'     | 'IO'       | 'CAP CHIP 1000P 50V(5%,X7R,0402)MUR_AEC'                       | 'CHIP0402'     | ''          | ''   | '20160525'
 '100PF'    | '50V'   | '5%'      | 'C0402'     | 'NPO'     | 'CH1106J0B19'(!)   = ''              | ''                 | ''       | 'CH1106J0B19'    |'C0402'| '(C0402-0201)'                                                       | '100PF'    | '50V'         | '5%'     | 'DISCRETE' | 'CAP CHIP 100P 50V(5%,NPO,0402)MUR_AEC'                        | 'CHIP0402'     | ''          | ''   | '20160525'
 '100PF'    | '50V'   | '5%'      | 'C0402'     | 'EMPTY'   | 'CH1106J0B19'(!)   = ''              | ''                 | ''       | 'CH1106J0B19'    |'C0402'| '(C0402-0201)'                                                       | 'NA'       | '50V'         | '5%'     | 'IO'       | 'CAP CHIP 100P 50V(5%,NPO,0402)MUR_AEC'                        | 'CHIP0402'     | ''          | ''   | '20160525'
 '10PF'     | '50V'   | '2%'      | 'C0402'     | 'NPO'     | 'CH0106G0B05'(!)   = ''              | ''                 | ''       | 'CH0106G0B05'    |'C0402'| '(C0402-0201)'                                                       | '10PF'     | '50V'         | '2%'     | 'DISCRETE' | 'CAP CHIP 10P 50V(2%,NPO,0402)MUR_AEC'                         | 'CHIP0402'     | ''          | ''   | '20160525'
 '10PF'     | '50V'   | '2%'      | 'C0402'     | 'EMPTY'   | 'CH0106G0B05'(!)   = ''              | ''                 | ''       | 'CH0106G0B05'    |'C0402'| '(C0402-0201)'                                                       | 'NA'       | '50V'         | '2%'     | 'IO'       | 'CAP CHIP 10P 50V(2%,NPO,0402)MUR_AEC'                         | 'CHIP0402'     | ''          | ''   | '20160525'
 '10UF'     | '10V'   | '20%'     | 'C0603'     | 'X6S'     | 'CH6102ME905'(!)   = ''              | ''                 | ''       | 'CH6102ME905'    |'C0603'| '(SMC0603AW)'                                                        | '10UF'     | '10V'         | '20%'    | 'DISCRETE' | 'CAP CHIP 10U 10V(20%,X6S,0603)MUR_AEC'                        | 'CHIP0603'     | ''          | ''   | '20160525'
 '10UF'     | '10V'   | '20%'     | 'C0603'     | 'EMPTY'   | 'CH6102ME905'(!)   = ''              | ''                 | ''       | 'CH6102ME905'    |'C0603'| '(SMC0603AW)'                                                        | 'NA'       | '10V'         | '20%'    | 'IO'       | 'CAP CHIP 10U 10V(20%,X6S,0603)MUR_AEC'                        | 'CHIP0603'     | ''          | ''   | '20160525'
 '10UF'     | '4V'    | '20%'     | 'C0603'     | 'X6S'     | 'CH610KME909'(!)   = ''              | ''                 | ''       | 'CH610KME909'    |'C0603'| '(SMC0603AW)'                                                        | '10UF'     | '4V'          | '20%'    | 'DISCRETE' | 'CAP CHIP 10U 4V(20%,X6S,0603)MUR_AEC'                         | 'CHIP0603'     | ''          | ''   | '20160525'
 '10UF'     | '4V'    | '20%'     | 'C0603'     | 'EMPTY'   | 'CH610KME909'(!)   = ''              | ''                 | ''       | 'CH610KME909'    |'C0603'| '(SMC0603AW)'                                                        | 'NA'       | '4V'          | '20%'    | 'IO'       | 'CAP CHIP 10U 4V(20%,X6S,0603)MUR_AEC'                         | 'CHIP0603'     | ''          | ''   | '20160525'
 '15PF'     | '50V'   | '5%'      | 'C0402'     | 'NPO'     | 'CH0156J0B12'(!)   = ''              | ''                 | ''       | 'CH0156J0B12'    |'C0402'| '(C0402-0201)'                                                       | '15PF'     | '50V'         | '5%'     | 'DISCRETE' | 'CAP CHIP 15P 50V(5%,NPO,0402)MUR_AEC'                         | 'CHIP0402'     | ''          | ''   | '20160525'
 '15PF'     | '50V'   | '5%'      | 'C0402'     | 'EMPTY'   | 'CH0156J0B12'(!)   = ''              | ''                 | ''       | 'CH0156J0B12'    |'C0402'| '(C0402-0201)'                                                       | 'NA'       | '50V'         | '5%'     | 'IO'       | 'CAP CHIP 15P 50V(5%,NPO,0402)MUR_AEC'                         | 'CHIP0402'     | ''          | ''   | '20160525'
 '18PF'     | '50V'   | '5%'      | 'C0402'     | 'NPO'     | 'CH0186J0B09'(!)   = ''              | ''                 | ''       | 'CH0186J0B09'    |'C0402'| '(C0402-0201)'                                                       | '15PF'     | '50V'         | '5%'     | 'DISCRETE' | 'CAP CHIP 18P 50V(5%,NPO,0402)MUR_AEC'                         | 'CHIP0402'     | ''          | ''   | '20160526'
 '18PF'     | '50V'   | '5%'      | 'C0402'     | 'EMPTY'   | 'CH0186J0B09'(!)   = ''              | ''                 | ''       | 'CH0186J0B09'    |'C0402'| '(C0402-0201)'                                                       | 'NA'       | '50V'         | '5%'     | 'IO'       | 'CAP CHIP 18P 50V(5%,NPO,0402)MUR_AEC'                         | 'CHIP0402'     | ''          | ''   | '20160526'
 '1UF'      | '16V'   | '10%'     | 'C0603'     | 'X7R'     | 'CH5103K1914'(!)   = 'End of Design' | 'Comp-Approve'     | ''       | 'CH5103K1914'    |'C0603'| '(SMC0603AW)'                                                        | '15PF'     | '16V'         | '10%'    | 'DISCRETE' | 'CAP CHIP 1U 16V(10%,X7R,0603)MUR_AEC'                         | 'CHIP0603'     | ''          | ''   | '20160526'
 '1UF'      | '16V'   | '10%'     | 'C0603'     | 'EMPTY'   | 'CH5103K1914'(!)   = 'End of Design' | 'Comp-Approve'     | ''       | 'CH5103K1914'    |'C0603'| '(SMC0603AW)'                                                        | 'NA'       | '16V'         | '10%'    | 'IO'       | 'CAP CHIP 1U 16V(10%,X7R,0603)MUR_AEC'                         | 'CHIP0603'     | ''          | ''   | '20160526'
 '1UF'      | '16V'   | '10%'     | 'C0402'     | 'X6S'     | 'CH5103KEB06'(!)   = ''              | ''                 | ''       | 'CH5103KEB06'    |'C0402'| '(C0402-0201)'                                                       | '15PF'     | '16V'         | '10%'    | 'DISCRETE' | 'CAP CHIP 1U 16V(10%,X6S,0402)MUR_AEC'                         | 'CHIP0402'     | ''          | ''   | '20160526'
 '1UF'      | '16V'   | '10%'     | 'C0402'     | 'EMPTY'   | 'CH5103KEB06'(!)   = ''              | ''                 | ''       | 'CH5103KEB06'    |'C0402'| '(C0402-0201)'                                                       | 'NA'       | '16V'         | '10%'    | 'IO'       | 'CAP CHIP 1U 16V(10%,X6S,0402)MUR_AEC'                         | 'CHIP0402'     | ''          | ''   | '20160526'
 '1UF'      | '25V'   | '10%'     | 'C0402'     | 'X6S'     | 'CH5104KEB06'(!)   = ''              | ''                 | ''       | 'CH5104KEB06'    |'C0402'| '(C0402-0201)'                                                       | '15PF'     | '25V'         | '10%'    | 'DISCRETE' | 'CAP CHIP 1U 25V(10%,X6S,0402)MUR_AEC'                         | 'CHIP0402'     | ''          | ''   | '20160526'
 '1UF'      | '25V'   | '10%'     | 'C0402'     | 'EMPTY'   | 'CH5104KEB06'(!)   = ''              | ''                 | ''       | 'CH5104KEB06'    |'C0402'| '(C0402-0201)'                                                       | 'NA'       | '25V'         | '10%'    | 'IO'       | 'CAP CHIP 1U 25V(10%,X6S,0402)MUR_AEC'                         | 'CHIP0402'     | ''          | ''   | '20160526'
 '2200PF'   | '50V'   | '10%'     | 'C0402'     | 'X7R'     | 'CH2226K1B14'(!)   = ''              | ''                 | ''       | 'CH2226K1B14'    |'C0402'| '(C0402-0201)'                                                       | '2200PF'   | '50V'         | '10%'    | 'DISCRETE' | 'CAP CHIP 2200P 50V(10%,X7R,0402)MUR_AEC'                      | 'CHIP0402'     | ''          | ''   | '20160526'
 '2200PF'   | '50V'   | '10%'     | 'C0402'     | 'EMPTY'   | 'CH2226K1B14'(!)   = ''              | ''                 | ''       | 'CH2226K1B14'    |'C0402'| '(C0402-0201)'                                                       | 'NA'       | '50V'         | '10%'    | 'IO'       | 'CAP CHIP 2200P 50V(10%,X7R,0402)MUR_AEC'                      | 'CHIP0402'     | ''          | ''   | '20160526'
 '22PF'     | '50V'   | '5%'      | 'C0402'     | 'NPO'     | 'CH0226J0B23'(!)   = ''              | ''                 | ''       | 'CH0226J0B23'    |'C0402'| '(C0402-0201)'                                                       | '22PF'     | '50V'         | '5%'     | 'DISCRETE' | 'CAP CHIP 22P 50V(5%,NPO,0402)MUR_AEC'                         | 'CHIP0402'     | ''          | ''   | '20160526'
 '22PF'     | '50V'   | '5%'      | 'C0402'     | 'EMPTY'   | 'CH0226J0B23'(!)   = ''              | ''                 | ''       | 'CH0226J0B23'    |'C0402'| '(C0402-0201)'                                                       | 'NA'       | '50V'         | '5%'     | 'IO'       | 'CAP CHIP 22P 50V(5%,NPO,0402)MUR_AEC'                         | 'CHIP0402'     | ''          | ''   | '20160526'
 '3300PF'   | '50V'   | '10%'     | 'C0402'     | 'X7R'     | 'CH2336K1B11'(!)   = ''              | ''                 | ''       | 'CH2336K1B11'    |'C0402'| '(C0402-0201)'                                                       | '3300PF'   | '50V'         | '10%'    | 'DISCRETE' | 'CAP CHIP 3300P 50V(10%,X7R,0402)MUR_AEC'                      | 'CHIP0402'     | ''          | ''   | '20160526'
 '3300PF'   | '50V'   | '10%'     | 'C0402'     | 'EMPTY'   | 'CH2336K1B11'(!)   = ''              | ''                 | ''       | 'CH2336K1B11'    |'C0402'| '(C0402-0201)'                                                       | 'NA'       | '50V'         | '10%'    | 'IO'       | 'CAP CHIP 3300P 50V(10%,X7R,0402)MUR_AEC'                      | 'CHIP0402'     | ''          | ''   | '20160526'
 '4.7UF'    | '6.3V'  | '10%'     | 'C0603'     | 'X6S'     | 'CH5471KE907'(!)   = 'End of Design' | 'Comp-Approve'     | ''       | 'CH5471KE907'    |'C0603'| '(SMC0603AW)'                                                        | '4.7UF'    | '6.3V'        | '10%'    | 'DISCRETE' | 'CAP CHIP 4.7U 6.3V(10%,X6S,0603)MUR_AEC'                      | 'CHIP0603'     | ''          | ''   | '20160526'
 '4.7UF'    | '6.3V'  | '10%'     | 'C0603'     | 'EMPTY'   | 'CH5471KE907'(!)   = 'End of Design' | 'Comp-Approve'     | ''       | 'CH5471KE907'    |'C0603'| '(SMC0603AW)'                                                        | 'NA'       | '6.3V'        | '10%'    | 'IO'       | 'CAP CHIP 4.7U 6.3V(10%,X6S,0603)MUR_AEC'                      | 'CHIP0603'     | ''          | ''   | '20160526'
 '4700PF'   | '25V'   | '10%'     | 'C0402'     | 'X7R'     | 'CH2474K1B11'(!)   = ''              | ''                 | ''       | 'CH2474K1B11'    |'C0402'| '(C0402-0201)'                                                       | '4700PF'   | '25V'         | '10%'    | 'DISCRETE' | 'CAP CHIP 4700P 25V(10%,X7R,0402)MUR_AEC'                      | 'CHIP0402'     | ''          | ''   | '20160526'
 '4700PF'   | '25V'   | '10%'     | 'C0402'     | 'EMPTY'   | 'CH2474K1B11'(!)   = ''              | ''                 | ''       | 'CH2474K1B11'    |'C0402'| '(C0402-0201)'                                                       | 'NA'       | '25V'         | '10%'    | 'IO'       | 'CAP CHIP 4700P 25V(10%,X7R,0402)MUR_AEC'                      | 'CHIP0402'     | ''          | ''   | '20160526'
 '470PF'    | '50V'   | '10%'     | 'C0402'     | 'X7R'     | 'CH1476K1B15'(!)   = ''              | ''                 | ''       | 'CH1476K1B15'    |'C0402'| '(C0402-0201)'                                                       | '470PF'    | '50V'         | '10%'    | 'DISCRETE' | 'CAP CHIP 470P 50V(10%,X7R,0402)MUR_AEC'                       | 'CHIP0402'     | ''          | ''   | '20160526'
 '470PF'    | '50V'   | '10%'     | 'C0402'     | 'EMPTY'   | 'CH1476K1B15'(!)   = ''              | ''                 | ''       | 'CH1476K1B15'    |'C0402'| '(C0402-0201)'                                                       | 'NA'       | '50V'         | '10%'    | 'IO'       | 'CAP CHIP 470P 50V(10%,X7R,0402)MUR_AEC'                       | 'CHIP0402'     | ''          | ''   | '20160526'
 '47PF'     | '50V'   | '5%'      | 'C0402'     | 'C0G'     | 'CH0476J0B15'(!)   = ''              | ''                 | ''       | 'CH0476J0B15'    |'C0402'| '(C0402-0201)'                                                       | '47PF'     | '50V'         | '5%'     | 'DISCRETE' | 'CAP CHIP 47P 50V(5%,C0G,0402)MUR_AEC'                         | 'CHIP0402'     | ''          | ''   | '20160526'
 '47PF'     | '50V'   | '5%'      | 'C0402'     | 'EMPTY'   | 'CH0476J0B15'(!)   = ''              | ''                 | ''       | 'CH0476J0B15'    |'C0402'| '(C0402-0201)'                                                       | 'NA'       | '50V'         | '5%'     | 'IO'       | 'CAP CHIP 47P 50V(5%,C0G,0402)MUR_AEC'                         | 'CHIP0402'     | ''          | ''   | '20160526'
 '27PF'     | '50V'   | '5%'      | 'C0402'     | 'C0G'     | 'CH0276J0B08'(!)   = ''              | ''                 | ''       | 'CH0276J0B08'    |'C0402'| '(C0402-0201)'                                                       | '27PF'     | '50V'         | '5%'     | 'DISCRETE' | 'CAP CHIP 27P 50V(5%,C0G,0402)MUR_AEC'                         | 'CHIP0402'     | ''          | ''   | '20160530'
 '27PF'     | '50V'   | '5%'      | 'C0402'     | 'EMPTY'   | 'CH0276J0B08'(!)   = ''              | ''                 | ''       | 'CH0276J0B08'    |'C0402'| '(C0402-0201)'                                                       | 'NA'       | '50V'         | '5%'     | 'IO'       | 'CAP CHIP 27P 50V(5%,C0G,0402)MUR_AEC'                         | 'CHIP0402'     | ''          | ''   | '20160530'
 '1UF'      | '10V'   | '10%'     | 'C0402'     | 'X7S'     | 'CH5102K6B02'(!)   = ''              | ''                 | ''       | 'CH5102K6B02'    |'C0402'| '(C0402-0201)'                                                       | '1UF'      | '10V'         | '10%'    | 'DISCRETE' | 'CAP CHIP 1U 10V(10%,X7S,0402)MUR_AEC'                         | 'CHIP0402'     | ''          | ''   | '20160530'
 '1UF'      | '10V'   | '10%'     | 'C0402'     | 'EMPTY'   | 'CH5102K6B02'(!)   = ''              | ''                 | ''       | 'CH5102K6B02'    |'C0402'| '(C0402-0201)'                                                       | 'NA'       | '10V'         | '10%'    | 'IO'       | 'CAP CHIP 1U 10V(10%,X7S,0402)MUR_AEC'                         | 'CHIP0402'     | ''          | ''   | '20160530'
 '4.7UF'    | '16V'   | '10%'     | 'C0603'     | 'X6S'     | 'CH5473KE901'(!)   = ''              | ''                 | ''       | 'CH5473KE901'    |'C0603'| '(SMC0603AW)'                                                        | '4.7UF'    | '16V'         | '10%'    | 'DISCRETE' | 'CAP CHIP 4.7U 16V(10%,X6S,0603)MUR_AEC'                       | 'CHIP0603'     | ''          | ''   | '20160530'
 '4.7UF'    | '16V'   | '10%'     | 'C0603'     | 'EMPTY'   | 'CH5473KE901'(!)   = ''              | ''                 | ''       | 'CH5473KE901'    |'C0603'| '(SMC0603AW)'                                                        | 'NA'       | '16V'         | '10%'    | 'IO'       | 'CAP CHIP 4.7U 16V(10%,X6S,0603)MUR_AEC'                       | 'CHIP0603'     | ''          | ''   | '20160530'
 '33PF'     | '50V'   | '5%'      | 'C0402'     | 'C0G'     | 'CH0336J0B14'(!)   = ''              | ''                 | ''       | 'CH0336J0B14'    |'C0402'| '(C0402-0201)'                                                       | '33PF'     | '50V'         | '5%'     | 'DISCRETE' | 'CAP CHIP 33P 50V(5%,C0G,0402)MUR_AEC'                         | 'CHIP0402'     | ''          | ''   | '20160530'
 '33PF'     | '50V'   | '5%'      | 'C0402'     | 'EMPTY'   | 'CH0336J0B14'(!)   = ''              | ''                 | ''       | 'CH0336J0B14'    |'C0402'| '(C0402-0201)'                                                       | 'NA'       | '50V'         | '5%'     | 'IO'       | 'CAP CHIP 33P 50V(5%,C0G,0402)MUR_AEC'                         | 'CHIP0402'     | ''          | ''   | '20160530'
 '0.01UF'   | '50V'   | '10%'     | 'C0603'     | 'X7R'     | 'CH3106K1915'(!)   = 'End of Design' | 'Comp-Approve'     | ''       | 'CH3106K1915'    |'C0603'| '(SMC0603AW)'                                                        | '0.01UF'   | '50V'         | '10%'    | 'DISCRETE' | 'CAP CHIP 0.01U 50V(10%,X7R,0603)MUR_AEC'                      | 'CHIP0603'     | ''          | ''   | '20160530'
 '0.01UF'   | '50V'   | '10%'     | 'C0603'     | 'EMPTY'   | 'CH3106K1915'(!)   = 'End of Design' | 'Comp-Approve'     | ''       | 'CH3106K1915'    |'C0603'| '(SMC0603AW)'                                                        | 'NA'       | '50V'         | '10%'    | 'IO'       | 'CAP CHIP 0.01U 50V(10%,X7R,0603)MUR_AEC'                      | 'CHIP0603'     | ''          | ''   | '20160530'
 '10UF'     | '16V'   | '10%'     | 'C1206'     | 'X7R'     | 'CH6103K1203'(!)   = ''              | ''                 | ''       | 'CH6103K1203'    |'C1206_H76'| '(SMC1206AW)'                                                        | '10UF'     | '16V'         | '10%'    | 'DISCRETE' | 'CAP CHIP 10U 16V(10%,X7R,1206)MUR_AEC'                        | 'CHIP1206'     | ''          | ''   | '20160531'
 '10UF'     | '16V'   | '10%'     | 'C1206'     | 'EMPTY'   | 'CH6103K1203'(!)   = ''              | ''                 | ''       | 'CH6103K1203'    |'C1206_H76'| '(SMC1206AW)'                                                        | 'NA'       | '16V'         | '10%'    | 'IO'       | 'CAP CHIP 10U 16V(10%,X7R,1206)MUR_AEC'                        | 'CHIP1206'     | ''          | ''   | '20160531'
 '10UF'     | '16V'   | '10%'     | 'C0805'     | 'X7S'     | 'CH6103K6A01'(!)   = ''              | ''                 | ''       | 'CH6103K6A01'    |'C0805_H57'| '(SMC0805AW)'                                                        | '10UF'     | '16V'         | '10%'    | 'DISCRETE' | 'CAP CHIP 10U 16V(10%,X7S,0805)MUR_AEC'                        | 'CHIP0805'     | ''          | ''   | '20160531'
 '10UF'     | '16V'   | '10%'     | 'C0805'     | 'EMPTY'   | 'CH6103K6A01'(!)   = ''              | ''                 | ''       | 'CH6103K6A01'    |'C0805_H57'| '(SMC0805AW)'                                                        | 'NA'       | '16V'         | '10%'    | 'IO'       | 'CAP CHIP 10U 16V(10%,X7S,0805)MUR_AEC'                        | 'CHIP0805'     | ''          | ''   | '20160531'
 '10UF'     | '25V'   | '10%'     | 'C1206'     | 'X7S'     | 'CH6104K6201'(!)   = 'End of Design' | 'Comp-Approve'     | ''       | 'CH6104K6201'    |'C1206_H76'| '(SMC1206AW)'                                                        | '10UF'     | '25V'         | '10%'    | 'DISCRETE' | 'CAP CHIP 10U 25V(10%,X7S,1206)MUR_AEC'                        | 'CHIP1206'     | ''          | ''   | '20160531'
 '10UF'     | '25V'   | '10%'     | 'C1206'     | 'EMPTY'   | 'CH6104K6201'(!)   = 'End of Design' | 'Comp-Approve'     | ''       | 'CH6104K6201'    |'C1206_H76'| '(SMC1206AW)'                                                        | 'NA'       | '25V'         | '10%'    | 'IO'       | 'CAP CHIP 10U 25V(10%,X7S,1206)MUR_AEC'                        | 'CHIP1206'     | ''          | ''   | '20160531'
 '10UF'     | '6.3V'  | '10%'     | 'C0805'     | 'X7R'     | 'CH6101K1A02'(!)   = ''              | ''                 | ''       | 'CH6101K1A02'    |'C0805_H57'| '(SMC0805AW)'                                                        | '10UF'     | '6.3V'        | '10%'    | 'DISCRETE' | 'CAP CHIP 10U 6.3V(10%,X7R,0805)MUR_AEC'                       | 'CHIP0805'     | ''          | ''   | '20160531'
 '10UF'     | '6.3V'  | '10%'     | 'C0805'     | 'EMPTY'   | 'CH6101K1A02'(!)   = ''              | ''                 | ''       | 'CH6101K1A02'    |'C0805_H57'| '(SMC0805AW)'                                                        | 'NA'       | '6.3V'        | '10%'    | 'IO'       | 'CAP CHIP 10U 6.3V(10%,X7R,0805)MUR_AEC'                       | 'CHIP0805'     | ''          | ''   | '20160531'
 '2.2UF'    | '10V'   | '10%'     | 'C0805'     | 'X7R'     | 'CH5222K1A02'(!)   = 'End of Design' | 'Comp-Approve'     | ''       | 'CH5222K1A02'    |'C0805_H57'| '(SMC0805AW)'                                                        | '2.2UF'    | '10V'         | '10%'    | 'DISCRETE' | 'CAP CHIP 2.2U 10V(10%,X7R,0805)MUR_AEC'                       | 'CHIP0805'     | ''          | ''   | '20160531'
 '2.2UF'    | '10V'   | '10%'     | 'C0805'     | 'EMPTY'   | 'CH5222K1A02'(!)   = 'End of Design' | 'Comp-Approve'     | ''       | 'CH5222K1A02'    |'C0805_H57'| '(SMC0805AW)'                                                        | 'NA'       | '10V'         | '10%'    | 'IO'       | 'CAP CHIP 2.2U 10V(10%,X7R,0805)MUR_AEC'                       | 'CHIP0805'     | ''          | ''   | '20160531'
 '22UF'     | '10V'   | '20%'     | 'C0805'     | 'X6S'     | 'CH6222MEA04'(!)   = ''              | ''                 | ''       | 'CH6222MEA04'    |'C0805_H57'| '(SMC0805AW)'                                                        | '22UF'     | '10V'         | '20%'    | 'DISCRETE' | 'CAP CHIP 22U 10V(20%,X6S,0805)MUR_AEC'                        | 'CHIP0805'     | ''          | ''   | '20160531'
 '22UF'     | '10V'   | '20%'     | 'C0805'     | 'EMPTY'   | 'CH6222MEA04'(!)   = ''              | ''                 | ''       | 'CH6222MEA04'    |'C0805_H57'| '(SMC0805AW)'                                                        | 'NA'       | '10V'         | '20%'    | 'IO'       | 'CAP CHIP 22U 10V(20%,X6S,0805)MUR_AEC'                        | 'CHIP0805'     | ''          | ''   | '20160531'
 '22UF'     | '25V'   | '10%'     | 'C1206'     | 'X5R'     | 'CH6224K9204'(!)   = ''              | ''                 | ''       | 'CH6224K9204'    |'C1206_H76'| '(SMC1206AW)'                                                        | '22UF'     | '25V'         | '10%'    | 'DISCRETE' | 'CAP CHIP 22U 25V(10%,X5R,1206)MUR_AEC'                        | 'CHIP1206'     | ''          | ''   | '20160531'
 '22UF'     | '25V'   | '10%'     | 'C1206'     | 'EMPTY'   | 'CH6224K9204'(!)   = ''              | ''                 | ''       | 'CH6224K9204'    |'C1206_H76'| '(SMC1206AW)'                                                        | 'NA'       | '25V'         | '10%'    | 'IO'       | 'CAP CHIP 22U 25V(10%,X5R,1206)MUR_AEC'                        | 'CHIP1206'     | ''          | ''   | '20160531'
 '4.7UF'    | '16V'   | '10%'     | 'C0805'     | 'X7R'     | 'CH5473K1A05'(!)   = 'End of Design' | 'Comp-Approve'     | ''       | 'CH5473K1A05'    |'C0805_H57'| '(SMC0805AW)'                                                        | '4.7UF'    | '16V'         | '10%'    | 'DISCRETE' | 'CAP CHIP 4.7UF 16V(10%,X7R,0805)MUR_AEC'                      | 'CHIP0805'     | ''          | ''   | '20160531'
 '4.7UF'    | '16V'   | '10%'     | 'C0805'     | 'EMPTY'   | 'CH5473K1A05'(!)   = 'End of Design' | 'Comp-Approve'     | ''       | 'CH5473K1A05'    |'C0805_H57'| '(SMC0805AW)'                                                        | 'NA'       | '16V'         | '10%'    | 'IO'       | 'CAP CHIP 4.7UF 16V(10%,X7R,0805)MUR_AEC'                      | 'CHIP0805'     | ''          | ''   | '20160531'
 '0.022UF'  | '25V'   | '10%'     | 'C0402'     | 'X7R'     | 'CH3224K1B06'(!)   = ''              | ''                 | ''       | 'CH3224K1B06'    |'C0402'| '(C0402-0201)'                                                       | '0.022UF'  | '25V'         | '10%'    | 'DISCRETE' | 'CAP CHIP 0.022U 25V(10%,X7R,0402)MUR_AEC'                     | 'CHIP0402'     | ''          | ''   | '20160602'
 '0.022UF'  | '25V'   | '10%'     | 'C0402'     | 'EMPTY'   | 'CH3224K1B06'(!)   = ''              | ''                 | ''       | 'CH3224K1B06'    |'C0402'| '(C0402-0201)'                                                       | 'NA'       | '25V'         | '10%'    | 'IO'       | 'CAP CHIP 0.022U 25V(10%,X7R,0402)MUR_AEC'                     | 'CHIP0402'     | ''          | ''   | '20160602'
 '47UF'     | '4V'    | '20%'     | 'C0805'     | 'X6S'     | 'CH647KMEA04'(!)   = ''              | ''                 | ''       | 'CH647KMEA04'    |'C0805_H57'| '(SMC0805AW,C0805_H57_M)'                                            | '47UF'     | '4V'          | '20%'    | 'DISCRETE' | 'CAP CHIP 47U 4V(+-20%,X6S,0805)MUR'                           | 'CHIP0805'     | ''          | ''   | '20160616'
 '47UF'     | '4V'    | '20%'     | 'C0805'     | 'EMPTY'   | 'CH647KMEA04'(!)   = ''              | ''                 | ''       | 'CH647KMEA04'    |'C0805_H57'| '(SMC0805AW,C0805_H57_M)'                                            | 'NA'       | '4V'          | '20%'    | 'IO'       | 'CAP CHIP 47U 4V(+-20%,X6S,0805)MUR'                           | 'CHIP0805'     | ''          | ''   | '20160616'
 '1UF'      | '16V'   | '10%'     | 'C0603'     | 'X7R'     | 'CH5103K1909'(!)   = 'End of Design' | 'Comp-Approve'     | ''       | 'CH5103K1909'    |'C0603'| '(SMC0603AW,C0603_M)'                                                | '1UF'      | '16V'         | '10%'    | 'DISCRETE' | 'CAP CHIP 1U 16V(+-10%,X7R,0603)MUR'                           | 'CHIP0603'     | ''          | ''   | '20160616'
 '1UF'      | '16V'   | '10%'     | 'C0603'     | 'EMPTY'   | 'CH5103K1909'(!)   = 'End of Design' | 'Comp-Approve'     | ''       | 'CH5103K1909'    |'C0603'| '(SMC0603AW,C0603_M)'                                                | 'NA'       | '16V'         | '10%'    | 'IO'       | 'CAP CHIP 1U 16V(+-10%,X7R,0603)MUR'                           | 'CHIP0603'     | ''          | ''   | '20160616'
 '0.1UF'    | '16V'   | '10%'     | 'C0402'     | 'X7R'     | 'CH4103K1B14'(!)   = 'End of Design' | 'Comp-Approve'     | ''       | 'CH4103K1B14'    |'C0402'| '(C0402_OCTAGONXA,C0402_M,C0402-0201,C0402_OCTAGONXA_BOUND22)'       | '0.1UF'    | '16V'         | '10%'    | 'DISCRETE' | 'CAP CHIP 0.1U 16V(10%,X7R,0402)MUR'                           | 'CHIP0402'     | ''          | ''   | '20160616'
 '0.1UF'    | '16V'   | '10%'     | 'C0402'     | 'EMPTY'   | 'CH4103K1B14'(!)   = 'End of Design' | 'Comp-Approve'     | ''       | 'CH4103K1B14'    |'C0402'| '(C0402_OCTAGONXA,C0402_M,C0402-0201,C0402_OCTAGONXA_BOUND22)'       | 'NA'       | '16V'         | '10%'    | 'IO'       | 'CAP CHIP 0.1U 16V(10%,X7R,0402)MUR'                           | 'CHIP0402'     | ''          | ''   | '20160616'
 '47UF'     | '4V'    | '20%'     | 'C0805'     | 'X6S'     | 'CH647KMEA08'(!)   = ''              | ''                 | ''       | 'CH647KMEA08'    |'C0805_H57'| '(SMC0805AW)'                                                        | '47UF'     | '4V'          | '20%'    | 'DISCRETE' | 'CAP CHIP 47U 4V(20%,X6S,0805)MUR_AEC'                         | 'CHIP0805'     | ''          | ''   | '20160624'
 '47UF'     | '4V'    | '20%'     | 'C0805'     | 'EMPTY'   | 'CH647KMEA08'(!)   = ''              | ''                 | ''       | 'CH647KMEA08'    |'C0805_H57'| '(SMC0805AW)'                                                        | 'NA'       | '4V'          | '20%'    | 'IO'       | 'CAP CHIP 47U 4V(20%,X6S,0805)MUR_AEC'                         | 'CHIP0805'     | ''          | ''   | '20160624'
 '22UF'     | '6.3V'  | '20%'     | 'C0805'     | 'X7T'     | 'CH6221MJA02'(!)   = ''              | ''                 | ''       | 'CH6221MJA02'    |'C0805_H57'| '(SMC0805AW)'                                                        | '22UF'     | '6.3V'        | '20%'    | 'DISCRETE' | 'CAP CHIP 22U 6.3V(20%,X7T,0805)MUR_AEC'                       | 'CHIP0805'     | ''          | ''   | '20160624'
 '22UF'     | '6.3V'  | '20%'     | 'C0805'     | 'EMPTY'   | 'CH6221MJA02'(!)   = ''              | ''                 | ''       | 'CH6221MJA02'    |'C0805_H57'| '(SMC0805AW)'                                                        | 'NA'       | '6.3V'        | '20%'    | 'IO'       | 'CAP CHIP 22U 6.3V(20%,X7T,0805)MUR_AEC'                       | 'CHIP0805'     | ''          | ''   | '20160624'
 '22UF'     | '25V'   | '10%'     | 'C1206'     | 'X6S'     | 'CH6224KE200'(!)   = 'End of Design' | 'Comp-Approve'     | ''       | 'CH6224KE200'    |'C1206_H76'| '(SMC1206AW)'                                                        | '22UF'     | '25V'         | '10%'    | 'DISCRETE' | 'CAP CHIP 22U 25V(+-10%,X6S,1206)'                             | 'CHIP1206'     | ''          | ''   | '20160624'
 '22UF'     | '25V'   | '10%'     | 'C1206'     | 'EMPTY'   | 'CH6224KE200'(!)   = 'End of Design' | 'Comp-Approve'     | ''       | 'CH6224KE200'    |'C1206_H76'| '(SMC1206AW)'                                                        | 'NA'       | '25V'         | '10%'    | 'IO'       | 'CAP CHIP 22U 25V(+-10%,X6S,1206)'                             | 'CHIP1206'     | ''          | ''   | '20160624'
 '6.8PF'    | '50V'   | '0.5PF'   | 'C0402'     | 'C0G'     | 'CH-686D0B02'(!)   = ''              | ''                 | ''       | 'CH-686D0B02'    |'C0402'| '(C0402-0201)'                                                       | '6.8PF'    | '50V'         | '0.5PF'  | 'DISCRETE' | 'CAP CHIP 6.8P 50V(0.5PF,C0G,0402)MUR_AEC'                     | 'CHIP0402'     | ''          | ''   | '20160803'
 '6.8PF'    | '50V'   | '0.5PF'   | 'C0402'     | 'EMPTY'   | 'CH-686D0B02'(!)   = ''              | ''                 | ''       | 'CH-686D0B02'    |'C0402'| '(C0402-0201)'                                                       | 'NA'       | '50V'         | '0.5PF'  | 'IO'       | 'CAP CHIP 6.8P 50V(0.5PF,C0G,0402)MUR_AEC'                     | 'CHIP0402'     | ''          | ''   | '20160803'
 '5.6PF'    | '50V'   | '0.5PF'   | 'C0402'     | 'C0G'     | 'CH-566D0B02'(!)   = ''              | 'End of Life'      | ''       | 'CH-566D0B02'    |'C0402_EOL'| '(C0402-0201)'                                                       | '5.6PF'    | '50V'         | '0.5PF'  | 'DISCRETE' | 'CAP CHIP 5.6P 50V(0.5PF,C0G,0402)MUR_AEC'                     | 'CHIP0402'     | ''          | ''   | '20160803'
 '5.6PF'    | '50V'   | '0.5PF'   | 'C0402'     | 'EMPTY'   | 'CH-566D0B02'(!)   = ''              | 'End of Life'      | ''       | 'CH-566D0B02'    |'C0402_EOL'| '(C0402-0201)'                                                       | 'NA'       | '50V'         | '0.5PF'  | 'IO'       | 'CAP CHIP 5.6P 50V(0.5PF,C0G,0402)MUR_AEC'                     | 'CHIP0402'     | ''          | ''   | '20160803'
 '4.7PF'    | '50V'   | '0.25P'   | 'C0402'     | 'C0G'     | 'CH-476C0B02'(!)   = ''              | 'End of Life'      | ''       | 'CH-476C0B02'    |'C0402_EOL'| '(C0402-0201)'                                                       | '4.7PF'    | '50V'         | '0.25P'  | 'DISCRETE' | 'CAP CHIP 4.7P 50V(0.25P,C0G 0402)MUR_AEC'                     | 'CHIP0402'     | ''          | ''   | '20160803'
 '4.7PF'    | '50V'   | '0.25P'   | 'C0402'     | 'EMPTY'   | 'CH-476C0B02'(!)   = ''              | 'End of Life'      | ''       | 'CH-476C0B02'    |'C0402_EOL'| '(C0402-0201)'                                                       | 'NA'       | '50V'         | '0.25P'  | 'IO'       | 'CAP CHIP 4.7P 50V(0.25P,C0G 0402)MUR_AEC'                     | 'CHIP0402'     | ''          | ''   | '20160803'
 '4.7PF'    | '50V'   | '0.05P'   | 'C0402'     | 'C0G'     | 'CH-476T0B01'(!)   = ''              | ''                 | ''       | 'CH-476T0B01'    |'C0402'| '(C0402-0201)'                                                       | '4.7PF'    | '50V'         | '0.05P'  | 'DISCRETE' | 'CAP CHIP 4.7P 50V(0.05P,C0G,0402)MUR_AEC'                     | 'CHIP0402'     | ''          | ''   | '20160810'
 '4.7PF'    | '50V'   | '0.05P'   | 'C0402'     | 'EMPTY'   | 'CH-476T0B01'(!)   = ''              | ''                 | ''       | 'CH-476T0B01'    |'C0402'| '(C0402-0201)'                                                       | 'NA'       | '50V'         | '0.05P'  | 'IO'       | 'CAP CHIP 4.7P 50V(0.05P,C0G,0402)MUR_AEC'                     | 'CHIP0402'     | ''          | ''   | '20160810'
 '5.6P'     | '50V'   | '0.1P'    | 'C0402'     | 'C0G'     | 'CH-566B0B02'(!)   = ''              | ''                 | ''       | 'CH-566B0B02'    |'C0402'| '(C0402-0201)'                                                       | '5.6P'     | '50V'         | '0.1P'   | 'DISCRETE' | 'CAP CHIP 5.6P 50V(0.1P,C0G,0402)MUR_AEC'                      | 'CHIP0402'     | ''          | ''   | '20160810'
 '5.6P'     | '50V'   | '0.1P'    | 'C0402'     | 'EMPTY'   | 'CH-566B0B02'(!)   = ''              | ''                 | ''       | 'CH-566B0B02'    |'C0402'| '(C0402-0201)'                                                       | 'NA'       | '50V'         | '0.1P'   | 'IO'       | 'CAP CHIP 5.6P 50V(0.1P,C0G,0402)MUR_AEC'                      | 'CHIP0402'     | ''          | ''   | '20160810'
 '22UF'     | '4V'    | '20%'     | 'C0402'     | 'X5R'     | 'SP_CH622KM9B02_1'(!) = 'End of Design' | 'Comp-Approve'     | ''       | 'CH622KM9B02'    |'C0402_SMDC25_SM30'| '(SMC0402AW)'                                                        | '22UF'     | '4V'          | '20%'    | 'DISCRETE' | 'CAP CHIP 22UF 4V (+-20%, X5R,0402)_AMD FOOTPRINT SMDC25_SM30' | 'CHIP0402'     | ''          | ''   | '20160815'
 '22UF'     | '4V'    | '20%'     | 'C0402'     | 'EMPTY'   | 'SP_CH622KM9B02_1'(!) = 'End of Design' | 'Comp-Approve'     | ''       | 'CH622KM9B02'    |'C0402_SMDC25_SM30'| '(SMC0402AW)'                                                        | 'NA'       | '4V'          | '20%'    | 'IO'       | 'CAP CHIP 22UF 4V (+-20%, X5R,0402)_AMD FOOTPRINT SMDC25_SM30' | 'CHIP0402'     | ''          | ''   | '20160815'
 '47UF'     | '2.5V'  | '20%'     | 'C0603'     | 'X6S'     | 'CH647LME901'(!)   = 'End of Design' | 'Comp-Approve'     | ''       | 'CH647LME901'    |'C0603'| '(SMC0603AW)'                                                        | '47UF'     | '2.5V'        | '20%'    | 'DISCRETE' | 'CAP CHIP 47U 2.5V(+-20%,X6S,0603)'                            | 'CHIP0603'     | ''          | ''   | '20160823'
 '47UF'     | '2.5V'  | '20%'     | 'C0603'     | 'EMPTY'   | 'CH647LME901'(!)   = 'End of Design' | 'Comp-Approve'     | ''       | 'CH647LME901'    |'C0603'| '(SMC0603AW)'                                                        | 'NA'       | '2.5V'        | '20%'    | 'IO'       | 'CAP CHIP 47U 2.5V(+-20%,X6S,0603)'                            | 'CHIP0603'     | ''          | ''   | '20160823'
 '0.1UF'    | '16V'   | '10%'     | 'C0402'     | 'X7R'     | 'SP_CH4103K1B08_3'(!) = ''              | ''                 | ''       | 'CH4103K1B08'    |'C0402_SMDC25_SM30'| '(SMC0402AW)'                                                        | '0.1UF'    | '16V'         | '10%'    | 'DISCRETE' | 'CAP CHIP 0.1U 16V(10%.X7R.0402)_AMD FOOTPRINT SMDC25_SM30'    | 'CHIP0402'     | ''          | ''   | '20160829'
 '0.1UF'    | '16V'   | '10%'     | 'C0402'     | 'EMPTY'   | 'SP_CH4103K1B08_3'(!) = ''              | ''                 | ''       | 'CH4103K1B08'    |'C0402_SMDC25_SM30'| '(SMC0402AW)'                                                        | 'NA'       | '16V'         | '10%'    | 'IO'       | 'CAP CHIP 0.1U 16V(10%.X7R.0402)_AMD FOOTPRINT SMDC25_SM30'    | 'CHIP0402'     | ''          | ''   | '20160829'
 '0.68UF'   | '16V'   | '10%'     | 'C0603'     | 'X7R'     | 'CH4683K1901'(!)   = ''              | ''                 | ''       | 'CH4683K1901'    |'C0603'| '(SMC0603AW)'                                                        | '0.68UF'   | '16V'         | '10%'    | 'DISCRETE' | 'CAP CHIP 0.68U 16V(+-10%,X7R,0603)WTC'                        | 'CHIP0603'     | ''          | ''   | '20160830'
 '0.68UF'   | '16V'   | '10%'     | 'C0603'     | 'EMPTY'   | 'CH4683K1901'(!)   = ''              | ''                 | ''       | 'CH4683K1901'    |'C0603'| '(SMC0603AW)'                                                        | 'NA'       | '16V'         | '10%'    | 'IO'       | 'CAP CHIP 0.68U 16V(+-10%,X7R,0603)WTC'                        | 'CHIP0603'     | ''          | ''   | '20160830'
 '4.7UF'    | '25V'   | '10%'     | 'C0603'     | 'X6S'     | 'CH5474KE906'(!)   = ''              | ''                 | ''       | 'CH5474KE906'    |'C0603'| '(SMC0603AW)'                                                        | '4.7UF'    | '25V'         | '10%'    | 'DISCRETE' | 'CAP CHIP 4.7UF 25V(+-10%,X6S,0603)'                           | 'CHIP0603'     | ''          | ''   | '20160830'
 '4.7UF'    | '25V'   | '10%'     | 'C0603'     | 'EMPTY'   | 'CH5474KE906'(!)   = ''              | ''                 | ''       | 'CH5474KE906'    |'C0603'| '(SMC0603AW)'                                                        | 'NA'       | '25V'         | '10%'    | 'IO'       | 'CAP CHIP 4.7UF 25V(+-10%,X6S,0603)'                           | 'CHIP0603'     | ''          | ''   | '20160830'
 '33PF'     | '50V'   | '1%'      | 'C0402'     | 'C0G'     | 'CH0336F0B00'(!)   = ''              | ''                 | ''       | 'CH0336F0B00'    |'C0402'| '(C0402-0201)'                                                       | '33PF'     | '50V'         | '1%'     | 'DISCRETE' | 'CAP CHIP 33P 50V(+-1%,C0G,0402)'                              | 'CHIP0402'     | ''          | ''   | '20160906'
 '33PF'     | '50V'   | '1%'      | 'C0402'     | 'EMPTY'   | 'CH0336F0B00'(!)   = ''              | ''                 | ''       | 'CH0336F0B00'    |'C0402'| '(C0402-0201)'                                                       | 'NA'       | '50V'         | '1%'     | 'IO'       | 'CAP CHIP 33P 50V(+-1%,C0G,0402)'                              | 'CHIP0402'     | ''          | ''   | '20160906'
 '22UF'     | '6.3V'  | '20%'     | 'C0402'     | 'X5R'     | 'CH6221M9B01'(!)   = 'End of Design' | 'Comp-Approve'     | ''       | 'CH6221M9B01'    |'C0402'| '(C0402_OCTAGONXA,C0402-0201)'                                       | '22UF'     | '6.3V'        | '20%'    | 'DISCRETE' | 'CAP CHIP 22U 6.3V(+-20%,X5R,0402)'                            | 'CHIP0402'     | ''          | ''   | '20160906'
 '22UF'     | '6.3V'  | '20%'     | 'C0402'     | 'EMPTY'   | 'CH6221M9B01'(!)   = 'End of Design' | 'Comp-Approve'     | ''       | 'CH6221M9B01'    |'C0402'| '(C0402_OCTAGONXA,C0402-0201)'                                       | 'NA'       | '6.3V'        | '20%'    | 'IO'       | 'CAP CHIP 22U 6.3V(+-20%,X5R,0402)'                            | 'CHIP0402'     | ''          | ''   | '20160906'
 '22UF'     | '6.3V'  | '20%'     | 'C0402'     | 'X5R'     | 'SP_CH6221M9B01'(!) = ''              | ''                 | ''       | 'SP_CH6221M9B01' |'C0402_SMDC25_SM30'| '(SMC0402AW)'                                                        | '22UF'     | '6.3V'        | '20%'    | 'DISCRETE' | 'CAP CHIP 22U 6.3V(+-20%,X5R,0402)_AMD FOOTPRINT SMDC25_SM30'  | 'CHIP0402'     | ''          | ''   | '20160906'
 '22UF'     | '6.3V'  | '20%'     | 'C0402'     | 'EMPTY'   | 'SP_CH6221M9B01'(!) = ''              | ''                 | ''       | 'SP_CH6221M9B01' |'C0402_SMDC25_SM30'| '(SMC0402AW)'                                                        | 'NA'       | '6.3V'        | '20%'    | 'IO'       | 'CAP CHIP 22U 6.3V(+-20%,X5R,0402)_AMD FOOTPRINT SMDC25_SM30'  | 'CHIP0402'     | ''          | ''   | '20160906'
 '10UF'     | '4V'    | '20%'     | 'C0402'     | 'X5R'     | 'CH610KM9B00'(!)   = 'End of Design' | 'Comp-Approve'     | ''       | 'CH610KM9B00'    |'C0402'| '(C0402-0201)'                                                       | '10UF'     | '4V'          | '20%'    | 'DISCRETE' | 'CAP CHIP 10UF 4V(+-20%,X5R,0402)'                             | 'CHIP0402'     | ''          | ''   | '20161017'
 '10UF'     | '4V'    | '20%'     | 'C0402'     | 'EMPTY'   | 'CH610KM9B00'(!)   = 'End of Design' | 'Comp-Approve'     | ''       | 'CH610KM9B00'    |'C0402'| '(C0402-0201)'                                                       | 'NA'       | '4V'          | '20%'    | 'IO'       | 'CAP CHIP 10UF 4V(+-20%,X5R,0402)'                             | 'CHIP0402'     | ''          | ''   | '20161017'
 '10UF'     | '2.5V'  | '20%'     | 'C0402'     | 'X6S'     | 'CH610LMEB00'(!)   = ''              | ''                 | ''       | 'CH610LMEB00'    |'C0402'| '(C0402-0201)'                                                       | '10UF'     | '2.5V'        | '20%'    | 'DISCRETE' | 'CAP CHIP 10U 2.5V(+-20%,X6S,0402)MUR_AEC'                     | 'CHIP0402'     | ''          | ''   | '20161017'
 '10UF'     | '2.5V'  | '20%'     | 'C0402'     | 'EMPTY'   | 'CH610LMEB00'(!)   = ''              | ''                 | ''       | 'CH610LMEB00'    |'C0402'| '(C0402-0201)'                                                       | 'NA'       | '2.5V'        | '20%'    | 'IO'       | 'CAP CHIP 10U 2.5V(+-20%,X6S,0402)MUR_AEC'                     | 'CHIP0402'     | ''          | ''   | '20161017'
 '0.01UF'   | '16V'   | '10%'     | 'C0402'     | 'X7R'     | 'CH3103K1B24'(!)   = 'End of Design' | 'P/N Release'      | ''       | 'CH3103K1B24'    |'C0402'| '(C0402-0201)'                                                       | '0.01UF'   | '16V'         | '10%'    | 'DISCRETE' | 'CAP CHIP 0.01U 16V(10%,X7R,0402)MUR_AEC'                      | 'CHIP0402'     | ''          | ''   | '20161017'
 '0.01UF'   | '16V'   | '10%'     | 'C0402'     | 'EMPTY'   | 'CH3103K1B24'(!)   = 'End of Design' | 'P/N Release'      | ''       | 'CH3103K1B24'    |'C0402'| '(C0402-0201)'                                                       | 'NA'       | '16V'         | '10%'    | 'IO'       | 'CAP CHIP 0.01U 16V(10%,X7R,0402)MUR_AEC'                      | 'CHIP0402'     | ''          | ''   | '20161017'
 '6.8P'     | '50V'   | '0.05P'   | 'C0402'     | 'C0G'     | 'CH-686T0B01'(!)   = ''              | ''                 | ''       | 'CH-686T0B01'    |'C0402'| '(C0402-0201)'                                                       | '6.8P'     | '50V'         | '6.8P'   | 'DISCRETE' | 'CAP CHIP 6.8P 50V(0.05P,C0G,0402)MUR_AEC'                     | 'CHIP0402'     | ''          | ''   | '20161227'
 '6.8P'     | '50V'   | '0.05P'   | 'C0402'     | 'EMPTY'   | 'CH-686T0B01'(!)   = ''              | ''                 | ''       | 'CH-686T0B01'    |'C0402'| '(C0402-0201)'                                                       | 'NA'       | '50V'         | '6.8P'   | 'IO'       | 'CAP CHIP 6.8P 50V(0.05P,C0G,0402)MUR_AEC'                     | 'CHIP0402'     | ''          | ''   | '20161227'
 '2.2UF'    | '6.3V'  | '20%'     | 'C0402'     | 'X6S'     | 'CH5221MEB00'(!)   = ''              | ''                 | ''       | 'CH5221MEB00'    |'C0402'| '(C0402_OCTAGONXA,C0402-0201)'                                       | '2.2UF'    | '6.3V'        | '20%'    | 'DISCRETE' | 'CAP CHIP 2.2U 6.3V(+-20%,X6S,0402)'                           | 'CHIP0402'     | ''          | ''   | '20170330'
 '2.2UF'    | '6.3V'  | '20%'     | 'C0402'     | 'EMPTY'   | 'CH5221MEB00'(!)   = ''              | ''                 | ''       | 'CH5221MEB00'    |'C0402'| '(C0402_OCTAGONXA,C0402-0201)'                                       | 'NA'       | '6.3V'        | '20%'    | 'IO'       | 'CAP CHIP 2.2U 6.3V(+-20%,X6S,0402)'                           | 'CHIP0402'     | ''          | ''   | '20170330'
 '10UF'     | '6.3V'  | '20%'     | 'C0402'     | 'X6S'     | 'CH6101MEB01'(!)   = ''              | ''                 | ''       | 'CH6101MEB01'    |'C0402'| '(C0402_OCTAGONXA,C0402-0201)'                                       | '10UF'     | '6.3V'        | '20%'    | 'DISCRETE' | 'CAP CHIP 10UF 6.3V(+-20%,X6S,0402)'                           | 'CHIP0402'     | ''          | ''   | '20170330'
 '10UF'     | '6.3V'  | '20%'     | 'C0402'     | 'EMPTY'   | 'CH6101MEB01'(!)   = ''              | ''                 | ''       | 'CH6101MEB01'    |'C0402'| '(C0402_OCTAGONXA,C0402-0201)'                                       | 'NA'       | '6.3V'        | '20%'    | 'IO'       | 'CAP CHIP 10UF 6.3V(+-20%,X6S,0402)'                           | 'CHIP0402'     | ''          | ''   | '20170330'
 '47UF'     | '10V'   | '20%'     | 'C0805'     | 'X5R'     | 'CH6472M9A00'(!)   = 'End of Design' | 'Comp-Approve'     | ''       | 'CH6472M9A00'    |'C0805_H61'| '(SMC0805AW)'                                                        | '47UF'     | '10V'         | '20%'    | 'DISCRETE' | 'CAP CHIP 47U 10V(+-20%,X5R,0805)H1.25'                        | 'CHIP0805'     | ''          | ''   | '20170331'
 '47UF'     | '10V'   | '20%'     | 'C0805'     | 'EMPTY'   | 'CH6472M9A00'(!)   = 'End of Design' | 'Comp-Approve'     | ''       | 'CH6472M9A00'    |'C0805_H61'| '(SMC0805AW)'                                                        | 'NA'       | '10V'         | '20%'    | 'IO'       | 'CAP CHIP 47U 10V(+-20%,X5R,0805)H1.25'                        | 'CHIP0805'     | ''          | ''   | '20170331'
 '1000PF'   | '16V'   | '10%'     | 'C0201'     | 'X7R'     | 'CH2103K1E10'(!)   = ''              | ''                 | ''       | 'CH2103K1E10'    |'C0201'| '(SMC0201AW)'                                                        | '1000PF'   | '16V'         | '10%'    | 'DISCRETE' | 'CAP CHIP 1000P 16V(10%,X7R,0201)SAM'                          | 'CHIP0201'     | ''          | ''   | '20170427'
 '1000PF'   | '16V'   | '10%'     | 'C0201'     | 'EMPTY'   | 'CH2103K1E10'(!)   = ''              | ''                 | ''       | 'CH2103K1E10'    |'C0201'| '(SMC0201AW)'                                                        | 'NA'       | '16V'         | '10%'    | 'IO'       | 'CAP CHIP 1000P 16V(10%,X7R,0201)SAM'                          | 'CHIP0201'     | ''          | ''   | '20170427'
 '1000PF'   | '16V'   | '10%'     | 'C0201'     | 'X7R'     | 'CH2103K1E11'(!)   = ''              | ''                 | ''       | 'CH2103K1E11'    |'C0201'| '(SMC0201AW)'                                                        | '1000PF'   | '16V'         | '10%'    | 'DISCRETE' | 'CAP CHIP 1000P 16V(10%,X7R,0201)WTC'                          | 'CHIP0201'     | ''          | ''   | '20170427'
 '1000PF'   | '16V'   | '10%'     | 'C0201'     | 'EMPTY'   | 'CH2103K1E11'(!)   = ''              | ''                 | ''       | 'CH2103K1E11'    |'C0201'| '(SMC0201AW)'                                                        | 'NA'       | '16V'         | '10%'    | 'IO'       | 'CAP CHIP 1000P 16V(10%,X7R,0201)WTC'                          | 'CHIP0201'     | ''          | ''   | '20170427'
 '1UF'      | '4V'    | '20%'     | 'C0201'     | 'X6S'     | 'CH510KMEE04'(!)   = ''              | ''                 | ''       | 'CH510KMEE04'    |'C0201'| '(SMC0201AW)'                                                        | '1UF'      | '4V'          | '20%'    | 'DISCRETE' | 'CAP CHIP 1U 4V(+-20%,X6S,0201)TAY'                            | 'CHIP0201'     | ''          | ''   | '20170427'
 '1UF'      | '4V'    | '20%'     | 'C0201'     | 'EMPTY'   | 'CH510KMEE04'(!)   = ''              | ''                 | ''       | 'CH510KMEE04'    |'C0201'| '(SMC0201AW)'                                                        | 'NA'       | '4V'          | '20%'    | 'IO'       | 'CAP CHIP 1U 4V(+-20%,X6S,0201)TAY'                            | 'CHIP0201'     | ''          | ''   | '20170427'
 '1UF'      | '4V'    | '20%'     | 'C0201'     | 'X6S'     | 'CH510KMEE03'(!)   = ''              | ''                 | ''       | 'CH510KMEE03'    |'C0201'| '(SMC0201AW)'                                                        | '1UF'      | '4V'          | '20%'    | 'DISCRETE' | 'CAP CHIP 1U 4V(+-20%,X6S,0201)MUR'                            | 'CHIP0201'     | ''          | ''   | '20170427'
 '1UF'      | '4V'    | '20%'     | 'C0201'     | 'EMPTY'   | 'CH510KMEE03'(!)   = ''              | ''                 | ''       | 'CH510KMEE03'    |'C0201'| '(SMC0201AW)'                                                        | 'NA'       | '4V'          | '20%'    | 'IO'       | 'CAP CHIP 1U 4V(+-20%,X6S,0201)MUR'                            | 'CHIP0201'     | ''          | ''   | '20170427'
 '0.1UF'    | '6.3V'  | '10%'     | 'C0201'     | 'X6S'     | 'CH4101KEE03'(!)   = ''              | ''                 | ''       | 'CH4101KEE03'    |'C0201'| '(SMC0201AW)'                                                        | '0.1UF'    | '6.3V'        | '10%'    | 'DISCRETE' | 'CAP CHIP 0.1UF 6.3V(10%,X6S,0201)TAY'                         | 'CHIP0201'     | ''          | ''   | '20170427'
 '0.1UF'    | '6.3V'  | '10%'     | 'C0201'     | 'EMPTY'   | 'CH4101KEE03'(!)   = ''              | ''                 | ''       | 'CH4101KEE03'    |'C0201'| '(SMC0201AW)'                                                        | 'NA'       | '6.3V'        | '10%'    | 'IO'       | 'CAP CHIP 0.1UF 6.3V(10%,X6S,0201)TAY'                         | 'CHIP0201'     | ''          | ''   | '20170427'
 '0.1UF'    | '6.3V'  | '10%'     | 'C0201'     | 'X6S'     | 'CH4101KEE02'(!)   = ''              | ''                 | ''       | 'CH4101KEE02'    |'C0201'| '(SMC0201AW)'                                                        | '0.1UF'    | '6.3V'        | '10%'    | 'DISCRETE' | 'CAP CHIP 0.1UF 6.3V(10%,X6S,0201)SAM'                         | 'CHIP0201'     | ''          | ''   | '20170427'
 '0.1UF'    | '6.3V'  | '10%'     | 'C0201'     | 'EMPTY'   | 'CH4101KEE02'(!)   = ''              | ''                 | ''       | 'CH4101KEE02'    |'C0201'| '(SMC0201AW)'                                                        | 'NA'       | '6.3V'        | '10%'    | 'IO'       | 'CAP CHIP 0.1UF 6.3V(10%,X6S,0201)SAM'                         | 'CHIP0201'     | ''          | ''   | '20170427'
 '0.01UF'   | '16V'   | '10%'     | 'C0201'     | 'X7R'     | 'CH3103K1E02'(!)   = ''              | ''                 | ''       | 'CH3103K1E02'    |'C0201'| '(SMC0201AW)'                                                        | '0.01UF'   | '16V'         | '10%'    | 'DISCRETE' | 'CAP CHIP 0.01U 16V(+-10%,X7R,0201)YGO'                        | 'CHIP0201'     | ''          | ''   | '20170427'
 '0.01UF'   | '16V'   | '10%'     | 'C0201'     | 'EMPTY'   | 'CH3103K1E02'(!)   = ''              | ''                 | ''       | 'CH3103K1E02'    |'C0201'| '(SMC0201AW)'                                                        | 'NA'       | '16V'         | '10%'    | 'IO'       | 'CAP CHIP 0.01U 16V(+-10%,X7R,0201)YGO'                        | 'CHIP0201'     | ''          | ''   | '20170427'
 '2200PF'   | '50V'   | '10%'     | 'C0402'     | 'X7R'     | 'CH2226K1B15'(!)   = ''              | ''                 | ''       | 'CH2226K1B15'    |'C0402'| '(C0402-0201)'                                                       | '2200PF'   | '50V'         | '10%'    | 'DISCRETE' | 'CAP CHIP 2200P 50V(+-10%,X7R,0402)SAM'                        | 'CHIP0402'     | ''          | ''   | '20170427'
 '2200PF'   | '50V'   | '10%'     | 'C0402'     | 'EMPTY'   | 'CH2226K1B15'(!)   = ''              | ''                 | ''       | 'CH2226K1B15'    |'C0402'| '(C0402-0201)'                                                       | 'NA'       | '50V'         | '10%'    | 'IO'       | 'CAP CHIP 2200P 50V(+-10%,X7R,0402)SAM'                        | 'CHIP0402'     | ''          | ''   | '20170427'
 '100PF'    | '50V'   | '5%'      | 'C0402'     | 'NPO'     | 'CH1106J0B23'(!)   = ''              | ''                 | ''       | 'CH1106J0B23'    |'C0402'| '(C0402-0201)'                                                       | '100PF'    | '50V'         | '5%'     | 'DISCRETE' | 'CAP CHIP 100P 50V(+-5%,NPO,0402)YGO'                          | 'CHIP0402'     | ''          | ''   | '20170427'
 '100PF'    | '50V'   | '5%'      | 'C0402'     | 'EMPTY'   | 'CH1106J0B23'(!)   = ''              | ''                 | ''       | 'CH1106J0B23'    |'C0402'| '(C0402-0201)'                                                       | 'NA'       | '50V'         | '5%'     | 'IO'       | 'CAP CHIP 100P 50V(+-5%,NPO,0402)YGO'                          | 'CHIP0402'     | ''          | ''   | '20170427'
 '100PF'    | '50V'   | '5%'      | 'C0402'     | 'NPO'     | 'CH1106J0B22'(!)   = ''              | ''                 | ''       | 'CH1106J0B22'    |'C0402'| '(C0402-0201)'                                                       | '100PF'    | '50V'         | '5%'     | 'DISCRETE' | 'CAP CHIP 100P 50V(+-5%,NPO,0402)WTC'                          | 'CHIP0402'     | ''          | ''   | '20170427'
 '100PF'    | '50V'   | '5%'      | 'C0402'     | 'EMPTY'   | 'CH1106J0B22'(!)   = ''              | ''                 | ''       | 'CH1106J0B22'    |'C0402'| '(C0402-0201)'                                                       | 'NA'       | '50V'         | '5%'     | 'IO'       | 'CAP CHIP 100P 50V(+-5%,NPO,0402)WTC'                          | 'CHIP0402'     | ''          | ''   | '20170427'
 '1000PF'   | '50V'   | '5%'      | 'C0402'     | 'X7R'     | 'CH2106J1B08'(!)   = ''              | ''                 | ''       | 'CH2106J1B08'    |'C0402'| '(C0402-0201)'                                                       | '1000PF'   | '50V'         | '5%'     | 'DISCRETE' | 'CAP CHIP 1000P 50V(+-5%,X7R,0402)WTC'                         | 'CHIP0402'     | ''          | ''   | '20170427'
 '1000PF'   | '50V'   | '5%'      | 'C0402'     | 'EMPTY'   | 'CH2106J1B08'(!)   = ''              | ''                 | ''       | 'CH2106J1B08'    |'C0402'| '(C0402-0201)'                                                       | 'NA'       | '50V'         | '5%'     | 'IO'       | 'CAP CHIP 1000P 50V(+-5%,X7R,0402)WTC'                         | 'CHIP0402'     | ''          | ''   | '20170427'
 '1000PF'   | '50V'   | '5%'      | 'C0402'     | 'X7R'     | 'CH2106J1B05'(!)   = ''              | ''                 | ''       | 'CH2106J1B05'    |'C0402'| '(C0402-0201)'                                                       | '1000PF'   | '50V'         | '5%'     | 'DISCRETE' | 'CAP CHIP 1000P 50V(+-5%,X7R,0402)SAM'                         | 'CHIP0402'     | ''          | ''   | '20170427'
 '1000PF'   | '50V'   | '5%'      | 'C0402'     | 'EMPTY'   | 'CH2106J1B05'(!)   = ''              | ''                 | ''       | 'CH2106J1B05'    |'C0402'| '(C0402-0201)'                                                       | 'NA'       | '50V'         | '5%'     | 'IO'       | 'CAP CHIP 1000P 50V(+-5%,X7R,0402)SAM'                         | 'CHIP0402'     | ''          | ''   | '20170427'
 '0.01UF'   | '50V'   | '10%'     | 'C0402'     | 'X7R'     | 'CH3106K1B11'(!)   = ''              | ''                 | ''       | 'CH3106K1B11'    |'C0402'| '(C0402-0201)'                                                       | '0.01UF'   | '50V'         | '10%'    | 'DISCRETE' | 'CAP CHIP 0.01U 50V(+-10%,X7R,0402)WTC'                        | 'CHIP0402'     | ''          | ''   | '20170427'
 '0.01UF'   | '50V'   | '10%'     | 'C0402'     | 'EMPTY'   | 'CH3106K1B11'(!)   = ''              | ''                 | ''       | 'CH3106K1B11'    |'C0402'| '(C0402-0201)'                                                       | 'NA'       | '50V'         | '10%'    | 'IO'       | 'CAP CHIP 0.01U 50V(+-10%,X7R,0402)WTC'                        | 'CHIP0402'     | ''          | ''   | '20170427'
 '0.01UF'   | '50V'   | '10%'     | 'C0402'     | 'X7R'     | 'CH3106K1B06'(!)   = ''              | ''                 | ''       | 'CH3106K1B06'    |'C0402'| '(C0402-0201)'                                                       | '0.01UF'   | '50V'         | '10%'    | 'DISCRETE' | 'CAP CHIP 0.01U 50V(+-10%,X7R,0402)SAM'                        | 'CHIP0402'     | ''          | ''   | '20170427'
 '0.01UF'   | '50V'   | '10%'     | 'C0402'     | 'EMPTY'   | 'CH3106K1B06'(!)   = ''              | ''                 | ''       | 'CH3106K1B06'    |'C0402'| '(C0402-0201)'                                                       | 'NA'       | '50V'         | '10%'    | 'IO'       | 'CAP CHIP 0.01U 50V(+-10%,X7R,0402)SAM'                        | 'CHIP0402'     | ''          | ''   | '20170427'
 '0.047UF'  | '25V'   | '10%'     | 'C0402'     | 'X7R'     | 'CH3474K1B09'(!)   = ''              | ''                 | ''       | 'CH3474K1B09'    |'C0402'| '(C0402-0201)'                                                       | '0.047UF'  | '25V'         | '10%'    | 'DISCRETE' | 'CAP CHIP 0.047U 25V(+-10%,X7R,0402)WTC'                       | 'CHIP0402'     | ''          | ''   | '20170427'
 '0.047UF'  | '25V'   | '10%'     | 'C0402'     | 'EMPTY'   | 'CH3474K1B09'(!)   = ''              | ''                 | ''       | 'CH3474K1B09'    |'C0402'| '(C0402-0201)'                                                       | 'NA'       | '25V'         | '10%'    | 'IO'       | 'CAP CHIP 0.047U 25V(+-10%,X7R,0402)WTC'                       | 'CHIP0402'     | ''          | ''   | '20170427'
 '0.1UF'    | '25V'   | '10%'     | 'C0402'     | 'X7R'     | 'CH4104K9B08'(!)   = 'End of Design' | 'Comp-Approve'     | ''       | 'CH4104K9B08'    |'C0402'| '(C0402-0201)'                                                       | '0.1UF'    | '25V'         | '10%'    | 'DISCRETE' | 'CAP CHIP 0.1U 25V(+-10%,X7R,0402)SAM'                         | 'CHIP0402'     | ''          | ''   | '20170427'
 '0.1UF'    | '25V'   | '10%'     | 'C0402'     | 'EMPTY'   | 'CH4104K9B08'(!)   = 'End of Design' | 'Comp-Approve'     | ''       | 'CH4104K9B08'    |'C0402'| '(C0402-0201)'                                                       | 'NA'       | '25V'         | '10%'    | 'IO'       | 'CAP CHIP 0.1U 25V(+-10%,X7R,0402)SAM'                         | 'CHIP0402'     | ''          | ''   | '20170427'
 '0.1UF'    | '25V'   | '10%'     | 'C0402'     | 'X7R'     | 'CH4104K1B09'(!)   = ''              | ''                 | ''       | 'CH4104K1B09'    |'C0402'| '(C0402-0201)'                                                       | '0.1UF'    | '25V'         | '10%'    | 'DISCRETE' | 'CAP CHIP 0.1U 25V(+-10%,X7R,0402)WTC'                         | 'CHIP0402'     | ''          | ''   | '20170427'
 '0.1UF'    | '25V'   | '10%'     | 'C0402'     | 'EMPTY'   | 'CH4104K1B09'(!)   = ''              | ''                 | ''       | 'CH4104K1B09'    |'C0402'| '(C0402-0201)'                                                       | 'NA'       | '25V'         | '10%'    | 'IO'       | 'CAP CHIP 0.1U 25V(+-10%,X7R,0402)WTC'                         | 'CHIP0402'     | ''          | ''   | '20170427'
 '1UF'      | '6.3V'  | '10%'     | 'C0402'     | 'X5R'     | 'CH5101K9B23'(!)   = ''              | ''                 | ''       | 'CH5101K9B23'    |'C0402'| '(C0402-0201)'                                                       | '1UF'      | '6.3V'        | '10%'    | 'DISCRETE' | 'CAP CHIP 1U 6.3V(+-10%,X5R,0402)SAM'                          | 'CHIP0402'     | ''          | ''   | '20170427'
 '1UF'      | '6.3V'  | '10%'     | 'C0402'     | 'EMPTY'   | 'CH5101K9B23'(!)   = ''              | ''                 | ''       | 'CH5101K9B23'    |'C0402'| '(C0402-0201)'                                                       | 'NA'       | '6.3V'        | '10%'    | 'IO'       | 'CAP CHIP 1U 6.3V(+-10%,X5R,0402)SAM'                          | 'CHIP0402'     | ''          | ''   | '20170427'
 '1UF'      | '6.3V'  | '10%'     | 'C0402'     | 'X5R'     | 'CH5101K9B17'(!)   = ''              | ''                 | ''       | 'CH5101K9B17'    |'C0402'| '(C0402-0201)'                                                       | '1UF'      | '6.3V'        | '10%'    | 'DISCRETE' | 'CAP CHIP 1U 6.3V(+-10%,X5R,0402)WTC'                          | 'CHIP0402'     | ''          | ''   | '20170427'
 '1UF'      | '6.3V'  | '10%'     | 'C0402'     | 'EMPTY'   | 'CH5101K9B17'(!)   = ''              | ''                 | ''       | 'CH5101K9B17'    |'C0402'| '(C0402-0201)'                                                       | 'NA'       | '6.3V'        | '10%'    | 'IO'       | 'CAP CHIP 1U 6.3V(+-10%,X5R,0402)WTC'                          | 'CHIP0402'     | ''          | ''   | '20170427'
 '1UF'      | '6.3V'  | '10%'     | 'C0402'     | 'X6S'     | 'CH5101KEB03'(!)   = ''              | ''                 | ''       | 'CH5101KEB03'    |'C0402'| '(C0402-0201)'                                                       | '1UF'      | '6.3V'        | '10%'    | 'DISCRETE' | 'CAP CHIP 1U 6.3V(+-10%,X6S,0402)SAM'                          | 'CHIP0402'     | ''          | ''   | '20170427'
 '1UF'      | '6.3V'  | '10%'     | 'C0402'     | 'EMPTY'   | 'CH5101KEB03'(!)   = ''              | ''                 | ''       | 'CH5101KEB03'    |'C0402'| '(C0402-0201)'                                                       | 'NA'       | '6.3V'        | '10%'    | 'IO'       | 'CAP CHIP 1U 6.3V(+-10%,X6S,0402)SAM'                          | 'CHIP0402'     | ''          | ''   | '20170427'
 '1UF'      | '6.3V'  | '10%'     | 'C0402'     | 'X6S'     | 'CH5101KEB02'(!)   = 'End of Design' | 'Comp-Approve'     | ''       | 'CH5101KEB02'    |'C0402'| '(C0402_OCTAGONXA,C0402-0201)'                                       | '1UF'      | '6.3V'        | '10%'    | 'DISCRETE' | 'CAP CHIP 1U 6.3V(+-10%,X6S,0402)MUR'                          | 'CHIP0402'     | ''          | ''   | '20170427'
 '1UF'      | '6.3V'  | '10%'     | 'C0402'     | 'EMPTY'   | 'CH5101KEB02'(!)   = 'End of Design' | 'Comp-Approve'     | ''       | 'CH5101KEB02'    |'C0402'| '(C0402_OCTAGONXA,C0402-0201)'                                       | 'NA'       | '6.3V'        | '10%'    | 'IO'       | 'CAP CHIP 1U 6.3V(+-10%,X6S,0402)MUR'                          | 'CHIP0402'     | ''          | ''   | '20170427'
 '1UF'      | '25V'   | '10%'     | 'C0402'     | 'X6S'     | 'CH5104KEB07'(!)   = 'End of Design' | 'Comp-Approve'     | ''       | 'CH5104KEB07'    |'C0402'| '(C0402-0201)'                                                       | '1UF'      | '25V'         | '10%'    | 'DISCRETE' | 'CAP CHIP 1UF 25V(+-10%,X6S,0402)WTC'                          | 'CHIP0402'     | ''          | ''   | '20170427'
 '1UF'      | '25V'   | '10%'     | 'C0402'     | 'EMPTY'   | 'CH5104KEB07'(!)   = 'End of Design' | 'Comp-Approve'     | ''       | 'CH5104KEB07'    |'C0402'| '(C0402-0201)'                                                       | 'NA'       | '25V'         | '10%'    | 'IO'       | 'CAP CHIP 1UF 25V(+-10%,X6S,0402)WTC'                          | 'CHIP0402'     | ''          | ''   | '20170427'
 '10UF'     | '16V'   | '20%'     | 'C0603'     | 'X6S'     | 'CH6103ME905'(!)   = ''              | ''                 | ''       | 'CH6103ME905'    |'C0603'| '(SMC0603AW)'                                                        | '10UF'     | '16V'         | '20%'    | 'DISCRETE' | 'CAP CHIP 10U 16V(+-20%,X6S,0603)WTC'                          | 'CHIP0603'     | ''          | ''   | '20170426'
 '10UF'     | '16V'   | '20%'     | 'C0603'     | 'EMPTY'   | 'CH6103ME905'(!)   = ''              | ''                 | ''       | 'CH6103ME905'    |'C0603'| '(SMC0603AW)'                                                        | 'NA'       | '16V'         | '20%'    | 'IO'       | 'CAP CHIP 10U 16V(+-20%,X6S,0603)WTC'                          | 'CHIP0603'     | ''          | ''   | '20170426'
 '10UF'     | '16V'   | '20%'     | 'C0603'     | 'X6S'     | 'CH6103ME904'(!)   = ''              | ''                 | ''       | 'CH6103ME904'    |'C0603'| '(SMC0603AW)'                                                        | '10UF'     | '16V'         | '20%'    | 'DISCRETE' | 'CAP CHIP 10UF 16V(+-20%,X6S,0603)MUR'                         | 'CHIP0603'     | ''          | ''   | '20170426'
 '10UF'     | '16V'   | '20%'     | 'C0603'     | 'EMPTY'   | 'CH6103ME904'(!)   = ''              | ''                 | ''       | 'CH6103ME904'    |'C0603'| '(SMC0603AW)'                                                        | 'NA'       | '16V'         | '20%'    | 'IO'       | 'CAP CHIP 10UF 16V(+-20%,X6S,0603)MUR'                         | 'CHIP0603'     | ''          | ''   | '20170426'
 '10UF'     | '6.3V'  | '20%'     | 'C0603'     | 'X6S'     | 'CH6101ME904'(!)   = ''              | ''                 | ''       | 'CH6101ME904'    |'C0603'| '(SMC0603AW)'                                                        | '10UF'     | '6.3V'        | '20%'    | 'DISCRETE' | 'CAP CHIP 10U 6.3V(+-20%,X6S,0603)SAM'                         | 'CHIP0603'     | ''          | ''   | '20170426'
 '10UF'     | '6.3V'  | '20%'     | 'C0603'     | 'EMPTY'   | 'CH6101ME904'(!)   = ''              | ''                 | ''       | 'CH6101ME904'    |'C0603'| '(SMC0603AW)'                                                        | 'NA'       | '6.3V'        | '20%'    | 'IO'       | 'CAP CHIP 10U 6.3V(+-20%,X6S,0603)SAM'                         | 'CHIP0603'     | ''          | ''   | '20170426'
 '4.7UF'    | '6.3V'  | '10%'     | 'C0603'     | 'X6S'     | 'CH5471KE904'(!)   = 'End of Design' | 'Comp-Approve'     | ''       | 'CH5471KE904'    |'C0603'| '(SMC0603AW)'                                                        | '4.7UF'    | '6.3V'        | '10%'    | 'DISCRETE' | 'CAP CHIP 4.7U 6.3V(+-10%,X6S,0603)SAM'                        | 'CHIP0603'     | ''          | ''   | '20170426'
 '4.7UF'    | '6.3V'  | '10%'     | 'C0603'     | 'EMPTY'   | 'CH5471KE904'(!)   = 'End of Design' | 'Comp-Approve'     | ''       | 'CH5471KE904'    |'C0603'| '(SMC0603AW)'                                                        | 'NA'       | '6.3V'        | '10%'    | 'IO'       | 'CAP CHIP 4.7U 6.3V(+-10%,X6S,0603)SAM'                        | 'CHIP0603'     | ''          | ''   | '20170426'
 '0.033UF'  | '50V'   | '10%'     | 'C0603'     | 'X7R'     | 'CH3336K1906'(!)   = 'End of Design' | 'Comp-Approve'     | ''       | 'CH3336K1906'    |'C0603'| '(SMC0603AW)'                                                        | '0.033UF'  | '50V'         | '10%'    | 'DISCRETE' | 'CAP CHIP 0.033U 50V(+-10%,X7R,0603)WTC'                       | 'CHIP0603'     | ''          | ''   | '20170426'
 '0.033UF'  | '50V'   | '10%'     | 'C0603'     | 'EMPTY'   | 'CH3336K1906'(!)   = 'End of Design' | 'Comp-Approve'     | ''       | 'CH3336K1906'    |'C0603'| '(SMC0603AW)'                                                        | 'NA'       | '50V'         | '10%'    | 'IO'       | 'CAP CHIP 0.033U 50V(+-10%,X7R,0603)WTC'                       | 'CHIP0603'     | ''          | ''   | '20170426'
 '22UF'     | '6.3V'  | '20%'     | 'C0603'     | 'X6S'     | 'CH6221ME902'(!)   = 'End of Design' | 'Comp-Approve'     | ''       | 'CH6221ME902'    |'C0603'| '(SMC0603AW)'                                                        | '22UF'     | '6.3V'        | '20%'    | 'DISCRETE' | 'CAP CHIP 22U 6.3V(+-20%,X6S,0603)WTC'                         | 'CHIP0603'     | ''          | ''   | '20170426'
 '22UF'     | '6.3V'  | '20%'     | 'C0603'     | 'EMPTY'   | 'CH6221ME902'(!)   = 'End of Design' | 'Comp-Approve'     | ''       | 'CH6221ME902'    |'C0603'| '(SMC0603AW)'                                                        | 'NA'       | '6.3V'        | '20%'    | 'IO'       | 'CAP CHIP 22U 6.3V(+-20%,X6S,0603)WTC'                         | 'CHIP0603'     | ''          | ''   | '20170426'
 '22UF'     | '6.3V'  | '20%'     | 'C0603'     | 'X6S'     | 'CH6221ME901'(!)   = ''              | ''                 | ''       | 'CH6221ME901'    |'C0603'| '(SMC0603AW)'                                                        | '22UF'     | '6.3V'        | '20%'    | 'DISCRETE' | 'CAP CHIP 22U 6.3V(+-20%,X6S,0603)MUR'                         | 'CHIP0603'     | ''          | ''   | '20170426'
 '22UF'     | '6.3V'  | '20%'     | 'C0603'     | 'EMPTY'   | 'CH6221ME901'(!)   = ''              | ''                 | ''       | 'CH6221ME901'    |'C0603'| '(SMC0603AW)'                                                        | 'NA'       | '6.3V'        | '20%'    | 'IO'       | 'CAP CHIP 22U 6.3V(+-20%,X6S,0603)MUR'                         | 'CHIP0603'     | ''          | ''   | '20170426'
 '10UF'     | '6.3V'  | '20%'     | 'C0603'     | 'X5R'     | 'CH6101M9921'(!)   = ''              | ''                 | ''       | 'CH6101M9921'    |'C0603'| '(SMC0603AW)'                                                        | '10UF'     | '6.3V'        | '20%'    | 'DISCRETE' | 'CAP CHIP 10U 6.3V(+-20%,X5R,0603)SAM'                         | 'CHIP0603'     | ''          | ''   | '20170427'
 '10UF'     | '6.3V'  | '20%'     | 'C0603'     | 'EMPTY'   | 'CH6101M9921'(!)   = ''              | ''                 | ''       | 'CH6101M9921'    |'C0603'| '(SMC0603AW)'                                                        | 'NA'       | '6.3V'        | '20%'    | 'IO'       | 'CAP CHIP 10U 6.3V(+-20%,X5R,0603)SAM'                         | 'CHIP0603'     | ''          | ''   | '20170427'
 '10UF'     | '6.3V'  | '20%'     | 'C0603'     | 'X5R'     | 'CH6101M9914'(!)   = 'End of Design' | 'Comp-Approve'     | ''       | 'CH6101M9914'    |'C0603'| '(SMC0603AW)'                                                        | '10UF'     | '6.3V'        | '20%'    | 'DISCRETE' | 'CAP CHIP 10U 6.3V(+-20%,X5R,0603)YGO'                         | 'CHIP0603'     | ''          | ''   | '20170427'
 '10UF'     | '6.3V'  | '20%'     | 'C0603'     | 'EMPTY'   | 'CH6101M9914'(!)   = 'End of Design' | 'Comp-Approve'     | ''       | 'CH6101M9914'    |'C0603'| '(SMC0603AW)'                                                        | 'NA'       | '6.3V'        | '20%'    | 'IO'       | 'CAP CHIP 10U 6.3V(+-20%,X5R,0603)YGO'                         | 'CHIP0603'     | ''          | ''   | '20170427'
 '22PF'     | '50V'   | '5%'      | 'C0402'     | 'NPO'     | 'CH0226J0B22'(!)   = ''              | ''                 | ''       | 'CH0226J0B22'    |'C0402'| '(C0402-0201)'                                                       | '22PF'     | '50V'         | '5%'     | 'DISCRETE' | 'CAP CHIP 22P 50V(+-5%,NPO,0402)SAM'                           | 'CHIP0402'     | ''          | ''   | '20170427'
 '22PF'     | '50V'   | '5%'      | 'C0402'     | 'EMPTY'   | 'CH0226J0B22'(!)   = ''              | ''                 | ''       | 'CH0226J0B22'    |'C0402'| '(C0402-0201)'                                                       | 'NA'       | '50V'         | '5%'     | 'IO'       | 'CAP CHIP 22P 50V(+-5%,NPO,0402)SAM'                           | 'CHIP0402'     | ''          | ''   | '20170427'
 '0.1UF'    | '16V'   | '10%'     | 'C0402'     | 'X7R'     | 'CH4103K1B19'(!)   = 'End of Design' | 'Comp-Approve'     | ''       | 'CH4103K1B19'    |'C0402'| '(C0402-0201)'                                                       | '0.1UF'    | '16V'         | '10%'    | 'DISCRETE' | 'CAP CHIP 0.1U 16V(10%,X7R,0402)SAM'                           | 'CHIP0402'     | ''          | ''   | '20170427'
 '0.1UF'    | '16V'   | '10%'     | 'C0402'     | 'EMPTY'   | 'CH4103K1B19'(!)   = 'End of Design' | 'Comp-Approve'     | ''       | 'CH4103K1B19'    |'C0402'| '(C0402-0201)'                                                       | 'NA'       | '16V'         | '10%'    | 'IO'       | 'CAP CHIP 0.1U 16V(10%,X7R,0402)SAM'                           | 'CHIP0402'     | ''          | ''   | '20170427'
 '10UF'     | '10V'   | '20%'     | 'C0402'     | 'X5R'     | 'CH6102M9B11'(!)   = ''              | ''                 | ''       | 'CH6102M9B11'    |'C0402'| '(C0402-0201)'                                                       | '10UF'     | '10V'         | '20%'    | 'DISCRETE' | 'CAP CHIP 10U 10V(+-20%, X5R,0402)YGO'                         | 'CHIP0402'     | ''          | ''   | '20170427'
 '10UF'     | '10V'   | '20%'     | 'C0402'     | 'EMPTY'   | 'CH6102M9B11'(!)   = ''              | ''                 | ''       | 'CH6102M9B11'    |'C0402'| '(C0402-0201)'                                                       | 'NA'       | '10V'         | '20%'    | 'IO'       | 'CAP CHIP 10U 10V(+-20%, X5R,0402)YGO'                         | 'CHIP0402'     | ''          | ''   | '20170427'
 '10PF'     | '50V'   | '5%'      | 'C0402'     | 'C0G'     | 'CH0106J0B17'(!)   = ''              | ''                 | ''       | 'CH0106J0B17'    |'C0402'| '(C0402-0201)'                                                       | '10PF'     | '50V'         | '5%'     | 'DISCRETE' | 'CAP CHIP 10P 50V(+-5%,C0G,0402)MUR'                           | 'CHIP0402'     | ''          | ''   | '20170427'
 '10PF'     | '50V'   | '5%'      | 'C0402'     | 'EMPTY'   | 'CH0106J0B17'(!)   = ''              | ''                 | ''       | 'CH0106J0B17'    |'C0402'| '(C0402-0201)'                                                       | 'NA'       | '50V'         | '5%'     | 'IO'       | 'CAP CHIP 10P 50V(+-5%,C0G,0402)MUR'                           | 'CHIP0402'     | ''          | ''   | '20170427'
 '10PF'     | '50V'   | '5%'      | 'C0402'     | 'C0G'     | 'CH0106J0B18'(!)   = ''              | ''                 | ''       | 'CH0106J0B18'    |'C0402'| '(C0402-0201)'                                                       | '10PF'     | '50V'         | '5%'     | 'DISCRETE' | 'CAP CHIP 10P 50V(+-5%,C0G,0402)YGO'                           | 'CHIP0402'     | ''          | ''   | '20170427'
 '10PF'     | '50V'   | '5%'      | 'C0402'     | 'EMPTY'   | 'CH0106J0B18'(!)   = ''              | ''                 | ''       | 'CH0106J0B18'    |'C0402'| '(C0402-0201)'                                                       | 'NA'       | '50V'         | '5%'     | 'IO'       | 'CAP CHIP 10P 50V(+-5%,C0G,0402)YGO'                           | 'CHIP0402'     | ''          | ''   | '20170427'
 '12PF'     | '50V'   | '5%'      | 'C0402'     | 'C0G'     | 'CH0126J0B15'(!)   = ''              | ''                 | ''       | 'CH0126J0B15'    |'C0402'| '(C0402-0201)'                                                       | '12PF'     | '50V'         | '5%'     | 'DISCRETE' | 'CAP CHIP 12P 50V(+-5%,C0G,0402)WTC'                           | 'CHIP0402'     | ''          | ''   | '20170427'
 '12PF'     | '50V'   | '5%'      | 'C0402'     | 'EMPTY'   | 'CH0126J0B15'(!)   = ''              | ''                 | ''       | 'CH0126J0B15'    |'C0402'| '(C0402-0201)'                                                       | 'NA'       | '50V'         | '5%'     | 'IO'       | 'CAP CHIP 12P 50V(+-5%,C0G,0402)WTC'                           | 'CHIP0402'     | ''          | ''   | '20170427'
 '12PF'     | '50V'   | '5%'      | 'C0402'     | 'NP0'     | 'CH0126J0B10'(!)   = ''              | ''                 | ''       | 'CH0126J0B10'    |'C0402'| '(C0402-0201)'                                                       | '12PF'     | '50V'         | '5%'     | 'DISCRETE' | 'CAP CHIP 12P 50V(+-5%,NP0,0402)TAY'                           | 'CHIP0402'     | ''          | ''   | '20170427'
 '12PF'     | '50V'   | '5%'      | 'C0402'     | 'EMPTY'   | 'CH0126J0B10'(!)   = ''              | ''                 | ''       | 'CH0126J0B10'    |'C0402'| '(C0402-0201)'                                                       | 'NA'       | '50V'         | '5%'     | 'IO'       | 'CAP CHIP 12P 50V(+-5%,NP0,0402)TAY'                           | 'CHIP0402'     | ''          | ''   | '20170427'
 '2200PF'   | '50V'   | '10%'     | 'C0402'     | 'X7R'     | 'CH2226K1B12'(!)   = ''              | ''                 | ''       | 'CH2226K1B12'    |'C0402'| '(C0402-0201)'                                                       | '2200PF'   | '50V'         | '10%'    | 'DISCRETE' | 'CAP CHIP 2200P 50V(+-10%,X7R,0402)TAY'                        | 'CHIP0402'     | ''          | ''   | '20170427'
 '2200PF'   | '50V'   | '10%'     | 'C0402'     | 'EMPTY'   | 'CH2226K1B12'(!)   = ''              | ''                 | ''       | 'CH2226K1B12'    |'C0402'| '(C0402-0201)'                                                       | 'NA'       | '50V'         | '10%'    | 'IO'       | 'CAP CHIP 2200P 50V(+-10%,X7R,0402)TAY'                        | 'CHIP0402'     | ''          | ''   | '20170427'
 '0.22UF'   | '16V'   | '10%'     | 'C0402'     | 'X7R'     | 'CH4223K1B05'(!)   = 'End of Design' | 'Comp-Approve'     | ''       | 'CH4223K1B05'    |'C0402'| '(C0402-0201)'                                                       | '0.22UF'   | '16V'         | '10%'    | 'DISCRETE' | 'CAP CHIP 0.22U 16V(10%,X7R,0402)SAM'                          | 'CHIP0402'     | ''          | ''   | '20170427'
 '0.22UF'   | '16V'   | '10%'     | 'C0402'     | 'EMPTY'   | 'CH4223K1B05'(!)   = 'End of Design' | 'Comp-Approve'     | ''       | 'CH4223K1B05'    |'C0402'| '(C0402-0201)'                                                       | 'NA'       | '16V'         | '10%'    | 'IO'       | 'CAP CHIP 0.22U 16V(10%,X7R,0402)SAM'                          | 'CHIP0402'     | ''          | ''   | '20170427'
 '4.7UF'    | '6.3V'  | '20%'     | 'C0402'     | 'X6S'     | 'CH5471MEB04'(!)   = ''              | ''                 | ''       | 'CH5471MEB04'    |'C0402'| '(C0402-0201)'                                                       | '4.7UF'    | '6.3V'        | '20%'    | 'DISCRETE' | 'CAP CHIP 4.7UF 6.3V(+-20%,X6S,0402)TAY'                       | 'CHIP0402'     | ''          | ''   | '20170427'
 '4.7UF'    | '6.3V'  | '20%'     | 'C0402'     | 'EMPTY'   | 'CH5471MEB04'(!)   = ''              | ''                 | ''       | 'CH5471MEB04'    |'C0402'| '(C0402-0201)'                                                       | 'NA'       | '6.3V'        | '20%'    | 'IO'       | 'CAP CHIP 4.7UF 6.3V(+-20%,X6S,0402)TAY'                       | 'CHIP0402'     | ''          | ''   | '20170427'
 '1UF'      | '6.3V'  | '10%'     | 'C0402'     | 'X7R'     | 'CH5101K1B06'(!)   = ''              | ''                 | ''       | 'CH5101K1B06'    |'C0402'| '(C0402-0201)'                                                       | '1UF'      | '6.3V'        | '10%'    | 'DISCRETE' | 'CAP CHIP 1U,6.3V(+-10%,X7R,0402)SAM'                          | 'CHIP0402'     | ''          | ''   | '20170427'
 '1UF'      | '6.3V'  | '10%'     | 'C0402'     | 'EMPTY'   | 'CH5101K1B06'(!)   = ''              | ''                 | ''       | 'CH5101K1B06'    |'C0402'| '(C0402-0201)'                                                       | 'NA'       | '6.3V'        | '10%'    | 'IO'       | 'CAP CHIP 1U,6.3V(+-10%,X7R,0402)SAM'                          | 'CHIP0402'     | ''          | ''   | '20170427'
 '1500PF'   | '50V'   | '10%'     | 'C0402'     | 'X7R'     | 'CH2156K1B09'(!)   = ''              | ''                 | ''       | 'CH2156K1B09'    |'C0402'| '(C0402-0201)'                                                       | '1500PF'   | '50V'         | '10%'    | 'DISCRETE' | 'CAP CHIP 1500PF 50V(+-10%,X7R,0402)SAM'                       | 'CHIP0402'     | ''          | ''   | '20170427'
 '1500PF'   | '50V'   | '10%'     | 'C0402'     | 'EMPTY'   | 'CH2156K1B09'(!)   = ''              | ''                 | ''       | 'CH2156K1B09'    |'C0402'| '(C0402-0201)'                                                       | 'NA'       | '50V'         | '10%'    | 'IO'       | 'CAP CHIP 1500PF 50V(+-10%,X7R,0402)SAM'                       | 'CHIP0402'     | ''          | ''   | '20170427'
 '1500PF'   | '50V'   | '10%'     | 'C0402'     | 'X7R'     | 'CH2156K1B10'(!)   = ''              | ''                 | ''       | 'CH2156K1B10'    |'C0402'| '(C0402-0201)'                                                       | '1500PF'   | '50V'         | '10%'    | 'DISCRETE' | 'CAP CHIP 1500PF 50V(+-10%,X7R,0402)WTC'                       | 'CHIP0402'     | ''          | ''   | '20170427'
 '1500PF'   | '50V'   | '10%'     | 'C0402'     | 'EMPTY'   | 'CH2156K1B10'(!)   = ''              | ''                 | ''       | 'CH2156K1B10'    |'C0402'| '(C0402-0201)'                                                       | 'NA'       | '50V'         | '10%'    | 'IO'       | 'CAP CHIP 1500PF 50V(+-10%,X7R,0402)WTC'                       | 'CHIP0402'     | ''          | ''   | '20170427'
 '1200PF'   | '50V'   | '10%'     | 'C0402'     | 'X7R'     | 'CH2126K1B03'(!)   = 'End of Design' | 'End of Life'      | ''       | 'CH2126K1B03'    |'C0402_EOL'| '(C0402-0201)'                                                       | '1200PF'   | '50V'         | '10%'    | 'DISCRETE' | 'CAP CHIP 1200P 50V(+-10%,X7R,0402)SAM'                        | 'CHIP0402'     | ''          | ''   | '20170427'
 '1200PF'   | '50V'   | '10%'     | 'C0402'     | 'EMPTY'   | 'CH2126K1B03'(!)   = 'End of Design' | 'End of Life'      | ''       | 'CH2126K1B03'    |'C0402_EOL'| '(C0402-0201)'                                                       | 'NA'       | '50V'         | '10%'    | 'IO'       | 'CAP CHIP 1200P 50V(+-10%,X7R,0402)SAM'                        | 'CHIP0402'     | ''          | ''   | '20170427'
 '1200PF'   | '50V'   | '10%'     | 'C0402'     | 'X7R'     | 'CH2126K1B04'(!)   = ''              | ''                 | ''       | 'CH2126K1B04'    |'C0402'| '(C0402-0201)'                                                       | '1200PF'   | '50V'         | '10%'    | 'DISCRETE' | 'CAP CHIP 1200P 50V(+-10%,X7R,0402)WTC'                        | 'CHIP0402'     | ''          | ''   | '20170427'
 '1200PF'   | '50V'   | '10%'     | 'C0402'     | 'EMPTY'   | 'CH2126K1B04'(!)   = ''              | ''                 | ''       | 'CH2126K1B04'    |'C0402'| '(C0402-0201)'                                                       | 'NA'       | '50V'         | '10%'    | 'IO'       | 'CAP CHIP 1200P 50V(+-10%,X7R,0402)WTC'                        | 'CHIP0402'     | ''          | ''   | '20170427'
 '10UF'     | '10V'   | '20%'     | 'C0402'     | 'X5R'     | 'CH6102M9B12'(!)   = ''              | ''                 | ''       | 'CH6102M9B12'    |'C0402'| '(C0402-0201)'                                                       | '10UF'     | '10V'         | '20%'    | 'DISCRETE' | 'CAP CHIP 10U 10V(+-20%, X5R,0402)SAM'                         | 'CHIP0402'     | ''          | ''   | '20170427'
 '10UF'     | '10V'   | '20%'     | 'C0402'     | 'EMPTY'   | 'CH6102M9B12'(!)   = ''              | ''                 | ''       | 'CH6102M9B12'    |'C0402'| '(C0402-0201)'                                                       | 'NA'       | '10V'         | '20%'    | 'IO'       | 'CAP CHIP 10U 10V(+-20%, X5R,0402)SAM'                         | 'CHIP0402'     | ''          | ''   | '20170427'
 '0.01UF'   | '16V'   | '10%'     | 'C0402'     | 'X7R'     | 'CH3103K1B26'(!)   = ''              | ''                 | ''       | 'CH3103K1B26'    |'C0402'| '(C0402-0201)'                                                       | '0.01UF'   | '16V'         | '10%'    | 'DISCRETE' | 'CAP CHIP 0.01U 16V(10%,X7R,0402)YGO'                          | 'CHIP0402'     | ''          | ''   | '20170427'
 '0.01UF'   | '16V'   | '10%'     | 'C0402'     | 'EMPTY'   | 'CH3103K1B26'(!)   = ''              | ''                 | ''       | 'CH3103K1B26'    |'C0402'| '(C0402-0201)'                                                       | 'NA'       | '16V'         | '10%'    | 'IO'       | 'CAP CHIP 0.01U 16V(10%,X7R,0402)YGO'                          | 'CHIP0402'     | ''          | ''   | '20170427'
 '0.01UF'   | '16V'   | '10%'     | 'C0402'     | 'X7R'     | 'CH3103K1B25'(!)   = ''              | ''                 | ''       | 'CH3103K1B25'    |'C0402'| '(C0402-0201)'                                                       | '0.01UF'   | '16V'         | '10%'    | 'DISCRETE' | 'CAP CHIP 0.01U 16V(10%,X7R,0402)WTC'                          | 'CHIP0402'     | ''          | ''   | '20170427'
 '0.01UF'   | '16V'   | '10%'     | 'C0402'     | 'EMPTY'   | 'CH3103K1B25'(!)   = ''              | ''                 | ''       | 'CH3103K1B25'    |'C0402'| '(C0402-0201)'                                                       | 'NA'       | '16V'         | '10%'    | 'IO'       | 'CAP CHIP 0.01U 16V(10%,X7R,0402)WTC'                          | 'CHIP0402'     | ''          | ''   | '20170427'
 '1UF'      | '16V'   | '10%'     | 'C0402'     | 'X5R'     | 'CH5103K9B06'(!)   = ''              | ''                 | ''       | 'CH5103K9B06'    |'C0402'| '(C0402-0201)'                                                       | '1UF'      | '16V'         | '10%'    | 'DISCRETE' | 'CAP CHIP 1U 16V(10%,X5R,0402)SAM'                             | 'CHIP0402'     | ''          | ''   | '20170427'
 '1UF'      | '16V'   | '10%'     | 'C0402'     | 'EMPTY'   | 'CH5103K9B06'(!)   = ''              | ''                 | ''       | 'CH5103K9B06'    |'C0402'| '(C0402-0201)'                                                       | 'NA'       | '16V'         | '10%'    | 'IO'       | 'CAP CHIP 1U 16V(10%,X5R,0402)SAM'                             | 'CHIP0402'     | ''          | ''   | '20170427'
 '1UF'      | '16V'   | '10%'     | 'C0402'     | 'X5R'     | 'CH5103K9B09'(!)   = ''              | ''                 | ''       | 'CH5103K9B09'    |'C0402'| '(C0402-0201)'                                                       | '1UF'      | '16V'         | '10%'    | 'DISCRETE' | 'CAP CHIP 1UF 16V(10%,X5R,0402)WTC'                            | 'CHIP0402'     | ''          | ''   | '20170427'
 '1UF'      | '16V'   | '10%'     | 'C0402'     | 'EMPTY'   | 'CH5103K9B09'(!)   = ''              | ''                 | ''       | 'CH5103K9B09'    |'C0402'| '(C0402-0201)'                                                       | 'NA'       | '16V'         | '10%'    | 'IO'       | 'CAP CHIP 1UF 16V(10%,X5R,0402)WTC'                            | 'CHIP0402'     | ''          | ''   | '20170427'
 '10UF'     | '25V'   | '10%'     | 'C0805'     | 'X6S'     | 'CH6104KEA06'(!)   = 'End of Design' | 'Comp-Approve'     | ''       | 'CH6104KEA06'    |'C0805_H57'| '(SMC0805AW)'                                                        | '10UF'     | '25V'         | '10%'    | 'DISCRETE' | 'CAP CHIP 10U 25V(+-10%,X6S,0805)WTC'                          | 'CHIP0805'     | ''          | ''   | '20170502'
 '10UF'     | '25V'   | '10%'     | 'C0805'     | 'EMPTY'   | 'CH6104KEA06'(!)   = 'End of Design' | 'Comp-Approve'     | ''       | 'CH6104KEA06'    |'C0805_H57'| '(SMC0805AW)'                                                        | 'NA'       | '25V'         | '10%'    | 'IO'       | 'CAP CHIP 10U 25V(+-10%,X6S,0805)WTC'                          | 'CHIP0805'     | ''          | ''   | '20170502'
 '22UF'     | '6.3V'  | '20%'     | 'C0805'     | 'X5R'     | 'CH6221M9A34'(!)   = ''              | ''                 | ''       | 'CH6221M9A34'    |'C0805_H57'| '(SMC0805AW)'                                                        | '22UF'     | '6.3V'        | '20%'    | 'DISCRETE' | 'CAP CHIP 22U 6.3V(+-20%,X5R,0805)WTC'                         | 'CHIP0805'     | ''          | ''   | '20170502'
 '22UF'     | '6.3V'  | '20%'     | 'C0805'     | 'EMPTY'   | 'CH6221M9A34'(!)   = ''              | ''                 | ''       | 'CH6221M9A34'    |'C0805_H57'| '(SMC0805AW)'                                                        | 'NA'       | '6.3V'        | '20%'    | 'IO'       | 'CAP CHIP 22U 6.3V(+-20%,X5R,0805)WTC'                         | 'CHIP0805'     | ''          | ''   | '20170502'
 '22UF'     | '6.3V'  | '20%'     | 'C0805'     | 'X6S'     | 'CH6221MEA06'(!)   = ''              | ''                 | ''       | 'CH6221MEA06'    |'C0805_H57'| '(SMC0805AW)'                                                        | '22UF'     | '6.3V'        | '20%'    | 'DISCRETE' | 'CAP CHIP 22U 6.3V(+-20%,X6S,0805)SAM'                         | 'CHIP0805'     | ''          | ''   | '20170502'
 '22UF'     | '6.3V'  | '20%'     | 'C0805'     | 'EMPTY'   | 'CH6221MEA06'(!)   = ''              | ''                 | ''       | 'CH6221MEA06'    |'C0805_H57'| '(SMC0805AW)'                                                        | 'NA'       | '6.3V'        | '20%'    | 'IO'       | 'CAP CHIP 22U 6.3V(+-20%,X6S,0805)SAM'                         | 'CHIP0805'     | ''          | ''   | '20170502'
 '10UF'     | '25V'   | '10%'     | 'C1206'     | 'X7R'     | 'CH6104K1212'(!)   = 'End of Design' | 'Comp-Approve'     | ''       | 'CH6104K1212'    |'C1206_H76'| '(SMC1206AW)'                                                        | '10UF'     | '25V'         | '10%'    | 'DISCRETE' | 'CAP CHIP 10U 25V(+-10%,X7R,1206)WTC'                          | 'CHIP1206'     | ''          | ''   | '20170502'
 '10UF'     | '25V'   | '10%'     | 'C1206'     | 'EMPTY'   | 'CH6104K1212'(!)   = 'End of Design' | 'Comp-Approve'     | ''       | 'CH6104K1212'    |'C1206_H76'| '(SMC1206AW)'                                                        | 'NA'       | '25V'         | '10%'    | 'IO'       | 'CAP CHIP 10U 25V(+-10%,X7R,1206)WTC'                          | 'CHIP1206'     | ''          | ''   | '20170502'
 '22UF'     | '25V'   | '10%'     | 'C1206'     | 'X6S'     | 'CH6224KE202'(!)   = 'End of Design' | 'Comp-Approve'     | ''       | 'CH6224KE202'    |'C1206_H76'| '(SMC1206AW)'                                                        | '22UF'     | '25V'         | '10%'    | 'DISCRETE' | 'CAP CHIP 22U 25V(+-10%,X6S,1206)SAM'                          | 'CHIP1206'     | ''          | ''   | '20170502'
 '22UF'     | '25V'   | '10%'     | 'C1206'     | 'EMPTY'   | 'CH6224KE202'(!)   = 'End of Design' | 'Comp-Approve'     | ''       | 'CH6224KE202'    |'C1206_H76'| '(SMC1206AW)'                                                        | 'NA'       | '25V'         | '10%'    | 'IO'       | 'CAP CHIP 22U 25V(+-10%,X6S,1206)SAM'                          | 'CHIP1206'     | ''          | ''   | '20170502'
 '22UF'     | '10V'   | '20%'     | 'C0805'     | 'X6S'     | 'CH6222MEA02'(!)   = ''              | ''                 | ''       | 'CH6222MEA02'    |'C0805_H57'| '(SMC0805AW)'                                                        | '22UF'     | '10V'         | '20%'    | 'DISCRETE' | 'CAP CHIP 22U 10V(+-20%,X6S,0805)TAY'                          | 'CHIP0805'     | ''          | ''   | '20170503'
 '22UF'     | '10V'   | '20%'     | 'C0805'     | 'EMPTY'   | 'CH6222MEA02'(!)   = ''              | ''                 | ''       | 'CH6222MEA02'    |'C0805_H57'| '(SMC0805AW)'                                                        | 'NA'       | '10V'         | '20%'    | 'IO'       | 'CAP CHIP 22U 10V(+-20%,X6S,0805)TAY'                          | 'CHIP0805'     | ''          | ''   | '20170503'
 '10UF'     | '6.3V'  | '20%'     | 'C0805'     | 'X6S'     | 'CH6101MEA01'(!)   = ''              | 'End of Life'      | ''       | 'CH6101MEA01'    |'C0805_H57_EOL'| '(SMC0805AW)'                                                        | '10UF'     | '6.3V'        | '20%'    | 'DISCRETE' | 'CAP CHIP 10UF 6.3V(+-20%,X6S,0805)TAY'                        | 'CHIP0805'     | ''          | ''   | '20170503'
 '10UF'     | '6.3V'  | '20%'     | 'C0805'     | 'EMPTY'   | 'CH6101MEA01'(!)   = ''              | 'End of Life'      | ''       | 'CH6101MEA01'    |'C0805_H57_EOL'| '(SMC0805AW)'                                                        | 'NA'       | '6.3V'        | '20%'    | 'IO'       | 'CAP CHIP 10UF 6.3V(+-20%,X6S,0805)TAY'                        | 'CHIP0805'     | ''          | ''   | '20170503'
 '22UF'     | '6.3V'  | '20%'     | 'C0805'     | 'X5R'     | 'CH6221M9A27'(!)   = ''              | ''                 | ''       | 'CH6221M9A27'    |'C0805_H57'| '(SMC0805AW)'                                                        | '22UF'     | '6.3V'        | '20%'    | 'DISCRETE' | 'CAP CHIP 22U 6.3V(+-20%,X5R,0805)TAY'                         | 'CHIP0805'     | ''          | ''   | '20170503'
 '22UF'     | '6.3V'  | '20%'     | 'C0805'     | 'EMPTY'   | 'CH6221M9A27'(!)   = ''              | ''                 | ''       | 'CH6221M9A27'    |'C0805_H57'| '(SMC0805AW)'                                                        | 'NA'       | '6.3V'        | '20%'    | 'IO'       | 'CAP CHIP 22U 6.3V(+-20%,X5R,0805)TAY'                         | 'CHIP0805'     | ''          | ''   | '20170503'
 '10UF'     | '6.3V'  | '10%'     | 'C0805'     | 'X6S'     | 'CH6101KEA02'(!)   = 'End of Design' | 'Comp-Approve'     | ''       | 'CH6101KEA02'    |'C0805_H57'| '(SMC0805AW)'                                                        | '10UF'     | '6.3V'        | '10%'    | 'DISCRETE' | 'CAP CHIP 10UF,6.3V (+-10%,X6S,0805)MUR'                       | 'CHIP0805'     | ''          | ''   | '20170503'
 '10UF'     | '6.3V'  | '10%'     | 'C0805'     | 'EMPTY'   | 'CH6101KEA02'(!)   = 'End of Design' | 'Comp-Approve'     | ''       | 'CH6101KEA02'    |'C0805_H57'| '(SMC0805AW)'                                                        | 'NA'       | '6.3V'        | '10%'    | 'IO'       | 'CAP CHIP 10UF,6.3V (+-10%,X6S,0805)MUR'                       | 'CHIP0805'     | ''          | ''   | '20170503'
 '10UF'     | '6.3V'  | '20%'     | 'C0805'     | 'X6S'     | 'CH6101MEA02'(!)   = ''              | ''                 | ''       | 'CH6101MEA02'    |'C0805_H57'| '(SMC0805AW)'                                                        | '10UF'     | '6.3V'        | '20%'    | 'DISCRETE' | 'CAP CHIP 10UF 6.3V(+-20%,X6S,0805)MUR'                        | 'CHIP0805'     | ''          | ''   | '20170503'
 '10UF'     | '6.3V'  | '20%'     | 'C0805'     | 'EMPTY'   | 'CH6101MEA02'(!)   = ''              | ''                 | ''       | 'CH6101MEA02'    |'C0805_H57'| '(SMC0805AW)'                                                        | 'NA'       | '6.3V'        | '20%'    | 'IO'       | 'CAP CHIP 10UF 6.3V(+-20%,X6S,0805)MUR'                        | 'CHIP0805'     | ''          | ''   | '20170503'
 '22UF'     | '25V'   | '10%'     | 'C1206'     | 'X6S'     | 'CH6224KE201'(!)   = 'End of Design' | 'Comp-Approve'     | ''       | 'CH6224KE201'    |'C1206_H76'| '(SMC1206AW)'                                                        | '22UF'     | '25V'         | '10%'    | 'DISCRETE' | 'CAP CHIP 22U 25V(+-10%,X6S,1206)MUR'                          | 'CHIP1206'     | ''          | ''   | '20170503'
 '22UF'     | '25V'   | '10%'     | 'C1206'     | 'EMPTY'   | 'CH6224KE201'(!)   = 'End of Design' | 'Comp-Approve'     | ''       | 'CH6224KE201'    |'C1206_H76'| '(SMC1206AW)'                                                        | 'NA'       | '25V'         | '10%'    | 'IO'       | 'CAP CHIP 22U 25V(+-10%,X6S,1206)MUR'                          | 'CHIP1206'     | ''          | ''   | '20170503'
 '1UF'      | '25V'   | '10%'     | 'C0402'     | 'X6S'     | 'CH5104KEB03'(!)   = ''              | ''                 | ''       | 'CH5104KEB03'    |'C0402'| '(C0402_OCTAGONXA,C0402-0201,C0402_OCTAGONXA_BOUND22)'               | '1UF'      | '25V'         | '10%'    | 'DISCRETE' | 'CAP CHIP 1UF 25V(+-10%,X6S,0402)MUR'                          | 'CHIP0402'     | ''          | ''   | '20170509'
 '1UF'      | '25V'   | '10%'     | 'C0402'     | 'EMPTY'   | 'CH5104KEB03'(!)   = ''              | ''                 | ''       | 'CH5104KEB03'    |'C0402'| '(C0402_OCTAGONXA,C0402-0201,C0402_OCTAGONXA_BOUND22)'               | 'NA'       | '25V'         | '10%'    | 'IO'       | 'CAP CHIP 1UF 25V(+-10%,X6S,0402)MUR'                          | 'CHIP0402'     | ''          | ''   | '20170509'
 '16PF'     | '25V'   | '5%'      | 'C0402'     | 'NP0'     | 'CH0164J0B00'(!)   = ''              | ''                 | ''       | 'CH0164J0B00'    |'C0402'| '(C0402-0201)'                                                       | '16PF'     | '25V'         | '5%'     | 'DISCRETE' | 'CAP CHIP 16P 25V(+-5%,NP0,0402)'                              | 'CHIP0402'     | ''          | ''   | '20170509'
 '16PF'     | '25V'   | '5%'      | 'C0402'     | 'EMPTY'   | 'CH0164J0B00'(!)   = ''              | ''                 | ''       | 'CH0164J0B00'    |'C0402'| '(C0402-0201)'                                                       | 'NA'       | '25V'         | '5%'     | 'IO'       | 'CAP CHIP 16P 25V(+-5%,NP0,0402)'                              | 'CHIP0402'     | ''          | ''   | '20170509'
 '0.1UF'    | '16V'   | '10%'     | 'C0402'     | 'X7R'     | 'CH4103K1B13'(!)   = 'End of Design' | 'Comp-Approve'     | ''       | 'CH4103K1B13'    |'C0402'| '(C0402_OCTAGONXA,C0402_SMDC25_SM30,C0402-0201)'                     | '0.1UF'    | '16V'         | '10%'    | 'DISCRETE' | 'CAP CHIP 0.1U 16V(10%,X7R,0402)MUR'                           | 'CHIP0402'     | ''          | ''   | '20170524'
 '0.1UF'    | '16V'   | '10%'     | 'C0402'     | 'EMPTY'   | 'CH4103K1B13'(!)   = 'End of Design' | 'Comp-Approve'     | ''       | 'CH4103K1B13'    |'C0402'| '(C0402_OCTAGONXA,C0402_SMDC25_SM30,C0402-0201)'                     | 'NA'       | '16V'         | '10%'    | 'IO'       | 'CAP CHIP 0.1U 16V(10%,X7R,0402)MUR'                           | 'CHIP0402'     | ''          | ''   | '20170524'
 '22UF'     | '4V'    | '20%'     | 'C0402'     | 'X6S'     | 'CH622KMEB00'(!)   = 'End of Design' | 'Comp-Approve'     | ''       | 'CH622KMEB00'    |'C0402'| '(C0402_SMDC25_SM30,C0402-0201)'                                     | '22UF'     | '4V'          | '20%'    | 'DISCRETE' | 'CAP CHIP 22UF 4V(+-20%,X6S,0402)TAY'                          | 'CHIP0402'     | ''          | ''   | '20170524'
 '22UF'     | '4V'    | '20%'     | 'C0402'     | 'EMPTY'   | 'CH622KMEB00'(!)   = 'End of Design' | 'Comp-Approve'     | ''       | 'CH622KMEB00'    |'C0402'| '(C0402_SMDC25_SM30,C0402-0201)'                                     | 'NA'       | '4V'          | '20%'    | 'IO'       | 'CAP CHIP 22UF 4V(+-20%,X6S,0402)TAY'                          | 'CHIP0402'     | ''          | ''   | '20170524'
 '4.7PF'    | '50V'   | '0.25PF'  | 'C0402'     | 'C0G'     | 'CH-476C0B05'(!)   = 'End of Design' | 'Comp-Approve'     | ''       | 'CH-476C0B05'    |'C0402'| '(C0402-0201)'                                                       | '4.7PF'    | '50V'         | '0.25PF' | 'DISCRETE' | 'CAP CHIP 4.7P 50V(+-0.25P,C0G,0402)SAM'                       | 'CHIP0402'     | ''          | ''   | '20170526'
 '4.7PF'    | '50V'   | '0.25PF'  | 'C0402'     | 'EMPTY'   | 'CH-476C0B05'(!)   = 'End of Design' | 'Comp-Approve'     | ''       | 'CH-476C0B05'    |'C0402'| '(C0402-0201)'                                                       | 'NA'       | '50V'         | '0.25PF' | 'IO'       | 'CAP CHIP 4.7P 50V(+-0.25P,C0G,0402)SAM'                       | 'CHIP0402'     | ''          | ''   | '20170526'
 '4.7PF'    | '50V'   | '0.25PF'  | 'C0402'     | 'C0G'     | 'CH-476C0B04'(!)   = ''              | ''                 | ''       | 'CH-476C0B04'    |'C0402'| '(C0402-0201)'                                                       | '4.7PF'    | '50V'         | '0.25PF' | 'DISCRETE' | 'CAP CHIP 4.7P 50V(+-0.25P,C0G,0402)WTC'                       | 'CHIP0402'     | ''          | ''   | '20170526'
 '4.7PF'    | '50V'   | '0.25PF'  | 'C0402'     | 'EMPTY'   | 'CH-476C0B04'(!)   = ''              | ''                 | ''       | 'CH-476C0B04'    |'C0402'| '(C0402-0201)'                                                       | 'NA'       | '50V'         | '0.25PF' | 'IO'       | 'CAP CHIP 4.7P 50V(+-0.25P,C0G,0402)WTC'                       | 'CHIP0402'     | ''          | ''   | '20170526'
 '4.7PF'    | '50V'   | '0.25PF'  | 'C0402'     | 'C0G'     | 'CH-476C0B03'(!)   = ''              | ''                 | ''       | 'CH-476C0B03'    |'C0402'| '(C0402-0201)'                                                       | '4.7PF'    | '50V'         | '0.25PF' | 'DISCRETE' | 'CAP CHIP 4.7P 50V(+-0.25P,C0G,0402)MUR'                       | 'CHIP0402'     | ''          | ''   | '20170526'
 '4.7PF'    | '50V'   | '0.25PF'  | 'C0402'     | 'EMPTY'   | 'CH-476C0B03'(!)   = ''              | ''                 | ''       | 'CH-476C0B03'    |'C0402'| '(C0402-0201)'                                                       | 'NA'       | '50V'         | '0.25PF' | 'IO'       | 'CAP CHIP 4.7P 50V(+-0.25P,C0G,0402)MUR'                       | 'CHIP0402'     | ''          | ''   | '20170526'
 '22UF'     | '6.3V'  | '20%'     | 'C0402'     | 'X5R'     | 'CH6221M9B05'(!)   = ''              | ''                 | ''       | 'CH6221M9B05'    |'C0402'| '(C0402-0201)'                                                       | '22UF'     | '6.3V'        | '20%'    | 'DISCRETE' | 'CAP CHIP 22UF 6.3V(+-20%,X5R,0402)MUR'                        | 'CHIP0402'     | ''          | ''   | '20170626'
 '22UF'     | '6.3V'  | '20%'     | 'C0402'     | 'EMPTY'   | 'CH6221M9B05'(!)   = ''              | ''                 | ''       | 'CH6221M9B05'    |'C0402'| '(C0402-0201)'                                                       | 'NA'       | '6.3V'        | '20%'    | 'IO'       | 'CAP CHIP 22UF 6.3V(+-20%,X5R,0402)MUR'                        | 'CHIP0402'     | ''          | ''   | '20170626'
 '1UF'      | '10V'   | '10%'     | 'C0402'     | 'X6S'     | 'CH5102KEB02'(!)   = ''              | ''                 | ''       | 'CH5102KEB02'    |'C0402'| '(C0402-0201)'                                                       | '1UF'      | '10V'         | '10%'    | 'DISCRETE' | 'CAP CHIP 1UF 10V(+-10%,X6S,0402)MUR'                          | 'CHIP0402'     | ''          | ''   | '20170626'
 '1UF'      | '10V'   | '10%'     | 'C0402'     | 'EMPTY'   | 'CH5102KEB02'(!)   = ''              | ''                 | ''       | 'CH5102KEB02'    |'C0402'| '(C0402-0201)'                                                       | 'NA'       | '10V'         | '10%'    | 'IO'       | 'CAP CHIP 1UF 10V(+-10%,X6S,0402)MUR'                          | 'CHIP0402'     | ''          | ''   | '20170626'
 '6800PF'   | '100V'  | '10%'     | 'C0603'     | 'X7R'     | 'CH2688K1900'(!)   = ''              | ''                 | ''       | 'CH2688K1900'    |'C0603'| '(SMC0603AW)'                                                        | '6800PF'   | '100V'        | '10%'    | 'DISCRETE' | 'CAP CHIP 6800P 100V(+-10%,X7R,0603)MUR'                       | 'CHIP0603'     | ''          | ''   | '20170704'
 '6800PF'   | '100V'  | '10%'     | 'C0603'     | 'EMPTY'   | 'CH2688K1900'(!)   = ''              | ''                 | ''       | 'CH2688K1900'    |'C0603'| '(SMC0603AW)'                                                        | 'NA'       | '100V'        | '10%'    | 'IO'       | 'CAP CHIP 6800P 100V(+-10%,X7R,0603)MUR'                       | 'CHIP0603'     | ''          | ''   | '20170704'
 '0.47UF'   | '100V'  | '10%'     | 'C0805'     | 'X7R'     | 'CH4478K1A01'(!)   = 'End of Design' | 'Comp-Approve'     | ''       | 'CH4478K1A01'    |'C0805_H61'| '(SMC0805AW)'                                                        | '0.47UF'   | '100V'        | '10%'    | 'DISCRETE' | 'CAP CHIP 0.47U 100V(+-10%,X7R,0805)MUR'                       | 'CHIP0805'     | ''          | ''   | '20170705'
 '0.47UF'   | '100V'  | '10%'     | 'C0805'     | 'EMPTY'   | 'CH4478K1A01'(!)   = 'End of Design' | 'Comp-Approve'     | ''       | 'CH4478K1A01'    |'C0805_H61'| '(SMC0805AW)'                                                        | 'NA'       | '100V'        | '10%'    | 'IO'       | 'CAP CHIP 0.47U 100V(+-10%,X7R,0805)MUR'                       | 'CHIP0805'     | ''          | ''   | '20170705'
 '4.7UF'    | '100V'  | '10%'     | 'C1206'     | 'X7R'     | 'CH5478K1200'(!)   = ''              | ''                 | ''       | 'CH5478K1200'    |'C1206XB'| '(SMC1206AW)'                                                        | '4.7UF'    | '100V'        | '10%'    | 'DISCRETE' | 'CAP CHIP 4.7UF 100V(+-10%,X7R,1206)MUR'                       | 'CHIP1206'     | ''          | ''   | '20170705'
 '4.7UF'    | '100V'  | '10%'     | 'C1206'     | 'EMPTY'   | 'CH5478K1200'(!)   = ''              | ''                 | ''       | 'CH5478K1200'    |'C1206XB'| '(SMC1206AW)'                                                        | 'NA'       | '100V'        | '10%'    | 'IO'       | 'CAP CHIP 4.7UF 100V(+-10%,X7R,1206)MUR'                       | 'CHIP1206'     | ''          | ''   | '20170705'
 '68PF'     | '50V'   | '5%'      | 'C0402'     | 'COG'     | 'CH06806JB01'(!)   = ''              | ''                 | ''       | 'CH06806JB01'    |'C0402'| '(C0402-0201)'                                                       | '68PF'     | '50V'         | '5%'     | 'DISCRETE' | 'CAP CHIP 68P 50V(+-5%.COG.0402)'                              | 'CHIP0402'     | ''          | ''   | '20170725'
 '68PF'     | '50V'   | '5%'      | 'C0402'     | 'EMPTY'   | 'CH06806JB01'(!)   = ''              | ''                 | ''       | 'CH06806JB01'    |'C0402'| '(C0402-0201)'                                                       | 'NA'       | '50V'         | '5%'     | 'IO'       | 'CAP CHIP 68P 50V(+-5%.COG.0402)'                              | 'CHIP0402'     | ''          | ''   | '20170725'
 '22UF'     | '10V'   | '20%'     | 'C0603'     | 'X5R'     | 'CH6222M9901'(!)   = ''              | ''                 | ''       | 'CH6222M9901'    |'C0603'| '(SMC0603AW)'                                                        | '22UF'     | '10V'         | '20%'    | 'DISCRETE' | 'CAP CHIP 22UF 10V(+-20%,X5R,0603)'                            | 'CHIP0603'     | ''          | ''   | '20170801'
 '22UF'     | '10V'   | '20%'     | 'C0603'     | 'EMPTY'   | 'CH6222M9901'(!)   = ''              | ''                 | ''       | 'CH6222M9901'    |'C0603'| '(SMC0603AW)'                                                        | 'NA'       | '10V'         | '20%'    | 'IO'       | 'CAP CHIP 22UF 10V(+-20%,X5R,0603)'                            | 'CHIP0603'     | ''          | ''   | '20170801'
 '0.047UF'  | '100V'  | '10%'     | 'C0805'     | 'X7R'     | 'CH3478K1A01'(!)   = ''              | ''                 | ''       | 'CH3478K1A01'    |'C0805_H57'| '(SMC0805AW)'                                                        | '0.047UF'  | '100V'        | '10%'    | 'DISCRETE' | 'CAP CHIP 0.047UF 100V(+-10%,X7R,0805)MUR'                     | 'CHIP0805'     | ''          | ''   | '20170809'
 '0.047UF'  | '100V'  | '10%'     | 'C0805'     | 'EMPTY'   | 'CH3478K1A01'(!)   = ''              | ''                 | ''       | 'CH3478K1A01'    |'C0805_H57'| '(SMC0805AW)'                                                        | 'NA'       | '100V'        | '10%'    | 'IO'       | 'CAP CHIP 0.047UF 100V(+-10%,X7R,0805)MUR'                     | 'CHIP0805'     | ''          | ''   | '20170809'
 '0.0082UF' | '50V'   | '5%'      | 'C0603'     | 'C0G'     | 'CH2826J0900'(!)   = 'End of Design' | 'Comp-Approve'     | ''       | 'CH2826J0900'    |'C0603'| '(SMC0603AW)'                                                        | '0.0082UF' | '50V'         | '5%'     | 'DISCRETE' | 'CAP CHIP 0.0082U 50V(+-5%,C0G,0603)'                          | 'CHIP0603'     | ''          | ''   | '20170817'
 '0.0082UF' | '50V'   | '5%'      | 'C0603'     | 'EMPTY'   | 'CH2826J0900'(!)   = 'End of Design' | 'Comp-Approve'     | ''       | 'CH2826J0900'    |'C0603'| '(SMC0603AW)'                                                        | 'NA'       | '50V'         | '5%'     | 'IO'       | 'CAP CHIP 0.0082U 50V(+-5%,C0G,0603)'                          | 'CHIP0603'     | ''          | ''   | '20170817'
 '0.47UF'   | '16V'   | '10%'     | 'C0402'     | 'X7R'     | 'CH4473K1B01'(!)   = 'End of Design' | 'Comp-Approve'     | ''       | 'CH4473K1B01'    |'C0402'| '(C0402-0201)'                                                       | '0.47UF'   | '16V'         | '10%'    | 'DISCRETE' | 'CAP CHIP 0.47U 16V(+-10%,X7R,0402)MUR'                        | 'CHIP0402'     | ''          | ''   | '20170817'
 '0.47UF'   | '16V'   | '10%'     | 'C0402'     | 'EMPTY'   | 'CH4473K1B01'(!)   = 'End of Design' | 'Comp-Approve'     | ''       | 'CH4473K1B01'    |'C0402'| '(C0402-0201)'                                                       | 'NA'       | '16V'         | '10%'    | 'IO'       | 'CAP CHIP 0.47U 16V(+-10%,X7R,0402)MUR'                        | 'CHIP0402'     | ''          | ''   | '20170817'
 '820PF'    | '100V'  | '5%'      | 'C0603'     | 'C0G'     | 'CH1828J0900'(!)   = 'End of Design' | 'Comp-Release Qty' | ''       | 'CH1828J0900'    |'C0603'| '(SMC0603AW)'                                                        | '820PF'    | '100V'        | '5%'     | 'DISCRETE' | 'CAP CHIP 820P 100V(+-5%,C0G,0603)'                            | 'CHIP0603'     | ''          | ''   | '20170821'
 '820PF'    | '100V'  | '5%'      | 'C0603'     | 'EMPTY'   | 'CH1828J0900'(!)   = 'End of Design' | 'Comp-Release Qty' | ''       | 'CH1828J0900'    |'C0603'| '(SMC0603AW)'                                                        | 'NA'       | '100V'        | '5%'     | 'IO'       | 'CAP CHIP 820P 100V(+-5%,C0G,0603)'                            | 'CHIP0603'     | ''          | ''   | '20170821'
 '33NF'     | '25V'   | '10%'     | 'C0402'     | 'X7R'     | 'CH3334K1B02'(!)   = ''              | ''                 | ''       | 'CH3334K1B02'    |'C0402'| '(C0402-0201)'                                                       | '33NF'     | '25V'         | '10%'    | 'DISCRETE' | 'CAP CHIP 33NF 25V(+-10%,X7R,0402)MUR'                         | 'CHIP0402'     | ''          | ''   | '20170904'
 '33NF'     | '25V'   | '10%'     | 'C0402'     | 'EMPTY'   | 'CH3334K1B02'(!)   = ''              | ''                 | ''       | 'CH3334K1B02'    |'C0402'| '(C0402-0201)'                                                       | 'NA'       | '25V'         | '10%'    | 'IO'       | 'CAP CHIP 33NF 25V(+-10%,X7R,0402)MUR'                         | 'CHIP0402'     | ''          | ''   | '20170904'
 '0.039UF'  | '50V'   | '10%'     | 'C0603'     | 'X7R'     | 'CH3396K1900'(!)   = ''              | ''                 | ''       | 'CH3396K1900'    |'C0603'| '(SMC0603AW)'                                                        | '0.039UF'  | '50V'         | '10%'    | 'DISCRETE' | 'CAP CHIP 0.039U 50V(+-10%,X7R,0603)'                          | 'CHIP0603'     | ''          | ''   | '20170918'
 '0.039UF'  | '50V'   | '10%'     | 'C0603'     | 'EMPTY'   | 'CH3396K1900'(!)   = ''              | ''                 | ''       | 'CH3396K1900'    |'C0603'| '(SMC0603AW)'                                                        | 'NA'       | '50V'         | '10%'    | 'IO'       | 'CAP CHIP 0.039U 50V(+-10%,X7R,0603)'                          | 'CHIP0603'     | ''          | ''   | '20170918'
 '100NF'    | '50V'   | '10%'     | 'C0402'     | 'X7R'     | 'CH4106K1B01'(!)   = ''              | ''                 | ''       | 'CH4106K1B01'    |'C0402'| '(C0402_OCTAGONXA,C0402-0201)'                                       | '100NF'    | '50V'         | '10%'    | 'DISCRETE' | 'CAP CHIP 100NF 50V(+-10%,X7R,0402)'                           | 'CHIP0402'     | ''          | ''   | '20171109'
 '100NF'    | '50V'   | '10%'     | 'C0402'     | 'EMPTY'   | 'CH4106K1B01'(!)   = ''              | ''                 | ''       | 'CH4106K1B01'    |'C0402'| '(C0402_OCTAGONXA,C0402-0201)'                                       | 'NA'       | '50V'         | '10%'    | 'IO'       | 'CAP CHIP 100NF 50V(+-10%,X7R,0402)'                           | 'CHIP0402'     | ''          | ''   | '20171109'
 '0.22UF'   | '25V'   | '10%'     | 'C0402'     | 'X7R'     | 'CH4224K1B01'(!)   = 'End of Design' | 'Comp-Release Qty' | ''       | 'CH4224K1B01'    |'C0402'| '(C0402_OCTAGONXA,C0402-0201)'                                       | '0.22UF'   | '25V'         | '10%'    | 'DISCRETE' | 'CAP CHIP 0.22U 25V(10%,X7R,0402)'                             | 'CHIP0402'     | ''          | ''   | '20171109'
 '0.22UF'   | '25V'   | '10%'     | 'C0402'     | 'EMPTY'   | 'CH4224K1B01'(!)   = 'End of Design' | 'Comp-Release Qty' | ''       | 'CH4224K1B01'    |'C0402'| '(C0402_OCTAGONXA,C0402-0201)'                                       | 'NA'       | '25V'         | '10%'    | 'IO'       | 'CAP CHIP 0.22U 25V(10%,X7R,0402)'                             | 'CHIP0402'     | ''          | ''   | '20171109'
 '1UF'      | '16V'   | '10%'     | '0603'      | 'X7R'     | 'TMP_QCH5103K1900'(!) = 'End of Design' | 'Comp-Approve'     | ''       | 'CH5103K1900'    |'C0603'| '(SMC0603AW)'                                                        | '1UF'      | '16V'         | '10%'    | 'DISCRETE' | 'CHIP0603'                                                     | 'CHIP0603'     | ''          | ''   | ''        
 '1UF'      | '16V'   | '10%'     | '0603'      | 'EMPTY'   | 'TMP_QCH5103K1900'(!) = 'End of Design' | 'Comp-Approve'     | ''       | 'CH5103K1900'    |'C0603'| '(SMC0603AW)'                                                        | 'NA'       | '16V'         | '10%'    | 'IO'       | 'CHIP0603'                                                     | 'CHIP0603'     | ''          | ''   | ''        
 '10UF'     | '6.3V'  | '20%'     | '0603'      | 'X5R'     | 'CH6101M9905'(!)   = 'End of Design' | 'Comp-Release Qty' | ''       | 'CH6101M9905'    |'C0603'| '(SMC0603AW)'                                                        | '10UF'     | '6.3V'        | '20%'    | 'DISCRETE' | 'CAP CHIP 10U 6.3V(+-20%,X5R,0603)'                            | 'CHIP0603'     | ''          | ''   | '2010701' 
 '10UF'     | '6.3V'  | '20%'     | '0603'      | 'EMPTY'   | 'CH6101M9905'(!)   = 'End of Design' | 'Comp-Release Qty' | ''       | 'CH6101M9905'    |'C0603'| '(SMC0603AW)'                                                        | 'NA'       | '6.3V'        | '20%'    | 'IO'       | 'CAP CHIP 10U 6.3V(+-20%,X5R,0603)'                            | 'CHIP0603'     | ''          | ''   | '2010701' 
 '10UF  '   | '16V '  | '10%'     | '0805'      | 'X5R'     | 'CH6103K9A00'(!)   = 'End of Design' | 'Comp-Approve'     | ''       | 'CH6103K9A00'    |'C0805_H61'| '(SMC0805AW)'                                                        | '10UF   '  | '16V'         | '10%'    | 'DISCRETE' | 'CAP CHIP 10U 16V(10%,X5R,0805)H1.25'                          | 'CHIP0805'     | ''          | ''   | '20100827'
 '10UF  '   | '16V '  | '10%'     | '0805'      | 'EMPTY'   | 'CH6103K9A00'(!)   = 'End of Design' | 'Comp-Approve'     | ''       | 'CH6103K9A00'    |'C0805_H61'| '(SMC0805AW)'                                                        | 'NA'       | '16V'         | '10%'    | 'IO'       | 'CAP CHIP 10U 16V(10%,X5R,0805)H1.25'                          | 'CHIP0805'     | ''          | ''   | '20100827'
 '22UF'     | '6.3V'  | '20%'     | '0805'      | 'X6S'     | 'CH6221MEA01'(!)   = 'End of Design' | 'Comp-Approve'     | ''       | 'CH6221MEA01'    |'C0805_H57'| '(SMC0805AW)'                                                        | '22UF'     | '6.3V'        | '20%'    | 'DISCRETE' | 'CAP CHIP 22U 6.3V(+-20%,X6S,0805)H1.25'                       | 'CHIP0805'     | ''          | ''   | '20101116'
 '22UF'     | '6.3V'  | '20%'     | '0805'      | 'EMPTY'   | 'CH6221MEA01'(!)   = 'End of Design' | 'Comp-Approve'     | ''       | 'CH6221MEA01'    |'C0805_H57'| '(SMC0805AW)'                                                        | 'NA'       | '6.3V'        | '20%'    | 'IO'       | 'CAP CHIP 22U 6.3V(+-20%,X6S,0805)H1.25'                       | 'CHIP0805'     | ''          | ''   | '20101116'
 '1UF'      | '6.3V'  | '20%'     | 'C0201'     | 'X6S'     | 'CH5101MEE01'(!)   = ''              | ''                 | ''       | 'CH5101MEE01'    |'C0201'| '(SMC0201AW)'                                                        | '1UF'      | '6.3V'        | '20%'    | 'DISCRETE' | 'CAP CHIP 1U 6.3V(+-20%,X6S,0201)'                             | 'CHIP0201'     | ''          | ''   | '20171115'
 '1UF'      | '6.3V'  | '20%'     | 'C0201'     | 'EMPTY'   | 'CH5101MEE01'(!)   = ''              | ''                 | ''       | 'CH5101MEE01'    |'C0201'| '(SMC0201AW)'                                                        | 'NA'       | '6.3V'        | '20%'    | 'IO'       | 'CAP CHIP 1U 6.3V(+-20%,X6S,0201)'                             | 'CHIP0201'     | ''          | ''   | '20171115'
 '0.22UF'   | '6.3V'  | '10%'     | 'C0201'     | 'X6S'     | 'CH4221KEE00'(!)   = ''              | ''                 | ''       | 'CH4221KEE00'    |'C0201'| '(SMC0201AW)'                                                        | '0.22UF'   | '6.3V'        | '10%'    | 'DISCRETE' | 'CAP CHIP 0.22UF 6.3V(+-10%,X6S,0201)'                         | 'CHIP0201'     | ''          | ''   | '20171116'
 '0.22UF'   | '6.3V'  | '10%'     | 'C0201'     | 'EMPTY'   | 'CH4221KEE00'(!)   = ''              | ''                 | ''       | 'CH4221KEE00'    |'C0201'| '(SMC0201AW)'                                                        | 'NA'       | '6.3V'        | '10%'    | 'IO'       | 'CAP CHIP 0.22UF 6.3V(+-10%,X6S,0201)'                         | 'CHIP0201'     | ''          | ''   | '20171116'
 '10UF'     | '4V'    | '20%'     | 'C0805'     | 'X6S'     | 'CH610KMEA03'(!)   = 'End of Design' | 'Comp-Approve'     | ''       | 'CH610KMEA03'    |'C0805_H57'| '(SMC0805AW)'                                                        | '10UF'     | '4V'          | '20%'    | 'DISCRETE' | 'CAP CHIP 10U,4V(+-20%,X6S,0805)MUR'                           | 'CHIP0805'     | ''          | ''   | '20171120'
 '10UF'     | '4V'    | '20%'     | 'C0805'     | 'EMPTY'   | 'CH610KMEA03'(!)   = 'End of Design' | 'Comp-Approve'     | ''       | 'CH610KMEA03'    |'C0805_H57'| '(SMC0805AW)'                                                        | 'NA'       | '4V'          | '20%'    | 'IO'       | 'CAP CHIP 10U,4V(+-20%,X6S,0805)MUR'                           | 'CHIP0805'     | ''          | ''   | '20171120'
 '0.01UF'   | '10V'   | '10%'     | 'C0201'     | 'X7R'     | 'CH3102K1E01'(!)   = ''              | ''                 | ''       | 'CH3102K1E01'    |'C0201'| '(SMC0201AW)'                                                        | '0.01UF'   | '10V'         | '10%'    | 'DISCRETE' | 'CAP CHIP 0.01UF 10V(10%,X7R,0201)'                            | 'CHIP0201'     | ''          | ''   | '20171121'
 '0.01UF'   | '10V'   | '10%'     | 'C0201'     | 'EMPTY'   | 'CH3102K1E01'(!)   = ''              | ''                 | ''       | 'CH3102K1E01'    |'C0201'| '(SMC0201AW)'                                                        | 'NA'       | '10V'         | '10%'    | 'IO'       | 'CAP CHIP 0.01UF 10V(10%,X7R,0201)'                            | 'CHIP0201'     | ''          | ''   | '20171121'
 '4.7UF'    | '25V'   | '10%'     | 'C0603'     | 'X6S'     | 'CH5474KE905'(!)   = 'End of Design' | 'Comp-Approve'     | ''       | 'CH5474KE905'    |'C0603'| '(SMC0603AW)'                                                        | '4.7UF'    | '25V'         | '10%'    | 'DISCRETE' | 'CAP CHIP 4.7U 25V(+-10%,X6S,0603)WTC'                         | 'CHIP0603'     | ''          | ''   | '20171121'
 '4.7UF'    | '25V'   | '10%'     | 'C0603'     | 'EMPTY'   | 'CH5474KE905'(!)   = 'End of Design' | 'Comp-Approve'     | ''       | 'CH5474KE905'    |'C0603'| '(SMC0603AW)'                                                        | 'NA'       | '25V'         | '10%'    | 'IO'       | 'CAP CHIP 4.7U 25V(+-10%,X6S,0603)WTC'                         | 'CHIP0603'     | ''          | ''   | '20171121'
 '1000PF'   | '16V'   | '5%'      | 'C0201'     | 'X7R'     | 'CH2103J1E01'(!)   = ''              | ''                 | ''       | 'CH2103J1E01'    |'C0201'| '(SMC0201AW)'                                                        | '1000PF'   | '16V'         | '5%'     | 'DISCRETE' | 'CAP CHIP 1000P 16V(+-5%,X7R,0201)'                            | 'CHIP0201'     | ''          | ''   | '20171121'
 '1000PF'   | '16V'   | '5%'      | 'C0201'     | 'EMPTY'   | 'CH2103J1E01'(!)   = ''              | ''                 | ''       | 'CH2103J1E01'    |'C0201'| '(SMC0201AW)'                                                        | 'NA'       | '16V'         | '5%'     | 'IO'       | 'CAP CHIP 1000P 16V(+-5%,X7R,0201)'                            | 'CHIP0201'     | ''          | ''   | '20171121'
 '22UF'     | '16V'   | '20%'     | 'C0805'     | 'X6S'     | 'CH6223MEA01'(!)   = ''              | ''                 | ''       | 'CH6223MEA01'    |'C0805_H57'| '(SMC0805AW)'                                                        | '22UF'     | '16V'         | '20%'    | 'DISCRETE' | 'CAP CHIP 22UF 16V(+-20%,X6S,0805)MUR'                         | 'CHIP0805'     | ''          | ''   | '20171127'
 '22UF'     | '16V'   | '20%'     | 'C0805'     | 'EMPTY'   | 'CH6223MEA01'(!)   = ''              | ''                 | ''       | 'CH6223MEA01'    |'C0805_H57'| '(SMC0805AW)'                                                        | 'NA'       | '16V'         | '20%'    | 'IO'       | 'CAP CHIP 22UF 16V(+-20%,X6S,0805)MUR'                         | 'CHIP0805'     | ''          | ''   | '20171127'
 '47UF'     | '6.3V'  | '20%'     | 'C0805'     | 'X5R'     | 'CH6471M9A08'(!)   = ''              | ''                 | ''       | 'CH6471M9A08'    |'C0805_H57'| '(SMC0805AW)'                                                        | '47UF'     | '6.3V'        | '20%'    | 'DISCRETE' | 'CAP CHIP 47U 6.3V(+-20%,X5R,0805)MUR'                         | 'CHIP0805'     | ''          | ''   | '20171206'
 '47UF'     | '6.3V'  | '20%'     | 'C0805'     | 'EMPTY'   | 'CH6471M9A08'(!)   = ''              | ''                 | ''       | 'CH6471M9A08'    |'C0805_H57'| '(SMC0805AW)'                                                        | 'NA'       | '6.3V'        | '20%'    | 'IO'       | 'CAP CHIP 47U 6.3V(+-20%,X5R,0805)MUR'                         | 'CHIP0805'     | ''          | ''   | '20171206'
 '0.1UF'    | '25V'   | '10%'     | 'C0402'     | 'X7R'     | 'CH4104K1B11'(!)   = ''              | ''                 | ''       | 'CH4104K1B11'    |'C0402'| '(C0402-0201)'                                                       | '0.1UF'    | '25V'         | '10%'    | 'DISCRETE' | 'CAP CHIP 0.1U 25V(+-10%,X7R,0402)TAY'                         | 'CHIP0402'     | ''          | ''   | '20171212'
 '0.1UF'    | '25V'   | '10%'     | 'C0402'     | 'EMPTY'   | 'CH4104K1B11'(!)   = ''              | ''                 | ''       | 'CH4104K1B11'    |'C0402'| '(C0402-0201)'                                                       | 'NA'       | '25V'         | '10%'    | 'IO'       | 'CAP CHIP 0.1U 25V(+-10%,X7R,0402)TAY'                         | 'CHIP0402'     | ''          | ''   | '20171212'
 '10UF'     | '16V'   | '20%'     | 'C0603'     | 'X5R'     | 'CH6103M9900'(!)   = ''              | ''                 | ''       | 'CH6103M9900'    |'C0603_H40'| '(SMC0603AW)'                                                        | '10UF'     | '16V'         | '20%'    | 'DISCRETE' | 'CAP CHIP 10U 16V(+-20%,X5R,0603)'                             | 'CHIP0603'     | ''          | ''   | '20171221'
 '10UF'     | '16V'   | '20%'     | 'C0603'     | 'EMPTY'   | 'CH6103M9900'(!)   = ''              | ''                 | ''       | 'CH6103M9900'    |'C0603_H40'| '(SMC0603AW)'                                                        | 'NA'       | '16V'         | '20%'    | 'IO'       | 'CAP CHIP 10U 16V(+-20%,X5R,0603)'                             | 'CHIP0603'     | ''          | ''   | '20171221'
 '0.1UF'    | '25V'   | '10%'     | 'C0402'     | 'X6S'     | 'CH4104KEB00'(!)   = 'End of Design' | 'Comp-Approve'     | ''       | 'CH4104KEB00'    |'C0402'| '(C0402-0201)'                                                       | '0.1UF'    | '25V'         | '10%'    | 'DISCRETE' | 'CAP CHIP 0.1U 25V(+-10%,X6S,0402)'                            | 'CHIP0402'     | ''          | ''   | '20171221'
 '0.1UF'    | '25V'   | '10%'     | 'C0402'     | 'EMPTY'   | 'CH4104KEB00'(!)   = 'End of Design' | 'Comp-Approve'     | ''       | 'CH4104KEB00'    |'C0402'| '(C0402-0201)'                                                       | 'NA'       | '25V'         | '10%'    | 'IO'       | 'CAP CHIP 0.1U 25V(+-10%,X6S,0402)'                            | 'CHIP0402'     | ''          | ''   | '20171221'
 '1UF'      | '6.3V'  | '10%'     | 'C0201'     | 'X5R'     | 'CH5101K9E02'(!)   = 'End of Design' | 'Comp-Release Qty' | ''       | 'CH5101K9E02'    |'C0201'| '(SMC0201AW)'                                                        | '1UF'      | '6.3V'        | '10%'    | 'DISCRETE' | 'CAP CHIP 1U 6.3V(+-10%,X5R,0201)'                             | 'CHIP0201'     | ''          | ''   | '20171221'
 '1UF'      | '6.3V'  | '10%'     | 'C0201'     | 'EMPTY'   | 'CH5101K9E02'(!)   = 'End of Design' | 'Comp-Release Qty' | ''       | 'CH5101K9E02'    |'C0201'| '(SMC0201AW)'                                                        | 'NA'       | '6.3V'        | '10%'    | 'IO'       | 'CAP CHIP 1U 6.3V(+-10%,X5R,0201)'                             | 'CHIP0201'     | ''          | ''   | '20171221'
 '4.7UF'    | '10V'   | '10%'     | 'C0402'     | 'X5R'     | 'CH5472K9B02'(!)   = ''              | ''                 | ''       | 'CH5472K9B02'    |'C0402'| '(C0402-0201)'                                                       | '4.7UF'    | '10V'         | '10%'    | 'DISCRETE' | 'CAP CHIP 4.7U 10V(+-10%,X5R,0402)MUR'                         | 'CHIP0402'     | ''          | ''   | '20171222'
 '4.7UF'    | '10V'   | '10%'     | 'C0402'     | 'EMPTY'   | 'CH5472K9B02'(!)   = ''              | ''                 | ''       | 'CH5472K9B02'    |'C0402'| '(C0402-0201)'                                                       | 'NA'       | '10V'         | '10%'    | 'IO'       | 'CAP CHIP 4.7U 10V(+-10%,X5R,0402)MUR'                         | 'CHIP0402'     | ''          | ''   | '20171222'
 '270PF'    | '25V'   | '5%'      | 'C0402'     | 'NPO'     | 'CH12704JB07'(!)   = ''              | ''                 | ''       | 'CH12704JB07'    |'C0402'| '(C0402-0201)'                                                       | ' 270PF'   | '25V'         | '5%'     | 'DISCRETE' | 'CAP CHIP 270P 25V(+-5%,NPO,0402)'                             | 'CHIP0402'     | ''          | ''   | '20180126'
 '270PF'    | '25V'   | '5%'      | 'C0402'     | 'EMPTY'   | 'CH12704JB07'(!)   = ''              | ''                 | ''       | 'CH12704JB07'    |'C0402'| '(C0402-0201)'                                                       | 'NA'       | '25V'         | '5%'     | 'IO'       | 'CAP CHIP 270P 25V(+-5%,NPO,0402)'                             | 'CHIP0402'     | ''          | ''   | '20180126'
 '22UF'     | '4V'    | '20%'     | 'C0402'     | 'X6S'     | 'CH622KMEB01'(!)   = ''              | ''                 | ''       | 'CH622KMEB01'    |'C0402_H32'| '(C0402_OCTAGONXA,C0402-0201_H32)'                                   | '22UF'     | '4V'          | '20%'    | 'DISCRETE' | 'CAP CHIP 22UF 4V(+-20%,X6S,0402)MUR'                          | 'CHIP0402'     | ''          | ''   | '20180313'
 '22UF'     | '4V'    | '20%'     | 'C0402'     | 'EMPTY'   | 'CH622KMEB01'(!)   = ''              | ''                 | ''       | 'CH622KMEB01'    |'C0402_H32'| '(C0402_OCTAGONXA,C0402-0201_H32)'                                   | 'NA'       | '4V'          | '20%'    | 'IO'       | 'CAP CHIP 22UF 4V(+-20%,X6S,0402)MUR'                          | 'CHIP0402'     | ''          | ''   | '20180313'
 '1UF'      | '10V'   | '20%'     | 'C0201'     | 'X5R'     | 'CH5102M9E01'(!)   = ''              | ''                 | ''       | 'CH5102M9E01'    |'C0201'| '(SMC0201AW)'                                                        | '1UF'      | '10V'         | '20%'    | 'DISCRETE' | 'CAP CHIP 1UF 10V(+-20%,X5R,0201)'                             | 'CHIP0201'     | ''          | ''   | '20180320'
 '1UF'      | '10V'   | '20%'     | 'C0201'     | 'EMPTY'   | 'CH5102M9E01'(!)   = ''              | ''                 | ''       | 'CH5102M9E01'    |'C0201'| '(SMC0201AW)'                                                        | 'NA'       | '10V'         | '20%'    | 'IO'       | 'CAP CHIP 1UF 10V(+-20%,X5R,0201)'                             | 'CHIP0201'     | ''          | ''   | '20180320'
 '1UF'      | '25V'   | '10%'     | 'C0402'     | 'X7S'     | 'CH5104K6B00'(!)   = ''              | ''                 | ''       | 'CH5104K6B00'    |'C0402_H28'| '(C0402-0201_H28)'                                                   | '1UF'      | '25V'         | '10%'    | 'DISCRETE' | 'CAP CHIP 1U 25V (+-10%, X7S, 0402)MUR'                        | 'CHIP0402'     | ''          | ''   | '20180403'
 '1UF'      | '25V'   | '10%'     | 'C0402'     | 'EMPTY'   | 'CH5104K6B00'(!)   = ''              | ''                 | ''       | 'CH5104K6B00'    |'C0402_H28'| '(C0402-0201_H28)'                                                   | 'NA'       | '25V'         | '10%'    | 'IO'       | 'CAP CHIP 1U 25V (+-10%, X7S, 0402)MUR'                        | 'CHIP0402'     | ''          | ''   | '20180403'
 '0.1UF'    | '16V'   | '10%'     | 'C0201'     | 'X6S'     | 'CH4103KEE03'(!)   = ''              | ''                 | ''       | 'CH4103KEE03'    |'C0201'| '(C0201_HOME-PLATE_H22)'                                             | '0.1UF'    | '16V'         | '10%'    | 'DISCRETE' | 'CAP CHIP 0.1UF 16V(+-10%,X6S,0201)MUR'                        | 'CHIP0201'     | ''          | ''   | '20180403'
 '0.1UF'    | '16V'   | '10%'     | 'C0201'     | 'EMPTY'   | 'CH4103KEE03'(!)   = ''              | ''                 | ''       | 'CH4103KEE03'    |'C0201'| '(C0201_HOME-PLATE_H22)'                                             | 'NA'       | '16V'         | '10%'    | 'IO'       | 'CAP CHIP 0.1UF 16V(+-10%,X6S,0201)MUR'                        | 'CHIP0201'     | ''          | ''   | '20180403'
 '0.01U'    | '25V'   | '5%'      | 'C0402'     | 'X7R'     | 'CH3104J1B01'(!)   = ''              | ''                 | ''       | 'CH3104J1B01'    |'C0402'| '(C0402-0201)'                                                       | '0.01UF'   | '25V'         | '5%'     | 'DISCRETE' | 'CAP CHIP 0.01U 25V (+-5%,X7R,0402)MUR'                        | 'CHIP0402'     | ''          | ''   | '20180403'
 '0.01U'    | '25V'   | '5%'      | 'C0402'     | 'EMPTY'   | 'CH3104J1B01'(!)   = ''              | ''                 | ''       | 'CH3104J1B01'    |'C0402'| '(C0402-0201)'                                                       | 'NA'       | '25V'         | '5%'     | 'IO'       | 'CAP CHIP 0.01U 25V (+-5%,X7R,0402)MUR'                        | 'CHIP0402'     | ''          | ''   | '20180403'
 '22UF'     | '4V'    | '20%'     | 'C0402'     | 'X6S'     | 'CH622KMEB02'(!)   = 'End of Design' | 'Comp-Approve'     | ''       | 'CH622KMEB02'    |'C0402_H32'| '(C0402-0201_H32,C0402_OCTAGONXA)'                                   | '22UF'     | '4V'          | '20%'    | 'DISCRETE' | 'CAP CHIP 22UF 4V(+-20%,X6S,0402)'                             | 'CHIP0402'     | ''          | ''   | '20180409'
 '22UF'     | '4V'    | '20%'     | 'C0402'     | 'EMPTY'   | 'CH622KMEB02'(!)   = 'End of Design' | 'Comp-Approve'     | ''       | 'CH622KMEB02'    |'C0402_H32'| '(C0402-0201_H32,C0402_OCTAGONXA)'                                   | 'NA'       | '4V'          | '20%'    | 'IO'       | 'CAP CHIP 22UF 4V(+-20%,X6S,0402)'                             | 'CHIP0402'     | ''          | ''   | '20180409'
 '1000PF'   | '25V'   | '5%'      | 'C0402'     | 'NPO'     | 'CH2104J0B00'(!)   = ''              | ''                 | ''       | 'CH2104J0B00'    |'C0402'| '(C0402-0201)'                                                       | '1000PF'   | '25V'         | '5%'     | 'DISCRETE' | 'CAP CHIP 1000PF 25V (5%,NPO,0402)'                            | 'CHIP0402'     | ''          | ''   | '20180419'
 '1000PF'   | '25V'   | '5%'      | 'C0402'     | 'EMPTY'   | 'CH2104J0B00'(!)   = ''              | ''                 | ''       | 'CH2104J0B00'    |'C0402'| '(C0402-0201)'                                                       | 'NA'       | '25V'         | '5%'     | 'IO'       | 'CAP CHIP 1000PF 25V (5%,NPO,0402)'                            | 'CHIP0402'     | ''          | ''   | '20180419'
 '1.4UF'    | '50V'   | '5%'      | 'C1812'     | 'U2J'     | 'CH5146JF400'(!)   = 'End of Design' | 'P/N Release'      | ''       | 'CH5146JF400'    |'C1812_X3'| '(SMC1812AW)'                                                        | '1.4UF'    | '50V'         | '5%'     | 'DISCRETE' | 'CAP CHIP 1.4UF 50V(5%,U2J,1812)KEM'                           | 'CHIP1812'     | ''          | ''   | '20180423'
 '1.4UF'    | '50V'   | '5%'      | 'C1812'     | 'EMPTY'   | 'CH5146JF400'(!)   = 'End of Design' | 'P/N Release'      | ''       | 'CH5146JF400'    |'C1812_X3'| '(SMC1812AW)'                                                        | 'NA'       | '50V'         | '5%'     | 'IO'       | 'CAP CHIP 1.4UF 50V(5%,U2J,1812)KEM'                           | 'CHIP1812'     | ''          | ''   | '20180423'
 '10UF'     | '100V'  | '10%'     | 'C1210'     | 'X7S'     | 'CH6108K6300'(!)   = ''              | ''                 | ''       | 'CH6108K6300'    |'C1210_GRM32E'| '(SMC1210AW)'                                                        | '10UF'     | '100V'        | '10%'    | 'DISCRETE' | 'CAP CHIP 10UF 100V(+-10%,X7S,1210)MUR'                        | 'CHIP1210'     | ''          | ''   | '20180423'
 '10UF'     | '100V'  | '10%'     | 'C1210'     | 'EMPTY'   | 'CH6108K6300'(!)   = ''              | ''                 | ''       | 'CH6108K6300'    |'C1210_GRM32E'| '(SMC1210AW)'                                                        | 'NA'       | '100V'        | '10%'    | 'IO'       | 'CAP CHIP 10UF 100V(+-10%,X7S,1210)MUR'                        | 'CHIP1210'     | ''          | ''   | '20180423'
 '0.1UF'    | '6.3V'  | '10%'     | 'C0402'     | 'X7R'     | 'CH4101K1B01'(!)   = 'End of Design' | 'Comp-Approve'     | ''       | 'CH4101K1B01'    |'C0402'| '(C0402-0201)'                                                       | '0.1UF'    | '6.3V'        | '10%'    | 'DISCRETE' | 'CAP CHIP 0.1UF 6.3V(+-10%,X7R,0402)MUR'                       | 'CHIP0402'     | ''          | ''   | '20150729'
 '0.1UF'    | '6.3V'  | '10%'     | 'C0402'     | 'EMPTY'   | 'CH4101K1B01'(!)   = 'End of Design' | 'Comp-Approve'     | ''       | 'CH4101K1B01'    |'C0402'| '(C0402-0201)'                                                       | 'NA'       | '6.3V'        | '10%'    | 'IO'       | 'CAP CHIP 0.1UF 6.3V(+-10%,X7R,0402)MUR'                       | 'CHIP0402'     | ''          | ''   | '20150729'
 '0.22UF'   | '25V'   | '10%'     | 'C0402'     | 'X7R'     | 'CH4224K1B03'(!)   = 'End of Design' | 'Comp-Approve'     | ''       | 'CH4224K1B03'    |'C0402'| '(C0402-0201)'                                                       | '0.22UF'   | '25V'         | '10%'    | 'DISCRETE' | 'CAP CHIP 0.22UF 25V(10%,X7R,0402)MUR'                         | 'CHIP0402'     | ''          | ''   | '20180430'
 '0.22UF'   | '25V'   | '10%'     | 'C0402'     | 'EMPTY'   | 'CH4224K1B03'(!)   = 'End of Design' | 'Comp-Approve'     | ''       | 'CH4224K1B03'    |'C0402'| '(C0402-0201)'                                                       | 'NA'       | '25V'         | '10%'    | 'IO'       | 'CAP CHIP 0.22UF 25V(10%,X7R,0402)MUR'                         | 'CHIP0402'     | ''          | ''   | '20180430'
 '68PF'     | '50V'   | '5%'      | 'C0402'     | 'C0G'     | 'CH0686J0B11'(!)   = ''              | ''                 | ''       | 'CH0686J0B11'    |'C0402'| '(C0402-0201)'                                                       | '68PF'     | '50V'         | '5%'     | 'DISCRETE' | 'CAP CHIP 68P 50V(+-5%,C0G,0402)MUR'                           | 'CHIP0402'     | ''          | ''   | '20171026'
 '68PF'     | '50V'   | '5%'      | 'C0402'     | 'EMPTY'   | 'CH0686J0B11'(!)   = ''              | ''                 | ''       | 'CH0686J0B11'    |'C0402'| '(C0402-0201)'                                                       | 'NA'       | '50V'         | '5%'     | 'IO'       | 'CAP CHIP 68P 50V(+-5%,C0G,0402)MUR'                           | 'CHIP0402'     | ''          | ''   | '20171026'
 '1000PF'   | '100V'  | '5%'      | 'C1206'     | 'NPO'     | 'CH2108J0200'(!)   = ''              | ''                 | ''       | 'CH2108J0200'    |'C1206XC'| '(SMC1206AW)'                                                        | '1000PF'   | '100V'        | '5%'     | 'DISCRETE' | 'CAP CHIP 1000PF 100V(+-5%,NPO,1206)'                          | 'CHIP1206'     | ''          | ''   | '20180516'
 '1000PF'   | '100V'  | '5%'      | 'C1206'     | 'EMPTY'   | 'CH2108J0200'(!)   = ''              | ''                 | ''       | 'CH2108J0200'    |'C1206XC'| '(SMC1206AW)'                                                        | 'NA'       | '100V'        | '5%'     | 'IO'       | 'CAP CHIP 1000PF 100V(+-5%,NPO,1206)'                          | 'CHIP1206'     | ''          | ''   | '20180516'
 '1000PF'   | '100V'  | '10%'     | 'C0805'     | 'C0G'     | 'CH2108K0A00'(!)   = ''              | ''                 | ''       | 'CH2108K0A00'    |'C0805_H43'| '(SMC0805AW)'                                                        | '1000PF'   | '100V'        | '10%'    | 'DISCRETE' | 'CAP CHIP 1000PF 100V(+-10%,C0G,0805)KEM'                      | 'CHIP0805'     | ''          | ''   | '20180522'
 '1000PF'   | '100V'  | '10%'     | 'C0805'     | 'EMPTY'   | 'CH2108K0A00'(!)   = ''              | ''                 | ''       | 'CH2108K0A00'    |'C0805_H43'| '(SMC0805AW)'                                                        | 'NA'       | '100V'        | '10%'    | 'IO'       | 'CAP CHIP 1000PF 100V(+-10%,C0G,0805)KEM'                      | 'CHIP0805'     | ''          | ''   | '20180522'
 '1000PF'   | '100V'  | '10%'     | 'C0805'     | 'X7R'     | 'CH2108K1A00'(!)   = ''              | ''                 | ''       | 'CH2108K1A00'    |'C0805'| '(SMC0805AW)'                                                        | '1000PF'   | '100V'        | '10%'    | 'DISCRETE' | 'CAP CHIP 1000PF 100V(+-10%,X7R,0805)YGO'                      | 'CHIP0805'     | ''          | ''   | '20180522'
 '1000PF'   | '100V'  | '10%'     | 'C0805'     | 'EMPTY'   | 'CH2108K1A00'(!)   = ''              | ''                 | ''       | 'CH2108K1A00'    |'C0805'| '(SMC0805AW)'                                                        | 'NA'       | '100V'        | '10%'    | 'IO'       | 'CAP CHIP 1000PF 100V(+-10%,X7R,0805)YGO'                      | 'CHIP0805'     | ''          | ''   | '20180522'
 '1000PF'   | '100V'  | '1%'      | 'C0805'     | 'NPO'     | 'CH2108F0A00'(!)   = ''              | ''                 | ''       | 'CH2108F0A00'    |'C0805'| '(SMC0805AW)'                                                        | '1000PF'   | '100V'        | '1%'     | 'DISCRETE' | 'CAP CHIP 1000PF 100V(+-1%,NPO,0805)YGO'                       | 'CHIP0805'     | ''          | ''   | '20180523'
 '1000PF'   | '100V'  | '1%'      | 'C0805'     | 'EMPTY'   | 'CH2108F0A00'(!)   = ''              | ''                 | ''       | 'CH2108F0A00'    |'C0805'| '(SMC0805AW)'                                                        | 'NA'       | '100V'        | '1%'     | 'IO'       | 'CAP CHIP 1000PF 100V(+-1%,NPO,0805)YGO'                       | 'CHIP0805'     | ''          | ''   | '20180523'
 '5.6PF'    | '50V'   | '0.1PF'   | 'C0402'     | 'NP0'     | 'CH-566B0100'(!)   = ''              | ''                 | ''       | 'CH-566B0100'    |'C0402'| '(C0402-0201)'                                                       | '5.6PF'    | '50V'         | '0.1PF'  | 'DISCRETE' | 'CAP CHIP 5.6PF 50V(+-0.1PF,NP0,0402)'                         | 'CHIP0402'     | ''          | ''   | '20180528'
 '5.6PF'    | '50V'   | '0.1PF'   | 'C0402'     | 'EMPTY'   | 'CH-566B0100'(!)   = ''              | ''                 | ''       | 'CH-566B0100'    |'C0402'| '(C0402-0201)'                                                       | 'NA'       | '50V'         | '0.1PF'  | 'IO'       | 'CAP CHIP 5.6PF 50V(+-0.1PF,NP0,0402)'                         | 'CHIP0402'     | ''          | ''   | '20180528'
 '4.7UF'    | '16V'   | '10%'     | 'C0603'     | 'X6S'     | 'CH5473KE902'(!)   = ''              | ''                 | ''       | 'CH5473KE902'    |'C0603_H40'| '(SMC0603AW)'                                                        | '4.7UF'    | '16V'         | '10%'    | 'DISCRETE' | 'CAP CHIP 4.7UF 16V(+-10%,X6S,0603)'                           | 'CHIP0603'     | ''          | ''   | '20180627'
 '4.7UF'    | '16V'   | '10%'     | 'C0603'     | 'EMPTY'   | 'CH5473KE902'(!)   = ''              | ''                 | ''       | 'CH5473KE902'    |'C0603_H40'| '(SMC0603AW)'                                                        | 'NA'       | '16V'         | '10%'    | 'IO'       | 'CAP CHIP 4.7UF 16V(+-10%,X6S,0603)'                           | 'CHIP0603'     | ''          | ''   | '20180627'
 '10UF'     | '16V'   | '10%'     | 'C0805'     | 'X6S'     | 'CH6103KEA00'(!)   = ''              | ''                 | ''       | 'CH6103KEA00'    |'C0805_H57'| '(SMC0805AW)'                                                        | '10UF'     | '16V'         | '10%'    | 'DISCRETE' | 'CAP CHIP 10UF 16V(+-10%,X6S,0805)'                            | 'CHIP0805'     | ''          | ''   | '20180706'
 '10UF'     | '16V'   | '10%'     | 'C0805'     | 'EMPTY'   | 'CH6103KEA00'(!)   = ''              | ''                 | ''       | 'CH6103KEA00'    |'C0805_H57'| '(SMC0805AW)'                                                        | 'NA'       | '16V'         | '10%'    | 'IO'       | 'CAP CHIP 10UF 16V(+-10%,X6S,0805)'                            | 'CHIP0805'     | ''          | ''   | '20180706'
 '1NF'      | '50V'   | '10%'     | 'C0402'     | 'X7R'     | 'CH2106K1B23'(!)   = ''              | ''                 | ''       | 'CH2106K1B23'    |'C0402'| '(C0402-0201)'                                                       | '1NF'      | '50V'         | '10%'    | 'DISCRETE' | 'CAP CHIP 1N 50V(+-10%,X7R,0402)TAY'                           | 'CHIP0402'     | ''          | ''   | '20180710'
 '1NF'      | '50V'   | '10%'     | 'C0402'     | 'EMPTY'   | 'CH2106K1B23'(!)   = ''              | ''                 | ''       | 'CH2106K1B23'    |'C0402'| '(C0402-0201)'                                                       | 'NA'       | '50V'         | '10%'    | 'IO'       | 'CAP CHIP 1N 50V(+-10%,X7R,0402)TAY'                           | 'CHIP0402'     | ''          | ''   | '20180710'
 '0.01UF'   | '16V'   | '10%'     | 'C0402'     | 'X7R'     | 'CH3103K1B15'(!)   = 'End of Design' | 'Comp-Approve'     | ''       | 'CH3103K1B15'    |'C0402'| '(C0402_OCTAGON,C0402_SMDC25_SM30,C0402-0201)'                       | '0.01UF'   | '16V'         | '10%'    | 'DISCRETE' | 'CAP CHIP 0.01U 16V(10%,X7R,0402)'                             | 'CHIP0402'     | ''          | ''   | '20150911'
 '0.01UF'   | '16V'   | '10%'     | 'C0402'     | 'EMPTY'   | 'CH3103K1B15'(!)   = 'End of Design' | 'Comp-Approve'     | ''       | 'CH3103K1B15'    |'C0402'| '(C0402_OCTAGON,C0402_SMDC25_SM30,C0402-0201)'                       | 'NA'       | '16V'         | '10%'    | 'IO'       | 'CAP CHIP 0.01U 16V(10%,X7R,0402)'                             | 'CHIP0402'     | ''          | ''   | '20150911'
 '0.1UF'    | '100V'  | '10%'     | 'C0805'     | 'X7R'     | 'CH4108K1A06'(!)   = ''              | ''                 | ''       | 'CH4108K1A06'    |'C0805_H43'| '(SMC0805AW)'                                                        | '0.1UF'    | '100V'        | '10%'    | 'DISCRETE' | 'CAP CHIP 0.1UF 100V(+-10%,X7R,0805)WTC'                       | 'CHIP0805'     | ''          | ''   | '20180720'
 '0.1UF'    | '100V'  | '10%'     | 'C0805'     | 'EMPTY'   | 'CH4108K1A06'(!)   = ''              | ''                 | ''       | 'CH4108K1A06'    |'C0805_H43'| '(SMC0805AW)'                                                        | 'NA'       | '100V'        | '10%'    | 'IO'       | 'CAP CHIP 0.1UF 100V(+-10%,X7R,0805)WTC'                       | 'CHIP0805'     | ''          | ''   | '20180720'
 '0.1UF'    | '100V'  | '10%'     | 'C0805'     | 'X7R'     | 'CH4108K1A05'(!)   = ''              | ''                 | ''       | 'CH4108K1A05'    |'C0805_H57'| '(SMC0805AW)'                                                        | '0.1UF'    | '100V'        | '10%'    | 'DISCRETE' | 'CAP CHIP 0.1UF 100V(+-10%,X7R,0805)YGO'                       | 'CHIP0805'     | ''          | ''   | '20180723'
 '0.1UF'    | '100V'  | '10%'     | 'C0805'     | 'EMPTY'   | 'CH4108K1A05'(!)   = ''              | ''                 | ''       | 'CH4108K1A05'    |'C0805_H57'| '(SMC0805AW)'                                                        | 'NA'       | '100V'        | '10%'    | 'IO'       | 'CAP CHIP 0.1UF 100V(+-10%,X7R,0805)YGO'                       | 'CHIP0805'     | ''          | ''   | '20180723'
 '0.01UF'   | '1KV'   | '10%'     | 'C1206'     | 'X7R'     | 'CH310FK1204'(!)   = ''              | ''                 | ''       | 'CH310FK1204'    |'C1206_H66'| '(SMC1206AW)'                                                        | '0.01UF'   | '1KV'         | '10%'    | 'DISCRETE' | 'CAP CHIP 0.01U 1KV(+-10%,X7R,1206)YGO'                        | 'CHIP1206'     | ''          | ''   | '20180724'
 '0.01UF'   | '1KV'   | '10%'     | 'C1206'     | 'EMPTY'   | 'CH310FK1204'(!)   = ''              | ''                 | ''       | 'CH310FK1204'    |'C1206_H66'| '(SMC1206AW)'                                                        | 'NA'       | '1KV'         | '10%'    | 'IO'       | 'CAP CHIP 0.01U 1KV(+-10%,X7R,1206)YGO'                        | 'CHIP1206'     | ''          | ''   | '20180724'
 '0.1UF'    | '100V'  | '10%'     | 'C1206'     | 'X7R'     | 'CH4108K1208'(!)   = ''              | ''                 | ''       | 'CH4108K1208'    |'C1206_H76'| '(SMC1206AW)'                                                        | '0.1UF'    | '100V'        | '10%'    | 'DISCRETE' | 'CAP CHIP 0.1UF 100V(+-10%,X7R,1206)TAY'                       | 'CHIP1206'     | ''          | ''   | '20180731'
 '0.1UF'    | '100V'  | '10%'     | 'C1206'     | 'EMPTY'   | 'CH4108K1208'(!)   = ''              | ''                 | ''       | 'CH4108K1208'    |'C1206_H76'| '(SMC1206AW)'                                                        | 'NA'       | '100V'        | '10%'    | 'IO'       | 'CAP CHIP 0.1UF 100V(+-10%,X7R,1206)TAY'                       | 'CHIP1206'     | ''          | ''   | '20180731'
 '1U'       | '100V'  | '10%'     | 'C1206'     | 'X7R'     | 'CH5108K1204'(!)   = ''              | ''                 | ''       | 'CH5108K1204'    |'C1206_H76'| '(SMC1206AW)'                                                        | '1U'       | '100V'        | '10%'    | 'DISCRETE' | 'CAP CHIP 1U 100V(10%,X7R,1206)SAM'                            | 'CHIP1206'     | ''          | ''   | '20180801'
 '1U'       | '100V'  | '10%'     | 'C1206'     | 'EMPTY'   | 'CH5108K1204'(!)   = ''              | ''                 | ''       | 'CH5108K1204'    |'C1206_H76'| '(SMC1206AW)'                                                        | 'NA'       | '100V'        | '10%'    | 'IO'       | 'CAP CHIP 1U 100V(10%,X7R,1206)SAM'                            | 'CHIP1206'     | ''          | ''   | '20180801'
 '4.7U'     | '100V'  | '10%'     | 'C1206'     | 'X7S'     | 'CH5478K6200'(!)   = ''              | ''                 | ''       | 'CH5478K6200'    |'C1206XB'| '(SMC1206AW)'                                                        | '4.7U'     | '100V'        | '10%'    | 'DISCRETE' | 'CAP CHIP 4.7U 100V(10%,X7S,1206)MUR'                          | 'CHIP1206'     | ''          | ''   | '20180803'
 '4.7U'     | '100V'  | '10%'     | 'C1206'     | 'EMPTY'   | 'CH5478K6200'(!)   = ''              | ''                 | ''       | 'CH5478K6200'    |'C1206XB'| '(SMC1206AW)'                                                        | 'NA'       | '100V'        | '10%'    | 'IO'       | 'CAP CHIP 4.7U 100V(10%,X7S,1206)MUR'                          | 'CHIP1206'     | ''          | ''   | '20180803'
 '4700PF'   | '25V'   | '10%'     | 'C0402'     | 'X7R'     | 'CH2474K1B18'(!)   = ''              | ''                 | ''       | 'CH2474K1B18'    |'C0402'| '(C0402-0201)'                                                       | '4700PF'   | '25V'         | '10%'    | 'DISCRETE' | 'CAP CHIP 4700P 25V(+-10%,X7R,0402)WTC'                        | 'CHIP0402'     | ''          | ''   | '20180904'
 '4700PF'   | '25V'   | '10%'     | 'C0402'     | 'EMPTY'   | 'CH2474K1B18'(!)   = ''              | ''                 | ''       | 'CH2474K1B18'    |'C0402'| '(C0402-0201)'                                                       | 'NA'       | '25V'         | '10%'    | 'IO'       | 'CAP CHIP 4700P 25V(+-10%,X7R,0402)WTC'                        | 'CHIP0402'     | ''          | ''   | '20180904'
 '0.022UF'  | '25V'   | '10%'     | 'C0402'     | 'X7R'     | 'CH3224K1B09'(!)   = ''              | ''                 | ''       | 'CH3224K1B09'    |'C0402'| '(C0402-0201)'                                                       | '0.022UF'  | '25V'         | '10%'    | 'DISCRETE' | 'CAP CHIP 0.022U 25V(+-10%,X7R,0402)WTC'                       | 'CHIP0402'     | ''          | ''   | '20180904'
 '0.022UF'  | '25V'   | '10%'     | 'C0402'     | 'EMPTY'   | 'CH3224K1B09'(!)   = ''              | ''                 | ''       | 'CH3224K1B09'    |'C0402'| '(C0402-0201)'                                                       | 'NA'       | '25V'         | '10%'    | 'IO'       | 'CAP CHIP 0.022U 25V(+-10%,X7R,0402)WTC'                       | 'CHIP0402'     | ''          | ''   | '20180904'
 '0.047UF'  | '50V'   | '10%'     | 'C0402'     | 'X7R'     | 'CH3476K1B04'(!)   = ''              | ''                 | ''       | 'CH3476K1B04'    |'C0402_H28'| '(C0402-0201_H28)'                                                   | '0.047UF'  | '50V'         | '10%'    | 'DISCRETE' | 'CAP CHIP 0.047U 50V(+-10%,X7R,0402)WTC'                       | 'CHIP0402'     | ''          | ''   | '20180904'
 '0.047UF'  | '50V'   | '10%'     | 'C0402'     | 'EMPTY'   | 'CH3476K1B04'(!)   = ''              | ''                 | ''       | 'CH3476K1B04'    |'C0402_H28'| '(C0402-0201_H28)'                                                   | 'NA'       | '50V'         | '10%'    | 'IO'       | 'CAP CHIP 0.047U 50V(+-10%,X7R,0402)WTC'                       | 'CHIP0402'     | ''          | ''   | '20180904'
 '0.039UF'  | '50V'   | '10%'     | 'C0603'     | 'X7R'     | 'CH3396K1904'(!)   = ''              | ''                 | ''       | 'CH3396K1904'    |'C0603'| '(SMC0603AW)'                                                        | '0.039UF'  | '50V'         | '10%'    | 'DISCRETE' | 'CAP CHIP 0.039U 50V(+-10%,X7R,0603)WTC'                       | 'CHIP0603'     | ''          | ''   | '20180904'
 '0.039UF'  | '50V'   | '10%'     | 'C0603'     | 'EMPTY'   | 'CH3396K1904'(!)   = ''              | ''                 | ''       | 'CH3396K1904'    |'C0603'| '(SMC0603AW)'                                                        | 'NA'       | '50V'         | '10%'    | 'IO'       | 'CAP CHIP 0.039U 50V(+-10%,X7R,0603)WTC'                       | 'CHIP0603'     | ''          | ''   | '20180904'
 '0.68UF'   | '16V'   | '10%'     | 'C0603'     | 'X7R'     | 'CH4683K1902'(!)   = ''              | ''                 | ''       | 'CH4683K1902'    |'C0603'| '(SMC0603AW)'                                                        | '0.68UF'   | '16V'         | '10%'    | 'DISCRETE' | 'CAP CHIP 0.68U 16V(+-10%,X7R,0603)SAM'                        | 'CHIP0603'     | ''          | ''   | '20160810'
 '0.68UF'   | '16V'   | '10%'     | 'C0603'     | 'EMPTY'   | 'CH4683K1902'(!)   = ''              | ''                 | ''       | 'CH4683K1902'    |'C0603'| '(SMC0603AW)'                                                        | 'NA'       | '16V'         | '10%'    | 'IO'       | 'CAP CHIP 0.68U 16V(+-10%,X7R,0603)SAM'                        | 'CHIP0603'     | ''          | ''   | '20160810'
 '4700PF'   | '25V'   | '10%'     | 'C0402'     | 'X7R'     | 'CH2474K1B12'(!)   = ''              | ''                 | ''       | 'CH2474K1B12'    |'C0402'| '(C0402-0201)'                                                       | '4700PF'   | '25V'         | '10%'    | 'DISCRETE' | 'CAP CHIP 4700P 25V(+-10%,X7R,0402)SAM'                        | 'CHIP0402'     | ''          | ''   | '20180917'
 '4700PF'   | '25V'   | '10%'     | 'C0402'     | 'EMPTY'   | 'CH2474K1B12'(!)   = ''              | ''                 | ''       | 'CH2474K1B12'    |'C0402'| '(C0402-0201)'                                                       | 'NA'       | '25V'         | '10%'    | 'IO'       | 'CAP CHIP 4700P 25V(+-10%,X7R,0402)SAM'                        | 'CHIP0402'     | ''          | ''   | '20180917'
 '470NF'    | '50V'   | '5%'      | 'C1812'     | 'U2J'     | 'CH4476JF400'(!)   = 'End of Design' | 'Comp-Release Qty' | ''       | 'CH4476JF400'    |'C1812XB'| '(SMC0603AW)'                                                        | '470NF'    | '50V'         | '5%'     | 'DISCRETE' | 'CAP CHIP 470NF 50V(+-5%,U2J,1812)'                            | 'CHIP1812'     | ''          | ''   | '20180927'
 '470NF'    | '50V'   | '5%'      | 'C1812'     | 'EMPTY'   | 'CH4476JF400'(!)   = 'End of Design' | 'Comp-Release Qty' | ''       | 'CH4476JF400'    |'C1812XB'| '(SMC0603AW)'                                                        | 'NA'       | '50V'         | '5%'     | 'IO'       | 'CAP CHIP 470NF 50V(+-5%,U2J,1812)'                            | 'CHIP1812'     | ''          | ''   | '20180927'
 '470NF'    | '50V'   | '5%'      | 'C1812'     | 'U2J'     | 'CH4476JF401'(!)   = 'End of Design' | 'Comp-Approve'     | ''       | 'CH4476JF401'    |'C1812XB'| '(SMC0603AW)'                                                        | '470NF'    | '50V'         | '5%'     | 'DISCRETE' | 'CAP CHIP 470NF 50V(+-5%,U2J,1812)KEM'                         | 'CHIP1812'     | ''          | ''   | '20181008'
 '470NF'    | '50V'   | '5%'      | 'C1812'     | 'EMPTY'   | 'CH4476JF401'(!)   = 'End of Design' | 'Comp-Approve'     | ''       | 'CH4476JF401'    |'C1812XB'| '(SMC0603AW)'                                                        | 'NA'       | '50V'         | '5%'     | 'IO'       | 'CAP CHIP 470NF 50V(+-5%,U2J,1812)KEM'                         | 'CHIP1812'     | ''          | ''   | '20181008'
 '22UF'     | '16V'   | '20%'     | 'C0805'     | 'X5R'     | 'CH6223M9A00'(!)   = ''              | ''                 | ''       | 'CH6223M9A00'    |'C0805_H57'| '(SMC0805AW)'                                                        | '22UF'     | '16V'         | '20%'    | 'DISCRETE' | 'CAP CHIP 22UF 16V( +-20% ,X5R,0805)'                          | 'CHIP0805'     | ''          | ''   | '20181016'
 '22UF'     | '16V'   | '20%'     | 'C0805'     | 'EMPTY'   | 'CH6223M9A00'(!)   = ''              | ''                 | ''       | 'CH6223M9A00'    |'C0805_H57'| '(SMC0805AW)'                                                        | 'NA'       | '16V'         | '20%'    | 'IO'       | 'CAP CHIP 22UF 16V( +-20% ,X5R,0805)'                          | 'CHIP0805'     | ''          | ''   | '20181016'
 '2.2UF'    | '25V'   | '10%'     | 'C0603'     | 'X6S'     | 'CH5224KE900'(!)   = ''              | ''                 | ''       | 'CH5224KE900'    |'C0603_H40'| '(SMC0603AW)'                                                        | '2.2UF'    | '25V'         | '10%'    | 'DISCRETE' | 'CAP CHIP 2.2U 25V(+-10%,X6S,0603)MUR'                         | 'CHIP0603'     | ''          | ''   | '20181017'
 '2.2UF'    | '25V'   | '10%'     | 'C0603'     | 'EMPTY'   | 'CH5224KE900'(!)   = ''              | ''                 | ''       | 'CH5224KE900'    |'C0603_H40'| '(SMC0603AW)'                                                        | 'NA'       | '25V'         | '10%'    | 'IO'       | 'CAP CHIP 2.2U 25V(+-10%,X6S,0603)MUR'                         | 'CHIP0603'     | ''          | ''   | '20181017'
 '1UF'      | '100V'  | '10%'     | 'C0805'     | 'X7S'     | 'CH5108K6A01'(!)   = ''              | ''                 | ''       | 'CH5108K6A01'    |'C0805_H57'| '(SMC0805AW)'                                                        | '1UF'      | '100V'        | '10%'    | 'DISCRETE' | 'CAP CHIP 1UF 100V(+-10%,X7S,0805)'                            | 'CHIP0805'     | ''          | ''   | '20181018'
 '1UF'      | '100V'  | '10%'     | 'C0805'     | 'EMPTY'   | 'CH5108K6A01'(!)   = ''              | ''                 | ''       | 'CH5108K6A01'    |'C0805_H57'| '(SMC0805AW)'                                                        | 'NA'       | '100V'        | '10%'    | 'IO'       | 'CAP CHIP 1UF 100V(+-10%,X7S,0805)'                            | 'CHIP0805'     | ''          | ''   | '20181018'
 '0.1UF'    | '16V'   | '10%'     | 'C0201'     | 'X5R'     | 'CH4103K9E01'(!)   = ''              | ''                 | ''       | 'CH4103K9E01'    |'C0201'| '(SMC0201AW)'                                                        | '0.1UF'    | '16V'         | '10%'    | 'DISCRETE' | 'CAP CHIP 0.1U 16V(+-10%,X5R,0201)'                            | 'CHIP0201'     | ''          | ''   | '20181018'
 '0.1UF'    | '16V'   | '10%'     | 'C0201'     | 'EMPTY'   | 'CH4103K9E01'(!)   = ''              | ''                 | ''       | 'CH4103K9E01'    |'C0201'| '(SMC0201AW)'                                                        | 'NA'       | '16V'         | '10%'    | 'IO'       | 'CAP CHIP 0.1U 16V(+-10%,X5R,0201)'                            | 'CHIP0201'     | ''          | ''   | '20181018'
 '0.033UF'  | '100V'  | '10%'     | 'C0603'     | 'X7R'     | 'CH3338K1900'(!)   = ''              | ''                 | ''       | 'CH3338K1900'    |'C0603'| '(SMC0603AW)'                                                        | '0.033UF'  | '100V'        | '10%'    | 'DISCRETE' | 'CAP CHIP 0.033U 100V(+-10%,X7R,0603)'                         | 'CHIP0603'     | ''          | ''   | '20181018'
 '0.033UF'  | '100V'  | '10%'     | 'C0603'     | 'EMPTY'   | 'CH3338K1900'(!)   = ''              | ''                 | ''       | 'CH3338K1900'    |'C0603'| '(SMC0603AW)'                                                        | 'NA'       | '100V'        | '10%'    | 'IO'       | 'CAP CHIP 0.033U 100V(+-10%,X7R,0603)'                         | 'CHIP0603'     | ''          | ''   | '20181018'
 '0.1UF'    | '100V'  | '10%'     | 'C0603'     | 'X7R'     | 'CH4108K1901'(!)   = 'End of Design' | 'Comp-Approve'     | ''       | 'CH4108K1901'    |'C0603'| '(SMC0603AW)'                                                        | '0.1UF'    | '100V'        | '10%'    | 'DISCRETE' | 'CAP CHIP 0.1U 100V(+-10%,X7R,0603)'                           | 'CHIP0603'     | ''          | ''   | '20181018'
 '0.1UF'    | '100V'  | '10%'     | 'C0603'     | 'EMPTY'   | 'CH4108K1901'(!)   = 'End of Design' | 'Comp-Approve'     | ''       | 'CH4108K1901'    |'C0603'| '(SMC0603AW)'                                                        | 'NA'       | '100V'        | '10%'    | 'IO'       | 'CAP CHIP 0.1U 100V(+-10%,X7R,0603)'                           | 'CHIP0603'     | ''          | ''   | '20181018'
 '0.68UF'   | '6.3V'  | '10%'     | 'C0402'     | 'X5R'     | 'CH4681K9B00'(!)   = 'End of Design' | 'Comp-Release Qty' | ''       | 'CH4681K9B00'    |'C0402'| '(C0402-0201)'                                                       | '0.68UF'   | '6.3V'        | '10%'    | 'DISCRETE' | 'CAP CHIP 0.68UF 6.3V(+-10%,X5R,0402)'                         | 'CHIP0402'     | ''          | ''   | '20181026'
 '0.68UF'   | '6.3V'  | '10%'     | 'C0402'     | 'EMPTY'   | 'CH4681K9B00'(!)   = 'End of Design' | 'Comp-Release Qty' | ''       | 'CH4681K9B00'    |'C0402'| '(C0402-0201)'                                                       | 'NA'       | '6.3V'        | '10%'    | 'IO'       | 'CAP CHIP 0.68UF 6.3V(+-10%,X5R,0402)'                         | 'CHIP0402'     | ''          | ''   | '20181026'
 '2.7PF'    | '50V'   | '0.1P'    | 'C0201'     | 'C0G'     | 'CH-276B0E00'(!)   = ''              | ''                 | ''       | 'CH-276B0E00'    |'C0201'| '(SMC0201AW)'                                                        | '2.7PF'    | '50V'         | '0.1P'   | 'DISCRETE' | 'CAP CHIP 2.7P 50V(+-0.1P,C0G,0201)'                           | 'CHIP0201'     | ''          | ''   | '20181026'
 '2.7PF'    | '50V'   | '0.1P'    | 'C0201'     | 'EMPTY'   | 'CH-276B0E00'(!)   = ''              | ''                 | ''       | 'CH-276B0E00'    |'C0201'| '(SMC0201AW)'                                                        | 'NA'       | '50V'         | '0.1P'   | 'IO'       | 'CAP CHIP 2.7P 50V(+-0.1P,C0G,0201)'                           | 'CHIP0201'     | ''          | ''   | '20181026'
 '2.2U'     | '6.3V'  | '20%'     | 'C0402'     | 'X6S'     | 'CH5221MEB03'(!)   = ''              | ''                 | ''       | 'CH5221MEB03'    |'C0402'| '(C0402-0201)'                                                       | '2.2U'     | '6.3V'        | '20%'    | 'DISCRETE' | 'CAP CHIP 2.2U 6.3V(+-20%,X6S,0402)MUR'                        | 'CHIP0402'     | ''          | ''   | '20181122'
 '2.2U'     | '6.3V'  | '20%'     | 'C0402'     | 'EMPTY'   | 'CH5221MEB03'(!)   = ''              | ''                 | ''       | 'CH5221MEB03'    |'C0402'| '(C0402-0201)'                                                       | 'NA'       | '6.3V'        | '20%'    | 'IO'       | 'CAP CHIP 2.2U 6.3V(+-20%,X6S,0402)MUR'                        | 'CHIP0402'     | ''          | ''   | '20181122'
 '2200PF'   | '50V'   | '10%'     | 'C0402'     | 'X7R'     | 'CH2226K1B10'(!)   = ''              | ''                 | ''       | 'CH2226K1B10'    |'C0402_H28'| '(C0402-0201_H28)'                                                   | '2200PF'   | '50V'         | '10%'    | 'DISCRETE' | 'CAP CHIP 2200P 50V(+-10%,X7R,0402)WTC'                        | 'CHIP0402'     | ''          | ''   | '20181126'
 '2200PF'   | '50V'   | '10%'     | 'C0402'     | 'EMPTY'   | 'CH2226K1B10'(!)   = ''              | ''                 | ''       | 'CH2226K1B10'    |'C0402_H28'| '(C0402-0201_H28)'                                                   | 'NA'       | '50V'         | '10%'    | 'IO'       | 'CAP CHIP 2200P 50V(+-10%,X7R,0402)WTC'                        | 'CHIP0402'     | ''          | ''   | '20181126'
 '10UF'     | '16V'   | '10%'     | 'C0805'     | 'X6S'     | 'CH6103KEA01'(!)   = ''              | ''                 | ''       | 'CH6103KEA01'    |'C0805_H57'| '(SMC0805AW)'                                                        | '10UF'     | '16V'         | '10%'    | 'DISCRETE' | 'CAP CHIP 10UF 16V(+-10%,X6S,0805)MUR'                         | 'CHIP0805'     | ''          | ''   | '20181128'
 '10UF'     | '16V'   | '10%'     | 'C0805'     | 'EMPTY'   | 'CH6103KEA01'(!)   = ''              | ''                 | ''       | 'CH6103KEA01'    |'C0805_H57'| '(SMC0805AW)'                                                        | 'NA'       | '16V'         | '10%'    | 'IO'       | 'CAP CHIP 10UF 16V(+-10%,X6S,0805)MUR'                         | 'CHIP0805'     | ''          | ''   | '20181128'
 '3300P'    | '50V'   | '10%'     | 'C0402'     | 'X7R'     | 'CH2336K1B19'(!)   = ''              | ''                 | ''       | 'CH2336K1B19'    |'C0402'| '(C0402-0201)'                                                       | '3300P'    | '50V'         | '10%'    | 'DISCRETE' | 'CAP CHIP 3300P 50V(+-10%,X7R,0402)WTC'                        | 'CHIP0402'     | ''          | ''   | '20181130'
 '3300P'    | '50V'   | '10%'     | 'C0402'     | 'EMPTY'   | 'CH2336K1B19'(!)   = ''              | ''                 | ''       | 'CH2336K1B19'    |'C0402'| '(C0402-0201)'                                                       | 'NA'       | '50V'         | '10%'    | 'IO'       | 'CAP CHIP 3300P 50V(+-10%,X7R,0402)WTC'                        | 'CHIP0402'     | ''          | ''   | '20181130'
 '1PF'      | '25V'   | '0.1%'    | 'C0201'     | 'C0G'     | 'CH-104B0E01'(!)   = ''              | ''                 | ''       | 'CH-104B0E01'    |'C0201'| '(SMC0201AW)'                                                        | '1PF'      | '25V'         | '0.1%'   | 'DISCRETE' | 'CAP CHIP 1PF 25V(+-0.1PF,C0G,0201)'                           | 'CHIP0201'     | ''          | ''   | '20190121'
 '1PF'      | '25V'   | '0.1%'    | 'C0201'     | 'EMPTY'   | 'CH-104B0E01'(!)   = ''              | ''                 | ''       | 'CH-104B0E01'    |'C0201'| '(SMC0201AW)'                                                        | 'NA'       | '25V'         | '0.1%'   | 'IO'       | 'CAP CHIP 1PF 25V(+-0.1PF,C0G,0201)'                           | 'CHIP0201'     | ''          | ''   | '20190121'
 '330P'     | '50V'   | '+-2%'    | 'C0402'     | 'NPO'     | 'CH1336G0B00'(!)   = ''              | ''                 | ''       | 'CH1336G0B00'    |'C0402'| '(C0402-0201)'                                                       | '330P'     | '50V'         | '+-2%'   | 'DISCRETE' | 'CAP CHIP 330P 50V(+-2%,NPO,0402)'                             | 'CHIP0402'     | ''          | ''   | '20190124'
 '330P'     | '50V'   | '+-2%'    | 'C0402'     | 'EMPTY'   | 'CH1336G0B00'(!)   = ''              | ''                 | ''       | 'CH1336G0B00'    |'C0402'| '(C0402-0201)'                                                       | 'NA'       | '50V'         | '+-2%'   | 'IO'       | 'CAP CHIP 330P 50V(+-2%,NPO,0402)'                             | 'CHIP0402'     | ''          | ''   | '20190124'
 '0.1U'     | '16V'   | '10%'     | 'C0402'     | 'X7R'     | 'CH4103K1B20'(!)   = ''              | ''                 | ''       | 'CH4103K1B20'    |'C0402'| '(C0402-0201)'                                                       | '0.1U'     | '16V'         | '10%'    | 'DISCRETE' | 'CAP CHIP 0.1U 16V(10%,X7R,0402)TAY'                           | 'CHIP0402'     | ''          | ''   | '20190124'
 '0.1U'     | '16V'   | '10%'     | 'C0402'     | 'EMPTY'   | 'CH4103K1B20'(!)   = ''              | ''                 | ''       | 'CH4103K1B20'    |'C0402'| '(C0402-0201)'                                                       | 'NA'       | '16V'         | '10%'    | 'IO'       | 'CAP CHIP 0.1U 16V(10%,X7R,0402)TAY'                           | 'CHIP0402'     | ''          | ''   | '20190124'
 '3300P'    | '50V'   | '+-10%'   | 'C0402'     | 'X7R'     | 'CH2336K1B10'(!)   = ''              | ''                 | ''       | 'CH2336K1B10'    |'C0402'| '(C0402-0201)'                                                       | '3300P'    | '50V'         | '+-10%'  | 'DISCRETE' | 'CAP CHIP 3300P 50V(+-10%,X7R,0402)SAM'                        | 'CHIP0402'     | ''          | ''   | '20190124'
 '3300P'    | '50V'   | '+-10%'   | 'C0402'     | 'EMPTY'   | 'CH2336K1B10'(!)   = ''              | ''                 | ''       | 'CH2336K1B10'    |'C0402'| '(C0402-0201)'                                                       | 'NA'       | '50V'         | '+-10%'  | 'IO'       | 'CAP CHIP 3300P 50V(+-10%,X7R,0402)SAM'                        | 'CHIP0402'     | ''          | ''   | '20190124'
 '330N'     | '250V'  | '+-10%'   | 'C1812'     | 'X7R'     | 'CH433CK1400'(!)   = ''              | ''                 | ''       | 'CH433CK1400'    |'C1812XC'| '(SMC1812AW)'                                                        | '330N'     | '250V'        | '+-10%'  | 'DISCRETE' | 'CAP CHIP 330N 250V(+-10%,X7R,1812)'                           | 'CHIP1812'     | ''          | ''   | '20190128'
 '330N'     | '250V'  | '+-10%'   | 'C1812'     | 'EMPTY'   | 'CH433CK1400'(!)   = ''              | ''                 | ''       | 'CH433CK1400'    |'C1812XC'| '(SMC1812AW)'                                                        | 'NA'       | '250V'        | '+-10%'  | 'IO'       | 'CAP CHIP 330N 250V(+-10%,X7R,1812)'                           | 'CHIP1812'     | ''          | ''   | '20190128'
 '0.22UF'   | '25V'   | '10%'     | 'C0402'     | 'X7R'     | 'CH4224K1B09'(!)   = ''              | ''                 | ''       | 'CH4224K1B09'    |'C0402'| '(C0402-0201)'                                                       | '0.22UF'   | '25V'         | '10%'    | 'DISCRETE' | 'CAP CHIP 0.22U 25V(+-10%,X7R,0402)TAY'                        | 'CHIP0402'     | ''          | ''   | '20190219'
 '0.22UF'   | '25V'   | '10%'     | 'C0402'     | 'EMPTY'   | 'CH4224K1B09'(!)   = ''              | ''                 | ''       | 'CH4224K1B09'    |'C0402'| '(C0402-0201)'                                                       | 'NA'       | '25V'         | '10%'    | 'IO'       | 'CAP CHIP 0.22U 25V(+-10%,X7R,0402)TAY'                        | 'CHIP0402'     | ''          | ''   | '20190219'
 '1UF'      | '50V'   | '10%'     | 'C0603'     | 'X7R'     | 'CH5106K1900'(!)   = ''              | ''                 | ''       | 'CH5106K1900'    |'C0603_H40'| '(SMC0603AW)'                                                        | '1UF'      | '50V'         | '10%'    | 'DISCRETE' | 'CAP CHIP 1U 50V(+-10%,X7R,0603)YGO'                           | 'CHIP0603'     | ''          | ''   | '20190401'
 '1UF'      | '50V'   | '10%'     | 'C0603'     | 'EMPTY'   | 'CH5106K1900'(!)   = ''              | ''                 | ''       | 'CH5106K1900'    |'C0603_H40'| '(SMC0603AW)'                                                        | 'NA'       | '50V'         | '10%'    | 'IO'       | 'CAP CHIP 1U 50V(+-10%,X7R,0603)YGO'                           | 'CHIP0603'     | ''          | ''   | '20190401'
 '4.7UF'    | '50V'   | '10%'     | 'C0805'     | 'X5R'     | 'CH5476K9A02'(!)   = ''              | ''                 | ''       | 'CH5476K9A02'    |'C0805_H57'| '(SMC0805AW)'                                                        | '4.7UF'    | '50V'         | '10%'    | 'DISCRETE' | 'CAP CHIP 4.7UF 50V(+-10%,X5R,0805)MUR'                        | 'CHIP0805'     | ''          | ''   | '20190401'
 '4.7UF'    | '50V'   | '10%'     | 'C0805'     | 'EMPTY'   | 'CH5476K9A02'(!)   = ''              | ''                 | ''       | 'CH5476K9A02'    |'C0805_H57'| '(SMC0805AW)'                                                        | 'NA'       | '50V'         | '10%'    | 'IO'       | 'CAP CHIP 4.7UF 50V(+-10%,X5R,0805)MUR'                        | 'CHIP0805'     | ''          | ''   | '20190401'
 '1UF'      | '50V'   | '10%'     | 'C0805'     | 'X7R'     | 'CH5106K1A05'(!)   = ''              | ''                 | ''       | 'CH5106K1A05'    |'C0805_H57'| '(SMC0805AW)'                                                        | '1UF'      | '50V'         | '10%'    | 'DISCRETE' | 'CAP CHIP 1U 50V(+-10%,X7R,0805)SAM'                           | 'CHIP0805'     | ''          | ''   | '20190412'
 '1UF'      | '50V'   | '10%'     | 'C0805'     | 'EMPTY'   | 'CH5106K1A05'(!)   = ''              | ''                 | ''       | 'CH5106K1A05'    |'C0805_H57'| '(SMC0805AW)'                                                        | 'NA'       | '50V'         | '10%'    | 'IO'       | 'CAP CHIP 1U 50V(+-10%,X7R,0805)SAM'                           | 'CHIP0805'     | ''          | ''   | '20190412'
 '220P'     | '50V'   | '5%'      | 'C0402'     | 'COG'     | 'CH1226J0B03'(!)   = ''              | ''                 | ''       | 'CH1226J0B03'    |'C0402'| '(C0402-0201)'                                                       | '220P'     | '50V'         | '5%'     | 'DISCRETE' | 'CAP CHIP 220P 50V(+-5%,COG,0402)MUR'                          | 'CHIP0402'     | ''          | ''   | '20190422'
 '220P'     | '50V'   | '5%'      | 'C0402'     | 'EMPTY'   | 'CH1226J0B03'(!)   = ''              | ''                 | ''       | 'CH1226J0B03'    |'C0402'| '(C0402-0201)'                                                       | 'NA'       | '50V'         | '5%'     | 'IO'       | 'CAP CHIP 220P 50V(+-5%,COG,0402)MUR'                          | 'CHIP0402'     | ''          | ''   | '20190422'
 '3.9P'     | '50V'   | '0.1P'    | 'C0402'     | 'NPO'     | 'CH-3916TB01'(!)   = ''              | ''                 | ''       | 'CH-3916TB01'    |'C0402'| '(C0402-0201)'                                                       | '3.9P'     | '50V'         | '0.1P'   | 'DISCRETE' | 'CAP CHIP 3.9P 50V(+-0.1P,NPO,0402)'                           | 'CHIP0402'     | ''          | ''   | '20190426'
 '3.9P'     | '50V'   | '0.1P'    | 'C0402'     | 'EMPTY'   | 'CH-3916TB01'(!)   = ''              | ''                 | ''       | 'CH-3916TB01'    |'C0402'| '(C0402-0201)'                                                       | 'NA'       | '50V'         | '0.1P'   | 'IO'       | 'CAP CHIP 3.9P 50V(+-0.1P,NPO,0402)'                           | 'CHIP0402'     | ''          | ''   | '20190426'
 '10PF'     | '50V'   | '2%'      | 'C0402'     | 'NPO'     | 'CH01006GB02'(!)   = ''              | ''                 | ''       | 'CH01006GB02'    |'C0402'| '(C0402-0201)'                                                       | '10PF'     | '50V'         | '2%'     | 'DISCRETE' | 'CAP CHIP 10P 50V(+-2%,NPO,0402)'                              | 'CHIP0402'     | ''          | ''   | '20190605'
 '10PF'     | '50V'   | '2%'      | 'C0402'     | 'EMPTY'   | 'CH01006GB02'(!)   = ''              | ''                 | ''       | 'CH01006GB02'    |'C0402'| '(C0402-0201)'                                                       | 'NA'       | '50V'         | '2%'     | 'IO'       | 'CAP CHIP 10P 50V(+-2%,NPO,0402)'                              | 'CHIP0402'     | ''          | ''   | '20190605'
 '47UF'     | '2.5V'  | '20%'     | 'C0603'     | 'X6S'     | 'CH647LME900'(!)   = 'End of Design' | 'Comp-Approve'     | ''       | 'CH647LME900'    |'C0603'| '(SMC0603AW)'                                                        | '47UF'     | '2.5V'        | '20%'    | 'DISCRETE' | 'CAP CHIP 47U 2.5V(+-20%,X6S,0603)MUR'                         | 'CHIP0603'     | ''          | ''   | '20190605'
 '47UF'     | '2.5V'  | '20%'     | 'C0603'     | 'EMPTY'   | 'CH647LME900'(!)   = 'End of Design' | 'Comp-Approve'     | ''       | 'CH647LME900'    |'C0603'| '(SMC0603AW)'                                                        | 'NA'       | '2.5V'        | '20%'    | 'IO'       | 'CAP CHIP 47U 2.5V(+-20%,X6S,0603)MUR'                         | 'CHIP0603'     | ''          | ''   | '20190605'
 '2.2PF'    | '50V'   | '0.1P'    | 'C0402'     | 'NPO'     | 'CH-2216TB02'(!)   = ''              | ''                 | ''       | 'CH-2216TB02'    |'C0402'| '(C0402-0201)'                                                       | '2.2PF'    | '50V'         | '0.1P'   | 'DISCRETE' | 'CAP CHIP 2.2P 50V (+-0.1P NPO 0402)'                          | 'CHIP0402'     | ''          | ''   | '20190605'
 '2.2PF'    | '50V'   | '0.1P'    | 'C0402'     | 'EMPTY'   | 'CH-2216TB02'(!)   = ''              | ''                 | ''       | 'CH-2216TB02'    |'C0402'| '(C0402-0201)'                                                       | 'NA'       | '50V'         | '0.1P'   | 'IO'       | 'CAP CHIP 2.2P 50V (+-0.1P NPO 0402)'                          | 'CHIP0402'     | ''          | ''   | '20190605'
 '22UF'     | '4V'    | '20%'     | 'C0805'     | 'X6S'     | 'CH622KMEA04'(!)   = ''              | ''                 | ''       | 'CH622KMEA04'    |'C0805_H57'| '(SMC0805AW)'                                                        | '22UF'     | '4V'          | '20%'    | 'DISCRETE' | 'CAP CHIP 22U 4V(+-20%,X6S,0805)SAM'                           | 'CHIP0805'     | ''          | ''   | '20190611'
 '22UF'     | '4V'    | '20%'     | 'C0805'     | 'EMPTY'   | 'CH622KMEA04'(!)   = ''              | ''                 | ''       | 'CH622KMEA04'    |'C0805_H57'| '(SMC0805AW)'                                                        | 'NA'       | '4V'          | '20%'    | 'IO'       | 'CAP CHIP 22U 4V(+-20%,X6S,0805)SAM'                           | 'CHIP0805'     | ''          | ''   | '20190611'
 '22UF'     | '16V'   | '20%'     | 'C0805'     | 'X6S'     | 'CH6223MEA03'(!)   = ''              | ''                 | ''       | 'CH6223MEA03'    |'C0805_H57'| '(SMC0805AW)'                                                        | '22UF'     | '16V'         | '20%'    | 'DISCRETE' | 'CAP CHIP 22U 16V(20%,X6S,0805)SAM'                            | 'CHIP0805'     | ''          | ''   | '20190611'
 '22UF'     | '16V'   | '20%'     | 'C0805'     | 'EMPTY'   | 'CH6223MEA03'(!)   = ''              | ''                 | ''       | 'CH6223MEA03'    |'C0805_H57'| '(SMC0805AW)'                                                        | 'NA'       | '16V'         | '20%'    | 'IO'       | 'CAP CHIP 22U 16V(20%,X6S,0805)SAM'                            | 'CHIP0805'     | ''          | ''   | '20190611'
 '3300PF'   | '50V'   | '5%'      | 'C0402'     | 'X7R'     | 'CH23306JB16'(!)   = ''              | ''                 | ''       | 'CH23306JB16'    |'C0402'| '(C0402-0201)'                                                       | '3300PF'   | '50V'         | '5%'     | 'DISCRETE' | 'CAP CHIP 3300P 50V(+-5%,X7R,0402)'                            | 'CHIP0402'     | ''          | ''   | '20190712'
 '3300PF'   | '50V'   | '5%'      | 'C0402'     | 'EMPTY'   | 'CH23306JB16'(!)   = ''              | ''                 | ''       | 'CH23306JB16'    |'C0402'| '(C0402-0201)'                                                       | 'NA'       | '50V'         | '5%'     | 'IO'       | 'CAP CHIP 3300P 50V(+-5%,X7R,0402)'                            | 'CHIP0402'     | ''          | ''   | '20190712'
 '4.7UF'    | '25V'   | '10%'     | 'C0603'     | 'X5R'     | 'CH5474K9901'(!)   = ''              | ''                 | ''       | 'CH5474K9901'    |'C0603_H40'| '(SMC0603AW)'                                                        | '4.7UF'    | '25V'         | '10%'    | 'DISCRETE' | 'CAP CHIP 4.7U 25V(+-10%,X5R,0603)'                            | 'CHIP0603'     | ''          | ''   | '20190730'
 '4.7UF'    | '25V'   | '10%'     | 'C0603'     | 'EMPTY'   | 'CH5474K9901'(!)   = ''              | ''                 | ''       | 'CH5474K9901'    |'C0603_H40'| '(SMC0603AW)'                                                        | 'NA'       | '25V'         | '10%'    | 'IO'       | 'CAP CHIP 4.7U 25V(+-10%,X5R,0603)'                            | 'CHIP0603'     | ''          | ''   | '20190730'
 '1UF'      | '25V'   | '10%'     | 'C0402'     | 'X5R'     | 'CH5104K9B01'(!)   = ''              | ''                 | ''       | 'CH5104K9B01'    |'C0402'| '(C0402-0201))'                                                      | '1UF'      | '25V'         | '10%'    | 'DISCRETE' | 'CAP CHIP 1UF 25V(+-10%,X5R,0402)'                             | 'CHIP0402'     | ''          | ''   | '20190731'
 '1UF'      | '25V'   | '10%'     | 'C0402'     | 'EMPTY'   | 'CH5104K9B01'(!)   = ''              | ''                 | ''       | 'CH5104K9B01'    |'C0402'| '(C0402-0201))'                                                      | 'NA'       | '25V'         | '10%'    | 'IO'       | 'CAP CHIP 1UF 25V(+-10%,X5R,0402)'                             | 'CHIP0402'     | ''          | ''   | '20190731'
 '4.7UF'    | '6.3V'  | '10%'     | 'C0402'     | 'X5R'     | 'CH5471K9B00'(!)   = ''              | ''                 | ''       | 'CH5471K9B00'    |'C0402_H28'| '(C0402-0201_H28)'                                                   | '4.7UF'    | '6.3V'        | '10%'    | 'DISCRETE' | 'CAP CHIP 4.7UF 6.3V(+-10%,X5R,0402)'                          | 'CHIP0402'     | ''          | ''   | '20190731'
 '4.7UF'    | '6.3V'  | '10%'     | 'C0402'     | 'EMPTY'   | 'CH5471K9B00'(!)   = ''              | ''                 | ''       | 'CH5471K9B00'    |'C0402_H28'| '(C0402-0201_H28)'                                                   | 'NA'       | '6.3V'        | '10%'    | 'IO'       | 'CAP CHIP 4.7UF 6.3V(+-10%,X5R,0402)'                          | 'CHIP0402'     | ''          | ''   | '20190731'
 '22UF'     | '6.3V'  | '20%'     | 'C0603'     | 'X6S'     | 'CH6221ME907'(!)   = ''              | ''                 | ''       | 'CH6221ME907'    |'C0603_H40'| '(SMC0603AW)'                                                        | '22UF'     | '6.3V'        | '20%'    | 'DISCRETE' | 'CAP CHIP 22U 6.3V(+-20%,X6S,0603)SAM'                         | 'CHIP0603'     | ''          | ''   | '20190807'
 '22UF'     | '6.3V'  | '20%'     | 'C0603'     | 'EMPTY'   | 'CH6221ME907'(!)   = ''              | ''                 | ''       | 'CH6221ME907'    |'C0603_H40'| '(SMC0603AW)'                                                        | 'NA'       | '6.3V'        | '20%'    | 'IO'       | 'CAP CHIP 22U 6.3V(+-20%,X6S,0603)SAM'                         | 'CHIP0603'     | ''          | ''   | '20190807'
 '2.2UF'    | '25V'   | '10%'     | 'C0402'     | 'X5R'     | 'CH5224K9B01'(!)   = ''              | ''                 | ''       | 'CH5224K9B01'    |'C0402_H28'| '(C0402-0201_H28)'                                                   | '2.2UF'    | '25V'         | '10%'    | 'DISCRETE' | 'CAP CHIP 2.2U 25V(+-10%,X5R,0402)'                            | 'CHIP0402'     | ''          | ''   | '20150729'
 '2.2UF'    | '25V'   | '10%'     | 'C0402'     | 'EMPTY'   | 'CH5224K9B01'(!)   = ''              | ''                 | ''       | 'CH5224K9B01'    |'C0402_H28'| '(C0402-0201_H28)'                                                   | 'NA'       | '25V'         | '10%'    | 'IO'       | 'CAP CHIP 2.2U 25V(+-10%,X5R,0402)'                            | 'CHIP0402'     | ''          | ''   | '20150729'
 '0.1UF'    | '100V'  | '10%'     | 'C0603'     | 'X7R'     | 'CH4108K1904'(!)   = ''              | ''                 | ''       | 'CH4108K1904'    |'C0603'| '(SMC0603AW)'                                                        | '0.1UF'    | '100V'        | '10%'    | 'DISCRETE' | 'CAP CHIP 0.1U 100V(+-10%,X7R,0603)SAM'                        | 'CHIP0603'     | ''          | ''   | '20190828'
 '0.1UF'    | '100V'  | '10%'     | 'C0603'     | 'EMPTY'   | 'CH4108K1904'(!)   = ''              | ''                 | ''       | 'CH4108K1904'    |'C0603'| '(SMC0603AW)'                                                        | 'NA'       | '100V'        | '10%'    | 'IO'       | 'CAP CHIP 0.1U 100V(+-10%,X7R,0603)SAM'                        | 'CHIP0603'     | ''          | ''   | '20190828'
 '1.8PF'    | '50V'   | '0.25PF'  | 'C0402'     | 'NPO'     | 'CH-1806TB07'(!)   = 'End of Design' | 'Comp-Approve'     | ''       | 'CH-1806TB07'    |'C0402'| '(C0402-0201)'                                                       | '1.8PF'    | '50V'         | '0.25PF' | 'DISCRETE' | 'CAP CHIP 1.8P 50V(+-0.25P,NPO,0402)'                          | 'CHIP0402'     | ''          | ''   | '20190906'
 '1.8PF'    | '50V'   | '0.25PF'  | 'C0402'     | 'EMPTY'   | 'CH-1806TB07'(!)   = 'End of Design' | 'Comp-Approve'     | ''       | 'CH-1806TB07'    |'C0402'| '(C0402-0201)'                                                       | 'NA'       | '50V'         | '0.25PF' | 'IO'       | 'CAP CHIP 1.8P 50V(+-0.25P,NPO,0402)'                          | 'CHIP0402'     | ''          | ''   | '20190906'
 '47NF'     | '50V'   | '10%'     | 'C0402'     | 'X7R'     | 'CH3476K1B00'(!)   = ''              | ''                 | ''       | 'CH3476K1B00'    |'C0402'| '(C0402-0201,C0402_OCTAGONXA)'                                       | '47NF'     | '50V'         | '10%'    | 'DISCRETE' | 'CAP CHIP 47NF 50V(+-10%,X7R,0402)'                            | 'CHIP0402'     | ''          | ''   | '20190925'
 '47NF'     | '50V'   | '10%'     | 'C0402'     | 'EMPTY'   | 'CH3476K1B00'(!)   = ''              | ''                 | ''       | 'CH3476K1B00'    |'C0402'| '(C0402-0201,C0402_OCTAGONXA)'                                       | 'NA'       | '50V'         | '10%'    | 'IO'       | 'CAP CHIP 47NF 50V(+-10%,X7R,0402)'                            | 'CHIP0402'     | ''          | ''   | '20190925'
 '100NF'    | '50V'   | '10%'     | 'C0402'     | 'X7R'     | 'CH4106K1B21'(!)   = ''              | ''                 | ''       | 'CH4106K1B21'    |'C0402_H28'| '(C0402-0201_H28)'                                                   | '100NF'    | '50V'         | '10%'    | 'DISCRETE' | 'CAP CHIP 100NF 50V(+-10%,X7R,0402)WTC'                        | 'CHIP0402'     | ''          | ''   | '20191021'
 '100NF'    | '50V'   | '10%'     | 'C0402'     | 'EMPTY'   | 'CH4106K1B21'(!)   = ''              | ''                 | ''       | 'CH4106K1B21'    |'C0402_H28'| '(C0402-0201_H28)'                                                   | 'NA'       | '50V'         | '10%'    | 'IO'       | 'CAP CHIP 100NF 50V(+-10%,X7R,0402)WTC'                        | 'CHIP0402'     | ''          | ''   | '20191021'
 '100NF'    | '50V'   | '10%'     | 'C0402'     | 'X7R'     | 'CH4106K1B20'(!)   = ''              | ''                 | ''       | 'CH4106K1B20'    |'C0402'| '(C0402-0201)'                                                       | '100NF'    | '50V'         | '10%'    | 'DISCRETE' | 'CAP CHIP 100NF 50V(+-10%,X7R,0402)SAM'                        | 'CHIP0402'     | ''          | ''   | '20191025'
 '100NF'    | '50V'   | '10%'     | 'C0402'     | 'EMPTY'   | 'CH4106K1B20'(!)   = ''              | ''                 | ''       | 'CH4106K1B20'    |'C0402'| '(C0402-0201)'                                                       | 'NA'       | '50V'         | '10%'    | 'IO'       | 'CAP CHIP 100NF 50V(+-10%,X7R,0402)SAM'                        | 'CHIP0402'     | ''          | ''   | '20191025'
 '390PF'    | '50V'   | '5%'      | 'C0402'     | 'X7R'     | 'CH13906JB16'(!)   = ''              | ''                 | ''       | 'CH13906JB16'    |'C0402'| '(C0402-0201)'                                                       | '390PF'    | '50V'         | '5%'     | 'DISCRETE' | 'CAP CHIP 390P 50V(+-5%,X7R,0402)'                             | 'CHIP0402'     | ''          | ''   | '20191101'
 '390PF'    | '50V'   | '5%'      | 'C0402'     | 'EMPTY'   | 'CH13906JB16'(!)   = ''              | ''                 | ''       | 'CH13906JB16'    |'C0402'| '(C0402-0201)'                                                       | 'NA'       | '50V'         | '5%'     | 'IO'       | 'CAP CHIP 390P 50V(+-5%,X7R,0402)'                             | 'CHIP0402'     | ''          | ''   | '20191101'
 '0.01UF'   | '100V'  | '10%'     | 'C0603'     | 'X7R'     | 'CH3108K1904'(!)   = ''              | ''                 | ''       | 'CH3108K1904'    |'C0603'| '(SMC0603AW)'                                                        | '0.01UF'   | '100V'        | '10%'    | 'DISCRETE' | 'CAP CHIP 0.01U 100V(+-10%,X7R,0603)MUR'                       | 'CHIP0603'     | ''          | ''   | '20191104'
 '0.01UF'   | '100V'  | '10%'     | 'C0603'     | 'EMPTY'   | 'CH3108K1904'(!)   = ''              | ''                 | ''       | 'CH3108K1904'    |'C0603'| '(SMC0603AW)'                                                        | 'NA'       | '100V'        | '10%'    | 'IO'       | 'CAP CHIP 0.01U 100V(+-10%,X7R,0603)MUR'                       | 'CHIP0603'     | ''          | ''   | '20191104'
 '0.01UF'   | '100V'  | '10%'     | 'C0603'     | 'X7R'     | 'CH3108K1905'(!)   = ''              | ''                 | ''       | 'CH3108K1905'    |'C0603'| '(SMC0603AW)'                                                        | '0.01UF'   | '100V'        | '10%'    | 'DISCRETE' | 'CAP CHIP 0.01U 100V(+-10%,X7R,0603)SAM'                       | 'CHIP0603'     | ''          | ''   | '20191108'
 '0.01UF'   | '100V'  | '10%'     | 'C0603'     | 'EMPTY'   | 'CH3108K1905'(!)   = ''              | ''                 | ''       | 'CH3108K1905'    |'C0603'| '(SMC0603AW)'                                                        | 'NA'       | '100V'        | '10%'    | 'IO'       | 'CAP CHIP 0.01U 100V(+-10%,X7R,0603)SAM'                       | 'CHIP0603'     | ''          | ''   | '20191108'
 '10UF'     | '50V'   | '10%'     | 'C1210'     | 'X7R'     | 'CH6106K1303'(!)   = ''              | ''                 | ''       | 'CH6106K1303'    |'C1210_GRM32E'| '(SMC1210AW)'                                                        | '10UF'     | '50V'         | '10%'    | 'DISCRETE' | 'CAP CHIP 10U 50V(+-10%,X7R,1210)MUR'                          | 'CHIP1210'     | ''          | ''   | '20191128'
 '10UF'     | '50V'   | '10%'     | 'C1210'     | 'EMPTY'   | 'CH6106K1303'(!)   = ''              | ''                 | ''       | 'CH6106K1303'    |'C1210_GRM32E'| '(SMC1210AW)'                                                        | 'NA'       | '50V'         | '10%'    | 'IO'       | 'CAP CHIP 10U 50V(+-10%,X7R,1210)MUR'                          | 'CHIP1210'     | ''          | ''   | '20191128'
 '4700PF'   | '50V'   | '5%'      | 'C0402'     | 'C0G'     | 'CH2476J0B01'(!)   = ''              | ''                 | ''       | 'CH2476J0B01'    |'C0402_H28'| '(C0402-0201_H28)'                                                   | '4700PF'   | '50V'         | '5%'     | 'DISCRETE' | 'CAP CHIP 4700P 50V(+-5%,C0G,0402)MUR'                         | 'CHIP0402'     | ''          | ''   | '20191128'
 '4700PF'   | '50V'   | '5%'      | 'C0402'     | 'EMPTY'   | 'CH2476J0B01'(!)   = ''              | ''                 | ''       | 'CH2476J0B01'    |'C0402_H28'| '(C0402-0201_H28)'                                                   | 'NA'       | '50V'         | '5%'     | 'IO'       | 'CAP CHIP 4700P 50V(+-5%,C0G,0402)MUR'                         | 'CHIP0402'     | ''          | ''   | '20191128'
 '2200PF'   | '50V'   | '5%'      | 'C0402'     | 'C0G'     | 'CH2226J0B01'(!)   = ''              | ''                 | ''       | 'CH2226J0B01'    |'C0402'| '(C0402-0201)'                                                       | '2200PF'   | '50V'         | '5%'     | 'DISCRETE' | 'CAP CHIP 2200P 50V(+-5%,C0G,0402)MUR'                         | 'CHIP0402'     | ''          | ''   | '20191128'
 '2200PF'   | '50V'   | '5%'      | 'C0402'     | 'EMPTY'   | 'CH2226J0B01'(!)   = ''              | ''                 | ''       | 'CH2226J0B01'    |'C0402'| '(C0402-0201)'                                                       | 'NA'       | '50V'         | '5%'     | 'IO'       | 'CAP CHIP 2200P 50V(+-5%,C0G,0402)MUR'                         | 'CHIP0402'     | ''          | ''   | '20191128'
 '1.1PF'    | '25V'   | '0.05PF'  | 'C0201'     | 'C0G'     | 'CH-114T0E00'(!)   = ''              | ''                 | ''       | 'CH-114T0E00'    |'C0201'| '(SMC0201AW)'                                                        | '1.1PF'    | '25V'         | '0.05PF' | 'DISCRETE' | 'CAPCHIP1.1PF25V(+-0.05PF,C0G,0201)HQ MUR'                     | 'CHIP0201'     | ''          | ''   | '20191210'
 '1.1PF'    | '25V'   | '0.05PF'  | 'C0201'     | 'EMPTY'   | 'CH-114T0E00'(!)   = ''              | ''                 | ''       | 'CH-114T0E00'    |'C0201'| '(SMC0201AW)'                                                        | 'NA'       | '25V'         | '0.05PF' | 'IO'       | 'CAPCHIP1.1PF25V(+-0.05PF,C0G,0201)HQ MUR'                     | 'CHIP0201'     | ''          | ''   | '20191210'
 '4.7UF'    | '100V'  | '10%'     | 'C1210'     | 'X7S'     | 'CH5478K6304'(!)   = ''              | ''                 | ''       | 'CH5478K6304'    |'C1210_HMK325'| '(SMC1210AW)'                                                        | '4.7UF'    | '100V'        | '10%'    | 'DISCRETE' | 'CAP CHIP 4.7U 100V(+-10%,X7S,1210)TAY'                        | 'CHIP1210'     | ''          | ''   | '20191210'
 '4.7UF'    | '100V'  | '10%'     | 'C1210'     | 'EMPTY'   | 'CH5478K6304'(!)   = ''              | ''                 | ''       | 'CH5478K6304'    |'C1210_HMK325'| '(SMC1210AW)'                                                        | 'NA'       | '100V'        | '10%'    | 'IO'       | 'CAP CHIP 4.7U 100V(+-10%,X7S,1210)TAY'                        | 'CHIP1210'     | ''          | ''   | '20191210'
 '12PF'     | '25V'   | '5%'      | 'C0201'     | 'NPO'     | 'CH0124J0E02'(!)   = ''              | ''                 | ''       | 'CH0124J0E02'    |'C0201'| '(SMC0201AW)'                                                        | '12PF'     | '25V'         | '5%'     | 'DISCRETE' | 'CAP CHIP 12PF 25V(+-5%,NPO,0201)'                             | 'CHIP0201'     | ''          | ''   | '20191210'
 '12PF'     | '25V'   | '5%'      | 'C0201'     | 'EMPTY'   | 'CH0124J0E02'(!)   = ''              | ''                 | ''       | 'CH0124J0E02'    |'C0201'| '(SMC0201AW)'                                                        | 'NA'       | '25V'         | '5%'     | 'IO'       | 'CAP CHIP 12PF 25V(+-5%,NPO,0201)'                             | 'CHIP0201'     | ''          | ''   | '20191210'
 '180PF'    | '50V'   | '5%'      | 'C0201'     | 'C0G'     | 'CH1186J0E00'(!)   = ''              | ''                 | ''       | 'CH1186J0E00'    |'C0201'| '(SMC0201AW)'                                                        | '180PF'    | '50V'         | '5%'     | 'DISCRETE' | 'CAP CHIP 180PF 50V(+-5%,C0G,0201)'                            | 'CHIP0201'     | ''          | ''   | '20191210'
 '180PF'    | '50V'   | '5%'      | 'C0201'     | 'EMPTY'   | 'CH1186J0E00'(!)   = ''              | ''                 | ''       | 'CH1186J0E00'    |'C0201'| '(SMC0201AW)'                                                        | 'NA'       | '50V'         | '5%'     | 'IO'       | 'CAP CHIP 180PF 50V(+-5%,C0G,0201)'                            | 'CHIP0201'     | ''          | ''   | '20191210'
 '15PF'     | '25V'   | '5%'      | 'C0201'     | 'COG'     | 'CH0154J0E03'(!)   = ''              | ''                 | ''       | 'CH0154J0E03'    |'C0201'| '(SMC0201AW)'                                                        | '15PF'     | '25V'         | '5%'     | 'DISCRETE' | 'CAP CHIP 15P 25V(+-5%,COG,0201)'                              | 'CHIP0201'     | ''          | ''   | '20191210'
 '15PF'     | '25V'   | '5%'      | 'C0201'     | 'EMPTY'   | 'CH0154J0E03'(!)   = ''              | ''                 | ''       | 'CH0154J0E03'    |'C0201'| '(SMC0201AW)'                                                        | 'NA'       | '25V'         | '5%'     | 'IO'       | 'CAP CHIP 15P 25V(+-5%,COG,0201)'                              | 'CHIP0201'     | ''          | ''   | '20191210'
 '18PF'     | '25V'   | '5%'      | 'C0201'     | 'COG'     | 'CH0184J0E04'(!)   = ''              | ''                 | ''       | 'CH0184J0E04'    |'C0201'| '(SMC0201AW)'                                                        | '18PF'     | '25V'         | '5%'     | 'DISCRETE' | 'CAP CHIP 18P 25V(+-5%,COG,0201)'                              | 'CHIP0201'     | ''          | ''   | '20191216'
 '18PF'     | '25V'   | '5%'      | 'C0201'     | 'EMPTY'   | 'CH0184J0E04'(!)   = ''              | ''                 | ''       | 'CH0184J0E04'    |'C0201'| '(SMC0201AW)'                                                        | 'NA'       | '25V'         | '5%'     | 'IO'       | 'CAP CHIP 18P 25V(+-5%,COG,0201)'                              | 'CHIP0201'     | ''          | ''   | '20191216'
 '33PF'     | '25V'   | '5%'      | 'C0201'     | 'COG'     | 'CH0334J0E01'(!)   = ''              | ''                 | ''       | 'CH0334J0E01'    |'C0201'| '(SMC0201AW)'                                                        | '33PF'     | '25V'         | '5%'     | 'DISCRETE' | 'CAP CHIP 33P 25V(+-5%,COG,0201)'                              | 'CHIP0201'     | ''          | ''   | '20191217'
 '33PF'     | '25V'   | '5%'      | 'C0201'     | 'EMPTY'   | 'CH0334J0E01'(!)   = ''              | ''                 | ''       | 'CH0334J0E01'    |'C0201'| '(SMC0201AW)'                                                        | 'NA'       | '25V'         | '5%'     | 'IO'       | 'CAP CHIP 33P 25V(+-5%,COG,0201)'                              | 'CHIP0201'     | ''          | ''   | '20191217'
 '5PF'      | '25V'   | '0.25PF'  | 'C0201'     | 'NPO'     | 'CH-504T0E08'(!)   = 'End of Design' | 'Comp-Approve'     | ''       | 'CH-504T0E08'    |'C0201'| '(SMC0201AW)'                                                        | '5PF'      | '25V'         | '0.25PF' | 'DISCRETE' | 'CAP CHIP 5P 25V(+-0.25P,NPO,0201)'                            | 'CHIP0201'     | ''          | ''   | '20191212'
 '5PF'      | '25V'   | '0.25PF'  | 'C0201'     | 'EMPTY'   | 'CH-504T0E08'(!)   = 'End of Design' | 'Comp-Approve'     | ''       | 'CH-504T0E08'    |'C0201'| '(SMC0201AW)'                                                        | 'NA'       | '25V'         | '0.25PF' | 'IO'       | 'CAP CHIP 5P 25V(+-0.25P,NPO,0201)'                            | 'CHIP0201'     | ''          | ''   | '20191212'
 '6.8PF'    | '25V'   | '0.5PF'   | 'C0201'     | 'COG'     | 'CH-684T0E00'(!)   = ''              | ''                 | ''       | 'CH-684T0E00'    |'C0201'| '(SMC0201AW)'                                                        | '6.8PF'    | '25V'         | '0.5PF'  | 'DISCRETE' | 'CAP CHIP 6.8P 25V(+-0.5P,COG,0201)'                           | 'CHIP0201'     | ''          | ''   | '20191217'
 '6.8PF'    | '25V'   | '0.5PF'   | 'C0201'     | 'EMPTY'   | 'CH-684T0E00'(!)   = ''              | ''                 | ''       | 'CH-684T0E00'    |'C0201'| '(SMC0201AW)'                                                        | 'NA'       | '25V'         | '0.5PF'  | 'IO'       | 'CAP CHIP 6.8P 25V(+-0.5P,COG,0201)'                           | 'CHIP0201'     | ''          | ''   | '20191217'
 '1UF'      | '16V'   | '10%'     | 'C0402'     | 'X7R'     | 'CH5103K1B00'(!)   = 'End of Design' | 'Comp-Release Qty' | ''       | 'CH5103K1B00'    |'C0402_H28'| '(C0402-0201_H28)'                                                   | '1UF'      | '16V'         | '10%'    | 'DISCRETE' | 'CAP CHIP 1UF 16V(+-10%,X7R,0402)'                             | 'CHIP0402'     | ''          | ''   | '20191213'
 '1UF'      | '16V'   | '10%'     | 'C0402'     | 'EMPTY'   | 'CH5103K1B00'(!)   = 'End of Design' | 'Comp-Release Qty' | ''       | 'CH5103K1B00'    |'C0402_H28'| '(C0402-0201_H28)'                                                   | 'NA'       | '16V'         | '10%'    | 'IO'       | 'CAP CHIP 1UF 16V(+-10%,X7R,0402)'                             | 'CHIP0402'     | ''          | ''   | '20191213'
 '330PF'    | '50V'   | '5%'      | 'C0402'     | 'NPO'     | 'CH1336J0B01'(!)   = ''              | ''                 | ''       | 'CH1336J0B01'    |'C0402'| '(C0402-0201)'                                                       | '330PF'    | '50V'         | '5%'     | 'DISCRETE' | 'CAP CHIP 330P,50V(+-5%,NPO,0402)'                             | 'CHIP0402'     | ''          | ''   | '20191213'
 '330PF'    | '50V'   | '5%'      | 'C0402'     | 'EMPTY'   | 'CH1336J0B01'(!)   = ''              | ''                 | ''       | 'CH1336J0B01'    |'C0402'| '(C0402-0201)'                                                       | 'NA'       | '50V'         | '5%'     | 'IO'       | 'CAP CHIP 330P,50V(+-5%,NPO,0402)'                             | 'CHIP0402'     | ''          | ''   | '20191213'
 '5.0PF'    | '50V'   | '0.1PF'   | 'C0402'     | 'C0G'     | 'CH-506B0B00'(!)   = ''              | ''                 | ''       | 'CH-506B0B00'    |'C0402'| '(C0402-0201)'                                                       | '5.0PF'    | '50V'         | '0.1PF'  | 'DISCRETE' | 'CAP CHIP 5.0P 50V(+-0.1P,C0G,0402)'                           | 'CHIP0402'     | ''          | ''   | '20191213'
 '5.0PF'    | '50V'   | '0.1PF'   | 'C0402'     | 'EMPTY'   | 'CH-506B0B00'(!)   = ''              | ''                 | ''       | 'CH-506B0B00'    |'C0402'| '(C0402-0201)'                                                       | 'NA'       | '50V'         | '0.1PF'  | 'IO'       | 'CAP CHIP 5.0P 50V(+-0.1P,C0G,0402)'                           | 'CHIP0402'     | ''          | ''   | '20191213'
 '2.2UF'    | '16V'   | '20%'     | 'C0603'     | 'X7R'     | 'CH5223M1900'(!)   = ''              | ''                 | ''       | 'CH5223M1900'    |'C0603_H40'| '(SMC0603AW)'                                                        | '2.2UF'    | '16V'         | '20%'    | 'DISCRETE' | 'CAP CHIP 2.2UF 16V(20%,X7R,0603)'                             | 'CHIP0603'     | ''          | ''   | '20191216'
 '2.2UF'    | '16V'   | '20%'     | 'C0603'     | 'EMPTY'   | 'CH5223M1900'(!)   = ''              | ''                 | ''       | 'CH5223M1900'    |'C0603_H40'| '(SMC0603AW)'                                                        | 'NA'       | '16V'         | '20%'    | 'IO'       | 'CAP CHIP 2.2UF 16V(20%,X7R,0603)'                             | 'CHIP0603'     | ''          | ''   | '20191216'
 '47000PF'  | '100V'  | '5%'      | 'C1206'     | 'C0G'     | 'CH3478J0200'(!)   = ''              | ''                 | ''       | 'CH3478J0200'    |'C1206XG'| '(SMC1206AW)'                                                        | '47000PF'  | '100V'        | '5%'     | 'DISCRETE' | 'CAP CHIP 47000P 100V(+-5%,C0G,1206)MUR'                       | 'CHIP1206'     | ''          | ''   | '20191220'
 '47000PF'  | '100V'  | '5%'      | 'C1206'     | 'EMPTY'   | 'CH3478J0200'(!)   = ''              | ''                 | ''       | 'CH3478J0200'    |'C1206XG'| '(SMC1206AW)'                                                        | 'NA'       | '100V'        | '5%'     | 'IO'       | 'CAP CHIP 47000P 100V(+-5%,C0G,1206)MUR'                       | 'CHIP1206'     | ''          | ''   | '20191220'
 '27PF'     | '25V'   | '5%'      | 'C0201'     | 'NPO'     | 'CH0274J0E03'(!)   = ''              | ''                 | ''       | 'CH0274J0E03'    |'C0201'| '(SMC0201AW)'                                                        | '27PF'     | '25V'         | '5%'     | 'DISCRETE' | 'CAP CHIP 27PF 25V(+-5%,NPO,0201)'                             | 'CHIP0201'     | ''          | ''   | '20200109'
 '27PF'     | '25V'   | '5%'      | 'C0201'     | 'EMPTY'   | 'CH0274J0E03'(!)   = ''              | ''                 | ''       | 'CH0274J0E03'    |'C0201'| '(SMC0201AW)'                                                        | 'NA'       | '25V'         | '5%'     | 'IO'       | 'CAP CHIP 27PF 25V(+-5%,NPO,0201)'                             | 'CHIP0201'     | ''          | ''   | '20200109'
 '5600PF'   | '50V'   | '10%'     | 'C0402'     | 'X7R'     | 'CH2566K1B00'(!)   = 'End of Design' | 'Comp-Approve'     | ''       | 'CH2566K1B00'    |'C0402'| '(C0402-0201)'                                                       | '5600PF'   | '50V'         | '10%'    | 'DISCRETE' | 'CAP CHIP 5600PF 50V(+-10%,X7R,0402)'                          | 'CHIP0402'     | ''          | ''   | '20200107'
 '5600PF'   | '50V'   | '10%'     | 'C0402'     | 'EMPTY'   | 'CH2566K1B00'(!)   = 'End of Design' | 'Comp-Approve'     | ''       | 'CH2566K1B00'    |'C0402'| '(C0402-0201)'                                                       | 'NA'       | '50V'         | '10%'    | 'IO'       | 'CAP CHIP 5600PF 50V(+-10%,X7R,0402)'                          | 'CHIP0402'     | ''          | ''   | '20200107'
 '39PF'     | '50V'   | '5%'      | 'C0402'     | 'NPO'     | 'CH0396J0B04'(!)   = ''              | ''                 | ''       | 'CH0396J0B04'    |'C0402'| '(C0402-0201)'                                                       | '39PF'     | '50V'         | '5%'     | 'DISCRETE' | 'CAP CHIP 39P 50V(+-5%,NPO,0402)MUR'                           | 'CHIP0402'     | ''          | ''   | '20200218'
 '39PF'     | '50V'   | '5%'      | 'C0402'     | 'EMPTY'   | 'CH0396J0B04'(!)   = ''              | ''                 | ''       | 'CH0396J0B04'    |'C0402'| '(C0402-0201)'                                                       | 'NA'       | '50V'         | '5%'     | 'IO'       | 'CAP CHIP 39P 50V(+-5%,NPO,0402)MUR'                           | 'CHIP0402'     | ''          | ''   | '20200218'
 '8.2PF'    | '50V'   | '0.25PF'  | 'C0402'     | 'NPO'     | 'CH-826C0B05'(!)   = ''              | ''                 | ''       | 'CH-826C0B05'    |'C0402'| '(C0402-0201)'                                                       | '8.2PF'    | '50V'         | '0.25PF' | 'DISCRETE' | 'CAP CHIP 8.2P 50V(+-0.25P,NPO,0402)MUR'                       | 'CHIP0402'     | ''          | ''   | '20200218'
 '8.2PF'    | '50V'   | '0.25PF'  | 'C0402'     | 'EMPTY'   | 'CH-826C0B05'(!)   = ''              | ''                 | ''       | 'CH-826C0B05'    |'C0402'| '(C0402-0201)'                                                       | 'NA'       | '50V'         | '0.25PF' | 'IO'       | 'CAP CHIP 8.2P 50V(+-0.25P,NPO,0402)MUR'                       | 'CHIP0402'     | ''          | ''   | '20200218'
 '0.001UF'  | '50V'   | '10%'     | 'C0402'     | 'X7R'     | 'CH30106KB19'(!)   = 'End of Design' | 'Comp-Release Qty' | ''       | 'CH30106KB19'    |'C0402'| '(C0402-0201)'                                                       | '0.001UF'  | '50V'         | '10%'    | 'DISCRETE' | 'CAP CHIP 0.001U 50V(10%,X7R,0402)'                            | 'CHIP0402'     | ''          | ''   | '20200218'
 '0.001UF'  | '50V'   | '10%'     | 'C0402'     | 'EMPTY'   | 'CH30106KB19'(!)   = 'End of Design' | 'Comp-Release Qty' | ''       | 'CH30106KB19'    |'C0402'| '(C0402-0201)'                                                       | 'NA'       | '50V'         | '10%'    | 'IO'       | 'CAP CHIP 0.001U 50V(10%,X7R,0402)'                            | 'CHIP0402'     | ''          | ''   | '20200218'
 '0.22UF'   | '6.3V'  | '10%'     | 'C0201'     | 'X6S'     | 'CH4221KEE01'(!)   = ''              | ''                 | ''       | 'CH4221KEE01'    |'C0201'| '(SMC0201AW)'                                                        | '0.22UF'   | '6.3V'        | '10%'    | 'DISCRETE' | 'CAP CHIP 0.22UF 6.3V(+-10%,X6S,0201)MUR'                      | 'CHIP0201'     | ''          | ''   | '20200224'
 '0.22UF'   | '6.3V'  | '10%'     | 'C0201'     | 'EMPTY'   | 'CH4221KEE01'(!)   = ''              | ''                 | ''       | 'CH4221KEE01'    |'C0201'| '(SMC0201AW)'                                                        | 'NA'       | '6.3V'        | '10%'    | 'IO'       | 'CAP CHIP 0.22UF 6.3V(+-10%,X6S,0201)MUR'                      | 'CHIP0201'     | ''          | ''   | '20200224'
 '0.022UF'  | '250V'  | '20%'     | 'C0805'     | 'X7R'     | 'CH3220CMA17'(!)   = 'End of Design' | 'Comp-Approve'     | ''       | 'CH3220CMA17'    |'C0805_H57'| '(SMC0805AW)'                                                        | '0.022UF'  | '250V'        | '20%'    | 'DISCRETE' | 'CAP CHIP 0.022U 250V(+-20%,X7R,0805)'                         | 'CHIP0805'     | ''          | ''   | '20200303'
 '0.022UF'  | '250V'  | '20%'     | 'C0805'     | 'EMPTY'   | 'CH3220CMA17'(!)   = 'End of Design' | 'Comp-Approve'     | ''       | 'CH3220CMA17'    |'C0805_H57'| '(SMC0805AW)'                                                        | 'NA'       | '250V'        | '20%'    | 'IO'       | 'CAP CHIP 0.022U 250V(+-20%,X7R,0805)'                         | 'CHIP0805'     | ''          | ''   | '20200303'
 '47PF'     | '50V'   | '5%'      | 'C0402'     | 'NPO'     | 'CH0476J0B12'(!)   = ''              | ''                 | ''       | 'CH0476J0B12'    |'C0402'| '(C0402-0201)'                                                       | '47PF'     | '50V'         | '5%'     | 'DISCRETE' | 'CAP CHIP 47P 50V(+-5%,NPO,0402)MUR'                           | 'CHIP0402'     | ''          | ''   | '20200312'
 '47PF'     | '50V'   | '5%'      | 'C0402'     | 'EMPTY'   | 'CH0476J0B12'(!)   = ''              | ''                 | ''       | 'CH0476J0B12'    |'C0402'| '(C0402-0201)'                                                       | 'NA'       | '50V'         | '5%'     | 'IO'       | 'CAP CHIP 47P 50V(+-5%,NPO,0402)MUR'                           | 'CHIP0402'     | ''          | ''   | '20200312'
 '220PF'    | '100V'  | '10%'     | 'C0402'     | 'X7R'     | 'CH1228K1B01'(!)   = ''              | ''                 | ''       | 'CH1228K1B01'    |'C0402'| '(C0402-0201)'                                                       | '220PF'    | '100V'        | '10%'    | 'DISCRETE' | 'CAP CHIP 220PF 100V(+-10%,X7R,0402)MUR'                       | 'CHIP0402'     | ''          | ''   | '20200312'
 '220PF'    | '100V'  | '10%'     | 'C0402'     | 'EMPTY'   | 'CH1228K1B01'(!)   = ''              | ''                 | ''       | 'CH1228K1B01'    |'C0402'| '(C0402-0201)'                                                       | 'NA'       | '100V'        | '10%'    | 'IO'       | 'CAP CHIP 220PF 100V(+-10%,X7R,0402)MUR'                       | 'CHIP0402'     | ''          | ''   | '20200312'
 '5600PF'   | '50V'   | '10%'     | 'C0402'     | 'X7R'     | 'CH2566K1B09'(!)   = ''              | ''                 | ''       | 'CH2566K1B09'    |'C0402'| '(C0402-0201)'                                                       | '5600PF'   | '50V'         | '10%'    | 'DISCRETE' | 'CAP CHIP 5600P 50V(+-10%,X7R,0402)API'                        | 'CHIP0402'     | ''          | ''   | '20200312'
 '5600PF'   | '50V'   | '10%'     | 'C0402'     | 'EMPTY'   | 'CH2566K1B09'(!)   = ''              | ''                 | ''       | 'CH2566K1B09'    |'C0402'| '(C0402-0201)'                                                       | 'NA'       | '50V'         | '10%'    | 'IO'       | 'CAP CHIP 5600P 50V(+-10%,X7R,0402)API'                        | 'CHIP0402'     | ''          | ''   | '20200312'
 '0.022UF'  | '50V'   | '10%'     | 'C0603'     | 'X7R'     | 'CH3226K1908'(!)   = ''              | ''                 | ''       | 'CH3226K1908'    |'C0603'| '(SMC0603AW)'                                                        | '0.022UF'  | '50V'         | '10%'    | 'DISCRETE' | 'CAP CHIP 0.022U 50V(+-10%,X7R,0603)API'                       | 'CHIP0603'     | ''          | ''   | '20200313'
 '0.022UF'  | '50V'   | '10%'     | 'C0603'     | 'EMPTY'   | 'CH3226K1908'(!)   = ''              | ''                 | ''       | 'CH3226K1908'    |'C0603'| '(SMC0603AW)'                                                        | 'NA'       | '50V'         | '10%'    | 'IO'       | 'CAP CHIP 0.022U 50V(+-10%,X7R,0603)API'                       | 'CHIP0603'     | ''          | ''   | '20200313'
 '22UF'     | '25V'   | '20%'     | 'C0805'     | 'X5R'     | 'CH6224M9A05'(!)   = ''              | ''                 | ''       | 'CH6224M9A05'    |'C0805_H57'| '(SMC0805AW)'                                                        | '22UF'     | '25V'         | '20%'    | 'DISCRETE' | 'CAP CHIP 22U 25V(+-20%,X5R,0805)MUR'                          | 'CHIP0805'     | ''          | ''   | '20200313'
 '22UF'     | '25V'   | '20%'     | 'C0805'     | 'EMPTY'   | 'CH6224M9A05'(!)   = ''              | ''                 | ''       | 'CH6224M9A05'    |'C0805_H57'| '(SMC0805AW)'                                                        | 'NA'       | '25V'         | '20%'    | 'IO'       | 'CAP CHIP 22U 25V(+-20%,X5R,0805)MUR'                          | 'CHIP0805'     | ''          | ''   | '20200313'
 '10UF'     | '25V'   | '20%'     | 'C0603'     | 'X5R'     | 'CH6104M9905'(!)   = ''              | ''                 | ''       | 'CH6104M9905'    |'C0603_H40'| '(SMC0603AW)'                                                        | '10UF'     | '25V'         | '20%'    | 'DISCRETE' | 'CAP CHIP 10UF 25V(+-20%,X5R,0603)MUR'                         | 'CHIP0603'     | ''          | ''   | '20200313'
 '10UF'     | '25V'   | '20%'     | 'C0603'     | 'EMPTY'   | 'CH6104M9905'(!)   = ''              | ''                 | ''       | 'CH6104M9905'    |'C0603_H40'| '(SMC0603AW)'                                                        | 'NA'       | '25V'         | '20%'    | 'IO'       | 'CAP CHIP 10UF 25V(+-20%,X5R,0603)MUR'                         | 'CHIP0603'     | ''          | ''   | '20200313'
 '4.7UF'    | '25V'   | '10%'     | 'C0805'     | 'X7R'     | 'CH5474K1A04'(!)   = 'End of Design' | 'Comp-Approve'     | ''       | 'CH5474K1A04'    |'C0805_H57'| '(SMC0805AW)'                                                        | '4.7UF'    | '25V'         | '10%'    | 'DISCRETE' | 'CAP CHIP 4.7U 25V(+-10%,X7R,0805)MUR'                         | 'CHIP0805'     | ''          | ''   | '20200317'
 '4.7UF'    | '25V'   | '10%'     | 'C0805'     | 'EMPTY'   | 'CH5474K1A04'(!)   = 'End of Design' | 'Comp-Approve'     | ''       | 'CH5474K1A04'    |'C0805_H57'| '(SMC0805AW)'                                                        | 'NA'       | '25V'         | '10%'    | 'IO'       | 'CAP CHIP 4.7U 25V(+-10%,X7R,0805)MUR'                         | 'CHIP0805'     | ''          | ''   | '20200317'
 '220PF'    | '50V'   | '10%'     | 'C0402'     | 'X7R'     | 'CH1226K1B10'(!)   = ''              | ''                 | ''       | 'CH1226K1B10'    |'C0402'| '(C0402-0201)'                                                       | '220PF'    | '50V'         | '10%'    | 'DISCRETE' | 'CAP CHIP 220PF 50V(+-10%,X7R,0402)MUR'                        | 'CHIP0402'     | ''          | ''   | '20200317'
 '220PF'    | '50V'   | '10%'     | 'C0402'     | 'EMPTY'   | 'CH1226K1B10'(!)   = ''              | ''                 | ''       | 'CH1226K1B10'    |'C0402'| '(C0402-0201)'                                                       | 'NA'       | '50V'         | '10%'    | 'IO'       | 'CAP CHIP 220PF 50V(+-10%,X7R,0402)MUR'                        | 'CHIP0402'     | ''          | ''   | '20200317'
 '0.047UF'  | '16V'   | '10%'     | 'C0402'     | 'X7R'     | 'CH3473K1B10'(!)   = ''              | ''                 | ''       | 'CH3473K1B10'    |'C0402'| '(C0402-0201)'                                                       | '0.047UF'  | '16V'         | '10%'    | 'DISCRETE' | 'CAP CHIP 0.047U 16V(+-10%,X7R,0402)MUR'                       | 'CHIP0402'     | ''          | ''   | '20200318'
 '0.047UF'  | '16V'   | '10%'     | 'C0402'     | 'EMPTY'   | 'CH3473K1B10'(!)   = ''              | ''                 | ''       | 'CH3473K1B10'    |'C0402'| '(C0402-0201)'                                                       | 'NA'       | '16V'         | '10%'    | 'IO'       | 'CAP CHIP 0.047U 16V(+-10%,X7R,0402)MUR'                       | 'CHIP0402'     | ''          | ''   | '20200318'
 '4.7UF'    | '16V'   | '10%'     | 'C0603'     | 'X6S'     | 'CH5473KE903'(!)   = ''              | ''                 | ''       | 'CH5473KE903'    |'C0603_H40'| '(SMC0603AW)'                                                        | '4.7UF'    | '16V'         | '10%'    | 'DISCRETE' | 'CAP CHIP 4.7UF 16V(+-10%,X6S,0603)MUR'                        | 'CHIP0603'     | ''          | ''   | '20200318'
 '4.7UF'    | '16V'   | '10%'     | 'C0603'     | 'EMPTY'   | 'CH5473KE903'(!)   = ''              | ''                 | ''       | 'CH5473KE903'    |'C0603_H40'| '(SMC0603AW)'                                                        | 'NA'       | '16V'         | '10%'    | 'IO'       | 'CAP CHIP 4.7UF 16V(+-10%,X6S,0603)MUR'                        | 'CHIP0603'     | ''          | ''   | '20200318'
 '0.047UF'  | '50V'   | '10%'     | 'C0603'     | 'X7R'     | 'CH3476K1905'(!)   = ''              | ''                 | ''       | 'CH3476K1905'    |'C0603'| '(SMC0603AW)'                                                        | '0.047UF'  | '50V'         | '10%'    | 'DISCRETE' | 'CAP CHIP 0.047UF 50V(+-10%,X7R,0603)SAM'                      | 'CHIP0603'     | ''          | ''   | '20200318'
 '0.047UF'  | '50V'   | '10%'     | 'C0603'     | 'EMPTY'   | 'CH3476K1905'(!)   = ''              | ''                 | ''       | 'CH3476K1905'    |'C0603'| '(SMC0603AW)'                                                        | 'NA'       | '50V'         | '10%'    | 'IO'       | 'CAP CHIP 0.047UF 50V(+-10%,X7R,0603)SAM'                      | 'CHIP0603'     | ''          | ''   | '20200318'
 '5PF'      | '50V'   | '0.25PF'  | 'C0402'     | 'C0G'     | 'CH-506C0B04'(!)   = ''              | ''                 | ''       | 'CH-506C0B04'    |'C0402'| '(C0402-0201)'                                                       | '5PF'      | '50V'         | '0.25PF' | 'DISCRETE' | 'CAP CHIP 5P 50V(0.25P,C0G,0402)MUR'                           | 'CHIP0402'     | ''          | ''   | '20200319'
 '5PF'      | '50V'   | '0.25PF'  | 'C0402'     | 'EMPTY'   | 'CH-506C0B04'(!)   = ''              | ''                 | ''       | 'CH-506C0B04'    |'C0402'| '(C0402-0201)'                                                       | 'NA'       | '50V'         | '0.25PF' | 'IO'       | 'CAP CHIP 5P 50V(0.25P,C0G,0402)MUR'                           | 'CHIP0402'     | ''          | ''   | '20200319'
 '8.2PF'    | '50V'   | '0.25PF'  | 'C0402'     | 'NPO'     | 'CH-826C0B07'(!)   = ''              | ''                 | ''       | 'CH-826C0B07'    |'C0402'| '(C0402-0201)'                                                       | '8.2PF'    | '50V'         | '0.25PF' | 'DISCRETE' | 'CAP CHIP 8.2P 50V(+-0.25P,NPO,0402)YGO'                       | 'CHIP0402'     | ''          | ''   | '20200320'
 '8.2PF'    | '50V'   | '0.25PF'  | 'C0402'     | 'EMPTY'   | 'CH-826C0B07'(!)   = ''              | ''                 | ''       | 'CH-826C0B07'    |'C0402'| '(C0402-0201)'                                                       | 'NA'       | '50V'         | '0.25PF' | 'IO'       | 'CAP CHIP 8.2P 50V(+-0.25P,NPO,0402)YGO'                       | 'CHIP0402'     | ''          | ''   | '20200320'
 '39PF'     | '50V'   | '5%'      | 'C0402'     | 'NPO'     | 'CH0396J0B06'(!)   = ''              | ''                 | ''       | 'CH0396J0B06'    |'C0402'| '(C0402-0201)'                                                       | '39PF'     | '50V'         | '5%'     | 'DISCRETE' | 'CAP CHIP 39P 50V(+-5%,NPO,0402)YGO'                           | 'CHIP0402'     | ''          | ''   | '20200327'
 '39PF'     | '50V'   | '5%'      | 'C0402'     | 'EMPTY'   | 'CH0396J0B06'(!)   = ''              | ''                 | ''       | 'CH0396J0B06'    |'C0402'| '(C0402-0201)'                                                       | 'NA'       | '50V'         | '5%'     | 'IO'       | 'CAP CHIP 39P 50V(+-5%,NPO,0402)YGO'                           | 'CHIP0402'     | ''          | ''   | '20200327'
 '1200PF'   | '50V'   | '5%'      | 'C0402'     | 'C0G'     | 'CH2126J0B01'(!)   = 'End of Design' | 'Comp-Approve'     | ''       | 'CH2126J0B01'    |'C0402'| '(C0402-0201)'                                                       | '1200PF'   | '50V'         | '5%'     | 'DISCRETE' | 'CAP CHIP 1200P 50V(+-5%,C0G,0402)MUR'                         | 'CHIP0402'     | ''          | ''   | '20200331'
 '1200PF'   | '50V'   | '5%'      | 'C0402'     | 'EMPTY'   | 'CH2126J0B01'(!)   = 'End of Design' | 'Comp-Approve'     | ''       | 'CH2126J0B01'    |'C0402'| '(C0402-0201)'                                                       | 'NA'       | '50V'         | '5%'     | 'IO'       | 'CAP CHIP 1200P 50V(+-5%,C0G,0402)MUR'                         | 'CHIP0402'     | ''          | ''   | '20200331'
 '27PF'     | '50V'   | '5%'      | 'C0402'     | 'NPO'     | 'CH0276J0B09'(!)   = ''              | ''                 | ''       | 'CH0276J0B09'    |'C0402'| '(C0402-0201)'                                                       | '27PF'     | '50V'         | '5%'     | 'DISCRETE' | 'CAP CHIP 27P 50V(+-5%,NPO,0402)MUR'                           | 'CHIP0402'     | ''          | ''   | '20200331'
 '27PF'     | '50V'   | '5%'      | 'C0402'     | 'EMPTY'   | 'CH0276J0B09'(!)   = ''              | ''                 | ''       | 'CH0276J0B09'    |'C0402'| '(C0402-0201)'                                                       | 'NA'       | '50V'         | '5%'     | 'IO'       | 'CAP CHIP 27P 50V(+-5%,NPO,0402)MUR'                           | 'CHIP0402'     | ''          | ''   | '20200331'
 '10UF'     | '35V'   | '10%'     | 'C0805'     | 'X6S'     | 'CH6105KEA01'(!)   = 'End of Design' | 'Comp-Approve'     | ''       | 'CH6105KEA01'    |'C0805_H57'| '(SMC0805AW)'                                                        | '10UF'     | '35V'         | '10%'    | 'DISCRETE' | 'CAP CHIP 10UF 35V(+-10%,X6S,0805)'                            | 'CHIP0805'     | ''          | ''   | '20200410'
 '10UF'     | '35V'   | '10%'     | 'C0805'     | 'EMPTY'   | 'CH6105KEA01'(!)   = 'End of Design' | 'Comp-Approve'     | ''       | 'CH6105KEA01'    |'C0805_H57'| '(SMC0805AW)'                                                        | 'NA'       | '35V'         | '10%'    | 'IO'       | 'CAP CHIP 10UF 35V(+-10%,X6S,0805)'                            | 'CHIP0805'     | ''          | ''   | '20200410'
 '5600PF'   | '50V'   | '10%'     | 'C0402'     | 'X7R'     | 'CH2566K1B06'(!)   = ''              | ''                 | ''       | 'CH2566K1B06'    |'C0402'| '(C0402-0201)'                                                       | '5600PF'   | '50V'         | '10%'    | 'DISCRETE' | 'CAP CHIP 5600PF 50V(+-10%,X7R,0402)SAM'                       | 'CHIP0402'     | ''          | ''   | '20200410'
 '5600PF'   | '50V'   | '10%'     | 'C0402'     | 'EMPTY'   | 'CH2566K1B06'(!)   = ''              | ''                 | ''       | 'CH2566K1B06'    |'C0402'| '(C0402-0201)'                                                       | 'NA'       | '50V'         | '10%'    | 'IO'       | 'CAP CHIP 5600PF 50V(+-10%,X7R,0402)SAM'                       | 'CHIP0402'     | ''          | ''   | '20200410'
 '0.047UF'  | '50V'   | '10%'     | 'C0402'     | 'X7R'     | 'CH3476K1B10'(!)   = ''              | ''                 | ''       | 'CH3476K1B10'    |'C0402'| '(C0402-0201)'                                                       | '0.047UF'  | '50V'         | '10%'    | 'DISCRETE' | 'CAP CHIP 0.047UF 50V(+-10%,X7R,0402)MUR'                      | 'CHIP0402'     | ''          | ''   | '20200520'
 '0.047UF'  | '50V'   | '10%'     | 'C0402'     | 'EMPTY'   | 'CH3476K1B10'(!)   = ''              | ''                 | ''       | 'CH3476K1B10'    |'C0402'| '(C0402-0201)'                                                       | 'NA'       | '50V'         | '10%'    | 'IO'       | 'CAP CHIP 0.047UF 50V(+-10%,X7R,0402)MUR'                      | 'CHIP0402'     | ''          | ''   | '20200520'
 '0.022UF'  | '100V'  | '10%'     | 'C0805'     | 'X7R'     | 'CH3228K1A00'(!)   = 'End of Design' | 'Comp-Approve'     | ''       | 'CH3228K1A00'    |'C0805_H57'| '(SMC0805AW)'                                                        | '0.022UF'  | '100V'        | '10%'    | 'DISCRETE' | 'CAP CHIP 0.022UF 100V(+-10%,X7R,0805)SAM'                     | 'CHIP0805'     | ''          | ''   | '20200520'
 '0.022UF'  | '100V'  | '10%'     | 'C0805'     | 'EMPTY'   | 'CH3228K1A00'(!)   = 'End of Design' | 'Comp-Approve'     | ''       | 'CH3228K1A00'    |'C0805_H57'| '(SMC0805AW)'                                                        | 'NA'       | '100V'        | '10%'    | 'IO'       | 'CAP CHIP 0.022UF 100V(+-10%,X7R,0805)SAM'                     | 'CHIP0805'     | ''          | ''   | '20200520'
 '68NF'     | '50V'   | '10%'     | 'C0603'     | 'X7R'     | 'CH3686K1902'(!)   = ''              | ''                 | ''       | 'CH3686K1902'    |'C0603'| '(SMC0603AW)'                                                        | '68NF'     | '50V'         | '10%'    | 'DISCRETE' | 'CAP CHIP 68NF 50V(+-10%,X7R,0603)SAM'                         | 'CHIP0603'     | ''          | ''   | '20200527'
 '68NF'     | '50V'   | '10%'     | 'C0603'     | 'EMPTY'   | 'CH3686K1902'(!)   = ''              | ''                 | ''       | 'CH3686K1902'    |'C0603'| '(SMC0603AW)'                                                        | 'NA'       | '50V'         | '10%'    | 'IO'       | 'CAP CHIP 68NF 50V(+-10%,X7R,0603)SAM'                         | 'CHIP0603'     | ''          | ''   | '20200527'
 '0.01UF'   | '100V'  | '10%'     | 'C1206'     | 'X7R'     | 'CH3108K1200'(!)   = ''              | ''                 | ''       | 'CH3108K1200'    |'C1206XG_H38'| '(SMC1206AW)'                                                        | '0.01UF'   | '100V'        | '10%'    | 'DISCRETE' | 'CAP CHIP 0.01U 100V(+-10%,X7R,1206)MUR'                       | 'CHIP1206'     | ''          | ''   | '20200617'
 '0.01UF'   | '100V'  | '10%'     | 'C1206'     | 'EMPTY'   | 'CH3108K1200'(!)   = ''              | ''                 | ''       | 'CH3108K1200'    |'C1206XG_H38'| '(SMC1206AW)'                                                        | 'NA'       | '100V'        | '10%'    | 'IO'       | 'CAP CHIP 0.01U 100V(+-10%,X7R,1206)MUR'                       | 'CHIP1206'     | ''          | ''   | '20200617'
 '10UF'     | '4V'    | '20%'     | 'C0402'     | 'X6S'     | 'CH610KMEB09'(!)   = ''              | ''                 | ''       | 'CH610KMEB09'    |'C0402_H28'| '(C0402-0201_H28)'                                                   | '10UF'     | '4V'          | '20%'    | 'DISCRETE' | 'CAP CHIP 10U 4V(+-20%,X6S,0402)MUR'                           | 'CHIP0402'     | ''          | ''   | '20200807'
 '10UF'     | '4V'    | '20%'     | 'C0402'     | 'EMPTY'   | 'CH610KMEB09'(!)   = ''              | ''                 | ''       | 'CH610KMEB09'    |'C0402_H28'| '(C0402-0201_H28)'                                                   | 'NA'       | '4V'          | '20%'    | 'IO'       | 'CAP CHIP 10U 4V(+-20%,X6S,0402)MUR'                           | 'CHIP0402'     | ''          | ''   | '20200807'
 '4700PF'   | '50V'   | '5%'      | 'C0603'     | 'C0G'     | 'CH2476J0902'(!)   = ''              | ''                 | ''       | 'CH2476J0902'    |'C0603_H40'| '(SMC0603AW)'                                                        | '4700PF'   | '50V'         | '5%'     | 'DISCRETE' | 'CAP CHIP 4700P 50V(+-5%,C0G,0603)MUR'                         | 'CHIP0603'     | ''          | ''   | '20200813'
 '4700PF'   | '50V'   | '5%'      | 'C0603'     | 'EMPTY'   | 'CH2476J0902'(!)   = ''              | ''                 | ''       | 'CH2476J0902'    |'C0603_H40'| '(SMC0603AW)'                                                        | 'NA'       | '50V'         | '5%'     | 'IO'       | 'CAP CHIP 4700P 50V(+-5%,C0G,0603)MUR'                         | 'CHIP0603'     | ''          | ''   | '20200813'
 '6.8PF'    | '50V'   | '0.25PF'  | 'C0402'     | 'C0G'     | 'CH-686C0B04'(!)   = ''              | ''                 | ''       | 'CH-686C0B04'    |'C0402'| '(C0402-0201)'                                                       | '6.8PF'    | '50V'         | '0.25PF' | 'DISCRETE' | 'CAP CHIP 6.8P 50V(+-0.25P,C0G,0402)YGO'                       | 'CHIP0402'     | ''          | ''   | '20200824'
 '6.8PF'    | '50V'   | '0.25PF'  | 'C0402'     | 'EMPTY'   | 'CH-686C0B04'(!)   = ''              | ''                 | ''       | 'CH-686C0B04'    |'C0402'| '(C0402-0201)'                                                       | 'NA'       | '50V'         | '0.25PF' | 'IO'       | 'CAP CHIP 6.8P 50V(+-0.25P,C0G,0402)YGO'                       | 'CHIP0402'     | ''          | ''   | '20200824'
 '22NF'     | '100V'  | '10%'     | 'C0805'     | 'X7R'     | 'CH3228K1A02'(!)   = ''              | ''                 | ''       | 'CH3228K1A02'    |'C0805_H43'| '(SMC0805AW)'                                                        | '22NF'     | '100V'        | '10%'    | 'DISCRETE' | 'CAP CHIP 22N 100V(+-10%,X7R,0805)YGO'                         | 'CHIP0805'     | ''          | ''   | '20200824'
 '22NF'     | '100V'  | '10%'     | 'C0805'     | 'EMPTY'   | 'CH3228K1A02'(!)   = ''              | ''                 | ''       | 'CH3228K1A02'    |'C0805_H43'| '(SMC0805AW)'                                                        | 'NA'       | '100V'        | '10%'    | 'IO'       | 'CAP CHIP 22N 100V(+-10%,X7R,0805)YGO'                         | 'CHIP0805'     | ''          | ''   | '20200824'
 '2.2UF'    | '16V'   | '10%'     | 'C0402'     | 'X6S'     | 'CH5223KEB01'(!)   = ''              | ''                 | ''       | 'CH5223KEB01'    |'C0402_H28'| '(C0402-0201_H28)'                                                   | '2.2UF'    | '16V'         | '10%'    | 'DISCRETE' | 'CAP CHIP 2.2U 16V(+-10%,X6S,0402)'                            | 'CHIP0402'     | ''          | ''   | '20200903'
 '2.2UF'    | '16V'   | '10%'     | 'C0402'     | 'EMPTY'   | 'CH5223KEB01'(!)   = ''              | ''                 | ''       | 'CH5223KEB01'    |'C0402_H28'| '(C0402-0201_H28)'                                                   | 'NA'       | '16V'         | '10%'    | 'IO'       | 'CAP CHIP 2.2U 16V(+-10%,X6S,0402)'                            | 'CHIP0402'     | ''          | ''   | '20200903'
 '75PF'     | '50V'   | '5%'      | 'C0402'     | 'C0G'     | 'CH0756J0B00'(!)   = 'End of Design' | 'Comp-Approve'     | ''       | 'CH0756J0B00'    |'C0402'| '(C0402-0201)'                                                       | '75PF'     | '50V'         | '5%'     | 'DISCRETE' | 'CAP CHIP 75PF 50V(+-5%,C0G,0402)'                             | 'CHIP0402'     | ''          | ''   | '20200909'
 '75PF'     | '50V'   | '5%'      | 'C0402'     | 'EMPTY'   | 'CH0756J0B00'(!)   = 'End of Design' | 'Comp-Approve'     | ''       | 'CH0756J0B00'    |'C0402'| '(C0402-0201)'                                                       | 'NA'       | '50V'         | '5%'     | 'IO'       | 'CAP CHIP 75PF 50V(+-5%,C0G,0402)'                             | 'CHIP0402'     | ''          | ''   | '20200909'
 '150PF'    | '50V'   | '5%'      | 'C0402'     | 'C0G'     | 'CH1156J0B00'(!)   = ''              | ''                 | ''       | 'CH1156J0B00'    |'C0402'| '(C0402-0201)'                                                       | '150PF'    | '50V'         | '5%'     | 'DISCRETE' | 'CAP CHIP 150P 50V(+-5%,0402,C0G)'                             | 'CHIP0402'     | ''          | ''   | '20200909'
 '150PF'    | '50V'   | '5%'      | 'C0402'     | 'EMPTY'   | 'CH1156J0B00'(!)   = ''              | ''                 | ''       | 'CH1156J0B00'    |'C0402'| '(C0402-0201)'                                                       | 'NA'       | '50V'         | '5%'     | 'IO'       | 'CAP CHIP 150P 50V(+-5%,0402,C0G)'                             | 'CHIP0402'     | ''          | ''   | '20200909'
 '51PF'     | '50V'   | '5%'      | 'C0402'     | 'NPO'     | 'CH0516J0B07'(!)   = ''              | ''                 | ''       | 'CH0516J0B07'    |'C0402'| '(C0402-0201)'                                                       | '51PF'     | '50V'         | '5%'     | 'DISCRETE' | 'CAP CHIP 51P 50V+-5% NPO(0402)'                               | 'CHIP0402'     | ''          | ''   | '20200914'
 '51PF'     | '50V'   | '5%'      | 'C0402'     | 'EMPTY'   | 'CH0516J0B07'(!)   = ''              | ''                 | ''       | 'CH0516J0B07'    |'C0402'| '(C0402-0201)'                                                       | 'NA'       | '50V'         | '5%'     | 'IO'       | 'CAP CHIP 51P 50V+-5% NPO(0402)'                               | 'CHIP0402'     | ''          | ''   | '20200914'
 '18PF'     | '50V'   | '2%'      | 'C0402'     | 'NP0'     | 'CH0186G0B00'(!)   = ''              | ''                 | ''       | 'CH0186G0B00'    |'C0402'| '(C0402-0201)'                                                       | '18PF'     | '50V'         | '2%'     | 'DISCRETE' | 'CAP CHIP 18PF 50V(+-2%,NP0,0402)H0.55'                        | 'CHIP0402'     | ''          | ''   | '20200914'
 '18PF'     | '50V'   | '2%'      | 'C0402'     | 'EMPTY'   | 'CH0186G0B00'(!)   = ''              | ''                 | ''       | 'CH0186G0B00'    |'C0402'| '(C0402-0201)'                                                       | 'NA'       | '50V'         | '2%'     | 'IO'       | 'CAP CHIP 18PF 50V(+-2%,NP0,0402)H0.55'                        | 'CHIP0402'     | ''          | ''   | '20200914'
 '0.3PF'    | '50V'   | '0.05PF'  | 'C0402'     | 'C0G'     | 'CH+306T0B00'(!)   = ''              | ''                 | ''       | 'CH+306T0B00'    |'C0402'| '(C0402-0201)'                                                       | '0.3PF'    | '50V'         | '0.05PF' | 'DISCRETE' | 'CAP CHIP 0.3P 50V(+-0.05P,C0G,0402)'                          | 'CHIP0402'     | ''          | ''   | '20200916'
 '0.3PF'    | '50V'   | '0.05PF'  | 'C0402'     | 'EMPTY'   | 'CH+306T0B00'(!)   = ''              | ''                 | ''       | 'CH+306T0B00'    |'C0402'| '(C0402-0201)'                                                       | 'NA'       | '50V'         | '0.05PF' | 'IO'       | 'CAP CHIP 0.3P 50V(+-0.05P,C0G,0402)'                          | 'CHIP0402'     | ''          | ''   | '20200916'
 '6.8PF'    | '50V'   | '0.5PF'   | 'C0603'     | 'NPO'     | 'CH-6806T901'(!)   = ''              | ''                 | ''       | 'CH-6806T901'    |'C0603'| '(SMC0603AW)'                                                        | '6.8PF'    | '50V'         | '0.5PF'  | 'DISCRETE' | 'CAP CHIP 6.8P 50V(+-0.5P 0603 NPO)'                           | 'CHIP0603'     | ''          | ''   | '20200916'
 '6.8PF'    | '50V'   | '0.5PF'   | 'C0603'     | 'EMPTY'   | 'CH-6806T901'(!)   = ''              | ''                 | ''       | 'CH-6806T901'    |'C0603'| '(SMC0603AW)'                                                        | 'NA'       | '50V'         | '0.5PF'  | 'IO'       | 'CAP CHIP 6.8P 50V(+-0.5P 0603 NPO)'                           | 'CHIP0603'     | ''          | ''   | '20200916'
 '0.2PF'    | '50V'   | '0.05PF'  | 'C0402'     | 'C0G'     | 'CH+206T0B00'(!)   = ''              | ''                 | ''       | 'CH+206T0B00'    |'C0402'| '(C0402-0201)'                                                       | '0.2PF'    | '50V'         | '0.05PF' | 'DISCRETE' | 'CAP CHIP 0.2P 50V(+-0.05P,C0G,0402)'                          | 'CHIP0402'     | ''          | ''   | '20200916'
 '0.2PF'    | '50V'   | '0.05PF'  | 'C0402'     | 'EMPTY'   | 'CH+206T0B00'(!)   = ''              | ''                 | ''       | 'CH+206T0B00'    |'C0402'| '(C0402-0201)'                                                       | 'NA'       | '50V'         | '0.05PF' | 'IO'       | 'CAP CHIP 0.2P 50V(+-0.05P,C0G,0402)'                          | 'CHIP0402'     | ''          | ''   | '20200916'
 '4.7UF'    | '25V'   | '10%'     | 'C0805'     | 'X5R'     | 'CH5474K9A01'(!)   = 'End of Design' | 'Comp-Release Qty' | ''       | 'CH5474K9A01'    |'C0805_H57'| '(SMC0805AW)'                                                        | '4.7UF'    | '25V'         | '10%'    | 'DISCRETE' | 'CAPACITOR CHIP 4.7U 25V(+-10% X5R 0805)'                      | 'CHIP0805'     | ''          | ''   | '20200916'
 '4.7UF'    | '25V'   | '10%'     | 'C0805'     | 'EMPTY'   | 'CH5474K9A01'(!)   = 'End of Design' | 'Comp-Release Qty' | ''       | 'CH5474K9A01'    |'C0805_H57'| '(SMC0805AW)'                                                        | 'NA'       | '100V'        | '10%'    | 'IO'       | 'CAPACITOR CHIP 4.7U 25V(+-10% X5R 0805)'                      | 'CHIP0805'     | ''          | ''   | '20200916'
 '0.5PF'    | '50V'   | '0.1PF'   | 'C0402'     | 'NPO'     | 'CH+5016TB01'(!)   = ''              | ''                 | ''       | 'CH+5016TB01'    |'C0402'| '(C0402-0201)'                                                       | '0.5PF'    | '50V'         | '0.1PF'  | 'DISCRETE' | 'CAP CHIP 0.5P 50V(+-0.1P,NPO,0402)'                           | 'CHIP0402'     | ''          | ''   | '20200918'
 '0.5PF'    | '50V'   | '0.1PF'   | 'C0402'     | 'EMPTY'   | 'CH+5016TB01'(!)   = ''              | ''                 | ''       | 'CH+5016TB01'    |'C0402'| '(C0402-0201)'                                                       | 'NA'       | '50V'         | '0.1PF'  | 'IO'       | 'CAP CHIP 0.5P 50V(+-0.1P,NPO,0402)'                           | 'CHIP0402'     | ''          | ''   | '20200918'
 '47UF'     | '25V'   | '20%'     | 'C1206'     | 'X5R'     | 'CH6474M9200'(!)   = 'End of Design' | 'Comp-Release Qty' | ''       | 'CH6474M9200'    |'C1206XH'| '(SMC1206AW)'                                                        | '47UF'     | '25V'         | '20%'    | 'DISCRETE' | 'CAP CHIP 47U 25V(+-20%,X5R,1206)'                             | 'CHIP1206'     | ''          | ''   | '20200921'
 '47UF'     | '25V'   | '20%'     | 'C1206'     | 'EMPTY'   | 'CH6474M9200'(!)   = 'End of Design' | 'Comp-Release Qty' | ''       | 'CH6474M9200'    |'C1206XH'| '(SMC1206AW)'                                                        | 'NA'       | '25V'         | '20%'    | 'IO'       | 'CAP CHIP 47U 25V(+-20%,X5R,1206)'                             | 'CHIP1206'     | ''          | ''   | '20200921'
 '10UF'     | '50V'   | '10%'     | 'C1206'     | 'X5R'     | 'CH6106K9201'(!)   = 'End of Design' | 'Comp-Release Qty' | ''       | 'CH6106K9201'    |'C1206XI'| '(SMC1206AW)'                                                        | '10UF'     | '50V'         | '10%'    | 'DISCRETE' | 'CAP CHIP 10UF 50V(+-10%,X5R,1206)'                            | 'CHIP1206'     | ''          | ''   | '20200923'
 '10UF'     | '50V'   | '10%'     | 'C1206'     | 'EMPTY'   | 'CH6106K9201'(!)   = 'End of Design' | 'Comp-Release Qty' | ''       | 'CH6106K9201'    |'C1206XI'| '(SMC1206AW)'                                                        | 'NA'       | '50V'         | '10%'    | 'IO'       | 'CAP CHIP 10UF 50V(+-10%,X5R,1206)'                            | 'CHIP1206'     | ''          | ''   | '20200923'
 '100UF'    | '10V'   | '20%'     | 'C1210'     | 'X5R'     | 'CH7102M9300'(!)   = 'End of Design' | 'Comp-Approve'     | ''       | 'CH7102M9300'    |'C1210_CL32A'| '(SMC1210AW)'                                                        | '100UF'    | '10V'         | '20%'    | 'DISCRETE' | 'CAP CHIP 100U 10V(+-20%,X5R,1210)H2.5'                        | 'CHIP1210'     | ''          | ''   | '20200923'
 '100UF'    | '10V'   | '20%'     | 'C1210'     | 'EMPTY'   | 'CH7102M9300'(!)   = 'End of Design' | 'Comp-Approve'     | ''       | 'CH7102M9300'    |'C1210_CL32A'| '(SMC1210AW)'                                                        | 'NA'       | '10V'         | '20%'    | 'IO'       | 'CAP CHIP 100U 10V(+-20%,X5R,1210)H2.5'                        | 'CHIP1210'     | ''          | ''   | '20200923'
 '4.7UF'    | '100V'  | '10%'     | 'C1206'     | 'X7S'     | 'CH5478K6201'(!)   = 'End of Design' | 'Comp-Approve'     | ''       | 'CH5478K6201'    |'C1206XB'| '(SMC1206AW)'                                                        | '4.7UF'    | '100V'        | '10%'    | 'DISCRETE' | 'CAP CHIP 4.7U 100V(10%,X7S,1206)'                             | 'CHIP1206'     | ''          | ''   | '20200925'
 '4.7UF'    | '100V'  | '10%'     | 'C1206'     | 'EMPTY'   | 'CH5478K6201'(!)   = 'End of Design' | 'Comp-Approve'     | ''       | 'CH5478K6201'    |'C1206XB'| '(SMC1206AW)'                                                        | 'NA'       | '100V'        | '10%'    | 'IO'       | 'CAP CHIP 4.7U 100V(10%,X7S,1206)'                             | 'CHIP1206'     | ''          | ''   | '20200925'
 '47UF'     | '6.3V'  | '20%'     | 'C0805'     | 'X6S'     | 'CH6471MEA02'(!)   = ''              | ''                 | ''       | 'CH6471MEA02'    |'C0805_H57'| '(C0805_BHS)'                                                        | '47UF'     | '6.3V'        | '20%'    | 'DISCRETE' | 'CAP CHIP 47U 6.3V(+-20%,X6S,0805)'                            | 'CHIP0805'     | ''          | ''   | '20200930'
 '47UF'     | '6.3V'  | '20%'     | 'C0805'     | 'EMPTY'   | 'CH6471MEA02'(!)   = ''              | ''                 | ''       | 'CH6471MEA02'    |'C0805_H57'| '(C0805_BHS)'                                                        | 'NA'       | '6.3V'        | '20%'    | 'IO'       | 'CAP CHIP 47U 6.3V(+-20%,X6S,0805)'                            | 'CHIP0805'     | ''          | ''   | '20200930'
 '4.7UF'    | '100V'  | '10%'     | 'C1206'     | 'X7R'     | 'CH5478K1201'(!)   = 'End of Design' | 'Comp-Approve'     | ''       | 'CH5478K1201'    |'C1206XB'| '(SMC1206AW)'                                                        | '4.7UF'    | '100V'        | '10%'    | 'DISCRETE' | 'CAP CHIP 4.7UF 100V(+-10%,X7R,1206)'                          | 'CHIP1206'     | ''          | ''   | '20201026'
 '4.7UF'    | '100V'  | '10%'     | 'C1206'     | 'EMPTY'   | 'CH5478K1201'(!)   = 'End of Design' | 'Comp-Approve'     | ''       | 'CH5478K1201'    |'C1206XB'| '(SMC1206AW)'                                                        | 'NA'       | '100V'        | '10%'    | 'IO'       | 'CAP CHIP 4.7UF 100V(+-10%,X7R,1206)'                          | 'CHIP1206'     | ''          | ''   | '20201026'
 '0.1UF'    | '25V'   | '10%'     | 'C0402'     | 'X7R'     | 'CH4104K1B13'(!)   = ''              | ''                 | ''       | 'CH4104K1B13'    |'C0402'| '(C0402-0201)'                                                       | '0.1UF'    | '25V'         | '10%'    | 'DISCRETE' | 'CAP CHIP 0.1U 25V(+-10%,X7R,0402)YGO'                         | 'CHIP0402'     | ''          | ''   | '20201223'
 '0.1UF'    | '25V'   | '10%'     | 'C0402'     | 'EMPTY'   | 'CH4104K1B13'(!)   = ''              | ''                 | ''       | 'CH4104K1B13'    |'C0402'| '(C0402-0201)'                                                       | 'NA'       | '25V'         | '10%'    | 'IO'       | 'CAP CHIP 0.1U 25V(+-10%,X7R,0402)YGO'                         | 'CHIP0402'     | ''          | ''   | '20201223'
 '33PF'     | '50V'   | '5%'      | 'C0402'     | 'NPO'     | 'CH0336J0B19'(!)   = ''              | ''                 | ''       | 'CH0336J0B19'    |'C0402'| '(C0402-0201)'                                                       | '33PF'     | '50V'         | '5%'     | 'DISCRETE' | 'CAP CHIP 33P 50V(+-5%,NPO,0402)YGO'                           | 'CHIP0402'     | ''          | ''   | '20201223'
 '33PF'     | '50V'   | '5%'      | 'C0402'     | 'EMPTY'   | 'CH0336J0B19'(!)   = ''              | ''                 | ''       | 'CH0336J0B19'    |'C0402'| '(C0402-0201)'                                                       | 'NA'       | '50V'         | '5%'     | 'IO'       | 'CAP CHIP 33P 50V(+-5%,NPO,0402)YGO'                           | 'CHIP0402'     | ''          | ''   | '20201223'
 '220PF'    | '50V'   | '5%'      | 'C0402'     | 'C0G'     | 'CH1226J0B04'(!)   = ''              | ''                 | ''       | 'CH1226J0B04'    |'C0402'| '(C0402-0201)'                                                       | '220PF'    | '50V'         | '5%'     | 'DISCRETE' | 'CAP CHIP 220P 50V(+-5%,C0G,0402)SAM'                          | 'CHIP0402'     | ''          | ''   | '20201223'
 '220PF'    | '50V'   | '5%'      | 'C0402'     | 'EMPTY'   | 'CH1226J0B04'(!)   = ''              | ''                 | ''       | 'CH1226J0B04'    |'C0402'| '(C0402-0201)'                                                       | 'NA'       | '50V'         | '5%'     | 'IO'       | 'CAP CHIP 220P 50V(+-5%,C0G,0402)SAM'                          | 'CHIP0402'     | ''          | ''   | '20201223'
 '0.01UF'   | '50V'   | '10%'     | 'C0603'     | 'X7R'     | 'CH3106K1921'(!)   = ''              | ''                 | ''       | 'CH3106K1921'    |'C0603'| '(SMC0603AW)'                                                        | '0.01UF'   | '50V'         | '10%'    | 'DISCRETE' | 'CAP CHIP 0.01U 50V(+-10%,X7R,0603)YGO'                        | 'CHIP0603'     | ''          | ''   | '20201223'
 '0.01UF'   | '50V'   | '10%'     | 'C0603'     | 'EMPTY'   | 'CH3106K1921'(!)   = ''              | ''                 | ''       | 'CH3106K1921'    |'C0603'| '(SMC0603AW)'                                                        | 'NA'       | '50V'         | '10%'    | 'IO'       | 'CAP CHIP 0.01U 50V(+-10%,X7R,0603)YGO'                        | 'CHIP0603'     | ''          | ''   | '20201223'
 '0.2PF'    | '50V'   | '0.1PF'   | 'C0603'     | 'NPO'     | 'CH+206B0900'(!)   = ''              | ''                 | ''       | 'CH+206B0900'    |'C0603'| '(SMC0603AW)'                                                        | '0.2PF'    | '50V'         | '0.1PF'  | 'DISCRETE' | 'CAP CHIP 0.2PF 50V(+-0.1P,NPO,0603)HQ'                        | 'CHIP0603'     | ''          | ''   | '20201223'
 '0.2PF'    | '50V'   | '0.1PF'   | 'C0603'     | 'EMPTY'   | 'CH+206B0900'(!)   = ''              | ''                 | ''       | 'CH+206B0900'    |'C0603'| '(SMC0603AW)'                                                        | 'NA'       | '50V'         | '0.1PF'  | 'IO'       | 'CAP CHIP 0.2PF 50V(+-0.1P,NPO,0603)HQ'                        | 'CHIP0603'     | ''          | ''   | '20201223'
 '5.6PF'    | '50V'   | '0.5PF'   | 'C0402'     | 'NPO'     | 'CH-566D0B01'(!)   = ''              | ''                 | ''       | 'CH-566D0B01'    |'C0402'| '(C0402-0201)'                                                       | '5.6PF'    | '50V'         | '0.5PF'  | 'DISCRETE' | 'CAP CHIP 5.6P 50V(+-0.5P,NPO,0402)'                           | 'CHIP0402'     | ''          | ''   | '20210126'
 '5.6PF'    | '50V'   | '0.5PF'   | 'C0402'     | 'EMPTY'   | 'CH-566D0B01'(!)   = ''              | ''                 | ''       | 'CH-566D0B01'    |'C0402'| '(C0402-0201)'                                                       | 'NA'       | '50V'         | '0.5PF'  | 'IO'       | 'CAP CHIP 5.6P 50V(+-0.5P,NPO,0402)'                           | 'CHIP0402'     | ''          | ''   | '20210126'
 '100UF'    | '6.3V'  | '20%'     | 'C1210'     | 'X6S'     | 'CH7101ME301'(!)   = ''              | ''                 | ''       | 'CH7101ME301'    |'C1210_CL32X'| '(SMC1210AW)'                                                        | '100UF'    | '6.3V'        | '20%'    | 'DISCRETE' | 'CAP CHIP 100U 6.3V(+-20%,X6S,1210)'                           | 'CHIP1210'     | ''          | ''   | '20210325'
 '100UF'    | '6.3V'  | '20%'     | 'C1210'     | 'EMPTY'   | 'CH7101ME301'(!)   = ''              | ''                 | ''       | 'CH7101ME301'    |'C1210_CL32X'| '(SMC1210AW)'                                                        | 'NA'       | '6.3V'        | '20%'    | 'IO'       | 'CAP CHIP 100U 6.3V(+-20%,X6S,1210)'                           | 'CHIP1210'     | ''          | ''   | '20210325'
 '330UF'    | '2.5V'  | '20%'     | 'C1210'     | 'X6S'     | 'CH733LME301'(!)   = ''              | ''                 | ''       | 'CH733LME301'    |'C1210_GRM32EXA'| '(SMC1210AW)'                                                        | '330UF'    | '2.5V'        | '20%'    | 'DISCRETE' | 'CAP CHIP 330UF 2.5V(+-20%,X6S,1210)'                          | 'CHIP1210'     | ''          | ''   | '20210407'
 '330UF'    | '2.5V'  | '20%'     | 'C1210'     | 'EMPTY'   | 'CH733LME301'(!)   = ''              | ''                 | ''       | 'CH733LME301'    |'C1210_GRM32EXA'| '(SMC1210AW)'                                                        | 'NA'       | '2.5V'        | '20%'    | 'IO'       | 'CAP CHIP 330UF 2.5V(+-20%,X6S,1210)'                          | 'CHIP1210'     | ''          | ''   | '20210407'
 '10UF'     | '4V'    | '20%'     | 'C0402'     | 'X6S'     | 'CH610KMEB10'(!)   = ''              | ''                 | ''       | 'CH610KMEB10'    |'C0402_H28'| '(C0402-0201_H28)'                                                   | '10UF'     | '4V'          | '20%'    | 'DISCRETE' | 'CAP CHIP 10U 4V(+-20%,X6S,0402)'                              | 'CHIP0402'     | ''          | ''   | '20210426'
 '10UF'     | '4V'    | '20%'     | 'C0402'     | 'EMPTY'   | 'CH610KMEB10'(!)   = ''              | ''                 | ''       | 'CH610KMEB10'    |'C0402_H28'| '(C0402-0201_H28)'                                                   | 'NA'       | '4V'          | '20%'    | 'IO'       | 'CAP CHIP 10U 4V(+-20%,X6S,0402)'                              | 'CHIP0402'     | ''          | ''   | '20210426'
 '220UF'    | '4V'    | '20%'     | 'C1206'     | 'X6S'     | 'CH722KME201'(!)   = ''              | ''                 | ''       | 'CH722KME201'    |'C1206XB'| '(SMC1206AW)'                                                        | '220UF'    | '4V'          | '20%'    | 'DISCRETE' | 'CAP CHIP 220U 4V(+-20%,X6S,1206)MUR'                          | 'CHIP1206'     | ''          | ''   | '20210426'
 '220UF'    | '4V'    | '20%'     | 'C1206'     | 'EMPTY'   | 'CH722KME201'(!)   = ''              | ''                 | ''       | 'CH722KME201'    |'C1206XB'| '(SMC1206AW)'                                                        | 'NA'       | '4V'          | '20%'    | 'IO'       | 'CAP CHIP 220U 4V(+-20%,X6S,1206)MUR'                          | 'CHIP1206'     | ''          | ''   | '20210426'
 '2.2UF'    | '6.3V'  | '20%'     | 'C0201'     | 'X5R'     | 'CH5221M9E07'(!)   = ''              | ''                 | ''       | 'CH5221M9E07'    |'C0201_H16'| '(C0201_HOME-PLATE_H22)'                                             | '2.2UF'    | '6.3V'        | '20%'    | 'DISCRETE' | 'CAP CHIP 2.2UF 6.3V(+-20%,X5R,0201)SAM'                       | 'CHIP0201'     | ''          | ''   | '20210429'
 '2.2UF'    | '6.3V'  | '20%'     | 'C0201'     | 'EMPTY'   | 'CH5221M9E07'(!)   = ''              | ''                 | ''       | 'CH5221M9E07'    |'C0201_H16'| '(C0201_HOME-PLATE_H22)'                                             | 'NA'       | '6.3V'        | '20%'    | 'IO'       | 'CAP CHIP 2.2UF 6.3V(+-20%,X5R,0201)SAM'                       | 'CHIP0201'     | ''          | ''   | '20210429'
 '10UF'     | '6.3V'  | '20%'     | 'C0402'     | 'X6S'     | 'CH6101MEB08'(!)   = ''              | ''                 | ''       | 'CH6101MEB08'    |'C0402_H28'| '(C0402-0201_H28)'                                                   | '10UF'     | '6.3V'        | '20%'    | 'DISCRETE' | 'CAP CHIP 10UF 6.3V(+-20%,X6S,0402)SAM'                        | 'CHIP0402'     | ''          | ''   | '20210506'
 '10UF'     | '6.3V'  | '20%'     | 'C0402'     | 'EMPTY'   | 'CH6101MEB08'(!)   = ''              | ''                 | ''       | 'CH6101MEB08'    |'C0402_H28'| '(C0402-0201_H28)'                                                   | 'NA'       | '6.3V'        | '20%'    | 'IO'       | 'CAP CHIP 10UF 6.3V(+-20%,X6S,0402)SAM'                        | 'CHIP0402'     | ''          | ''   | '20210506'
 '2.2UF'    | '6.3V'  | '20%'     | 'C0201'     | 'X5R'     | 'CH5221M9E00'(!)   = ''              | ''                 | ''       | 'CH5221M9E00'    |'C0201_H16'| '(SMC0201AW)'                                                        | '2.2UF'    | '6.3V'        | '20%'    | 'DISCRETE' | 'CAP CHIP 2.2UF 6.3V(+-20%,X5R,0201)'                          | 'CHIP0201'     | ''          | ''   | '20210507'
 '2.2UF'    | '6.3V'  | '20%'     | 'C0201'     | 'EMPTY'   | 'CH5221M9E00'(!)   = ''              | ''                 | ''       | 'CH5221M9E00'    |'C0201_H16'| '(SMC0201AW)'                                                        | 'NA'       | '6.3V'        | '20%'    | 'IO'       | 'CAP CHIP 2.2UF 6.3V(+-20%,X5R,0201)'                          | 'CHIP0201'     | ''          | ''   | '20210507'
 '10UF'     | '25V'   | '20%'     | 'C0805'     | 'X7S'     | 'CH6104M6A00'(!)   = ''              | ''                 | ''       | 'CH6104M6A00'    |'C0805_H57'| '(SMC0805AW)'                                                        | '10UF'     | '25V'         | '20%'    | 'DISCRETE' | 'CAP CHIP 10UF 25V(+-20%,X7S,0805)'                            | 'CHIP0805'     | ''          | ''   | '20210525'
 '10UF'     | '25V'   | '20%'     | 'C0805'     | 'EMPTY'   | 'CH6104M6A00'(!)   = ''              | ''                 | ''       | 'CH6104M6A00'    |'C0805_H57'| '(SMC0805AW)'                                                        | 'NA'       | '25V'         | '20%'    | 'IO'       | 'CAP CHIP 10UF 25V(+-20%,X7S,0805)'                            | 'CHIP0805'     | ''          | ''   | '20210525'
 '4.7UF'    | '25V'   | '10%'     | 'C0805'     | 'X7S'     | 'CH5474K6A01'(!)   = ''              | ''                 | ''       | 'CH5474K6A01'    |'C0805_H43'| '(SMC0805AW)'                                                        | '4.7UF'    | '25V'         | '10%'    | 'DISCRETE' | 'CAP CHIP 4.7U 25V(10%,X7S,0805)MUR'                           | 'CHIP0805'     | ''          | ''   | '20210525'
 '4.7UF'    | '25V'   | '10%'     | 'C0805'     | 'EMPTY'   | 'CH5474K6A01'(!)   = ''              | ''                 | ''       | 'CH5474K6A01'    |'C0805_H43'| '(SMC0805AW)'                                                        | 'NA'       | '25V'         | '10%'    | 'IO'       | 'CAP CHIP 4.7U 25V(10%,X7S,0805)MUR'                           | 'CHIP0805'     | ''          | ''   | '20210525'
 '0.027UF'  | '16V'   | '10%'     | 'C0402'     | 'X7R'     | 'CH3273K1B00'(!)   = ''              | ''                 | ''       | 'CH3273K1B00'    |'C0402'| '(C0402-0201)'                                                       | '0.027UF'  | '16V'         | '10%'    | 'DISCRETE' | 'CAP CHIP 0.027UF 16V(+-10%, X7R,0402)'                        | 'CHIP0402'     | ''          | ''   | '20210526'
 '0.027UF'  | '16V'   | '10%'     | 'C0402'     | 'EMPTY'   | 'CH3273K1B00'(!)   = ''              | ''                 | ''       | 'CH3273K1B00'    |'C0402'| '(C0402-0201)'                                                       | 'NA'       | '16V'         | '10%'    | 'IO'       | 'CAP CHIP 0.027UF 16V(+-10%, X7R,0402)'                        | 'CHIP0402'     | ''          | ''   | '20210526'
 '4700PF'   | '25V'   | '10%'     | 'C0201'     | 'X7R'     | 'CH2474K1E00'(!)   = ''              | ''                 | ''       | 'CH2474K1E00'    |'C0201'| '(SMC0201AW)'                                                        | '4700PF'   | '25V'         | '10%'    | 'DISCRETE' | 'CAP CHIP 4700P 25V(+-10%,X7R,0201)'                           | 'CHIP0201'     | ''          | ''   | '20210526'
 '4700PF'   | '25V'   | '10%'     | 'C0201'     | 'EMPTY'   | 'CH2474K1E00'(!)   = ''              | ''                 | ''       | 'CH2474K1E00'    |'C0201'| '(SMC0201AW)'                                                        | 'NA'       | '25V'         | '10%'    | 'IO'       | 'CAP CHIP 4700P 25V(+-10%,X7R,0201)'                           | 'CHIP0201'     | ''          | ''   | '20210526'
 '1UF'      | '10V'   | '20%'     | 'C0201'     | 'X6S'     | 'CH5102MEE02'(!)   = ''              | ''                 | ''       | 'CH5102MEE02'    |'C0201_H16'| '(SMC0201AW)'                                                        | '1UF'      | '10V'         | '20%'    | 'DISCRETE' | 'CAP CHIP 1UF 10V(20%,X6S,0201)'                               | 'CHIP0201'     | ''          | ''   | '20210531'
 '1UF'      | '10V'   | '20%'     | 'C0201'     | 'EMPTY'   | 'CH5102MEE02'(!)   = ''              | ''                 | ''       | 'CH5102MEE02'    |'C0201_H16'| '(SMC0201AW)'                                                        | 'NA'       | '10V'         | '20%'    | 'IO'       | 'CAP CHIP 1UF 10V(20%,X6S,0201)'                               | 'CHIP0201'     | ''          | ''   | '20210531'
 '4.7UF'    | '50V'   | '10%'     | 'C1206'     | 'X7R'     | 'CH5476K1207'(!)   = 'End of Design' | 'Comp-Approve'     | ''       | 'CH5476K1207'    |'C1206XG_H71'| '(SMC1206AW)'                                                        | '4.7UF'    | '50V'         | '10%'    | 'DISCRETE' | 'CAP CHIP 4.7U 50V(+-10%, X7R,1206,H1.6)'                      | 'CHIP1206'     | ''          | ''   | '20210609'
 '4.7UF'    | '50V'   | '10%'     | 'C1206'     | 'EMPTY'   | 'CH5476K1207'(!)   = 'End of Design' | 'Comp-Approve'     | ''       | 'CH5476K1207'    |'C1206XG_H71'| '(SMC1206AW)'                                                        | 'NA'       | '50V'         | '10%'    | 'IO'       | 'CAP CHIP 4.7U 50V(+-10%, X7R,1206,H1.6)'                      | 'CHIP1206'     | ''          | ''   | '20210609'
 '100UF'    | '6.3V'  | '20%'     | 'C1206'     | 'X6S'     | 'CH7101ME200'(!)   = 'End of Design' | 'Comp-Release Qty' | ''       | 'CH7101ME200'    |'C1206XE'| '(SMC1206AW)'                                                        | '100UF'    | '6.3V'        | '20%'    | 'DISCRETE' | 'CAP CHIP 100UF 6.3V(+-20%,X6S,1206)'                          | 'CHIP1206'     | ''          | ''   | '20210609'
 '100UF'    | '6.3V'  | '20%'     | 'C1206'     | 'EMPTY'   | 'CH7101ME200'(!)   = 'End of Design' | 'Comp-Release Qty' | ''       | 'CH7101ME200'    |'C1206XE'| '(SMC1206AW)'                                                        | 'NA'       | '6.3V'        | '20%'    | 'IO'       | 'CAP CHIP 100UF 6.3V(+-20%,X6S,1206)'                          | 'CHIP1206'     | ''          | ''   | '20210609'
 '200PF'    | '50V'   | '5%'      | 'C0402'     | 'NPO'     | 'CH1206J0B00'(!)   = 'End of Design' | 'Comp-Approve'     | ''       | 'CH1206J0B00'    |'C0402'| '(C0402-0201)'                                                       | '200PF'    | '50V'         | '5%'     | 'DISCRETE' | 'CAP CHIP 200P 50V(+-5%,NPO,0402)'                             | 'CHIP0402'     | ''          | ''   | '20210616'
 '200PF'    | '50V'   | '5%'      | 'C0402'     | 'EMPTY'   | 'CH1206J0B00'(!)   = 'End of Design' | 'Comp-Approve'     | ''       | 'CH1206J0B00'    |'C0402'| '(C0402-0201)'                                                       | 'NA'       | '50V'         | '5%'     | 'IO'       | 'CAP CHIP 200P 50V(+-5%,NPO,0402)'                             | 'CHIP0402'     | ''          | ''   | '20210616'
 '0.01UF'   | '50V'   | '10%'     | 'C0402'     | 'X7R'     | 'CH3106K1B10'(!)   = ''              | ''                 | ''       | 'CH3106K1B10'    |'C0402'| '(C0402-0201)'                                                       | '0.01UF'   | '50V'         | '10%'    | 'DISCRETE' | 'CAP CHIP 0.01U 50V(+-10%,X7R,0402)MUR'                        | 'CHIP0402'     | ''          | ''   | '20210727'
 '0.01UF'   | '50V'   | '10%'     | 'C0402'     | 'EMPTY'   | 'CH3106K1B10'(!)   = ''              | ''                 | ''       | 'CH3106K1B10'    |'C0402'| '(C0402-0201)'                                                       | 'NA'       | '50V'         | '10%'    | 'IO'       | 'CAP CHIP 0.01U 50V(+-10%,X7R,0402)MUR'                        | 'CHIP0402'     | ''          | ''   | '20210727'
 '0.3PF'    | '50V'   | '0.1PF'   | 'C0603'     | 'NPO'     | 'CH+306B0900'(!)   = ''              | ''                 | ''       | 'CH+306B0900'    |'C0603'| '(SMC0603AW)'                                                        | '0.3PF'    | '50V'         | '0.1PF'  | 'DISCRETE' | 'CAP CHIP 0.3PF 50V(+-0.1P,NPO,0603)HQ'                        | 'CHIP0603'     | ''          | ''   | '20210809'
 '0.3PF'    | '50V'   | '0.1PF'   | 'C0603'     | 'EMPTY'   | 'CH+306B0900'(!)   = ''              | ''                 | ''       | 'CH+306B0900'    |'C0603'| '(SMC0603AW)'                                                        | 'NA'       | '50V'         | '0.1PF'  | 'IO'       | 'CAP CHIP 0.3PF 50V(+-0.1P,NPO,0603)HQ'                        | 'CHIP0603'     | ''          | ''   | '20210809'
 '0.1UF'    | '50V'   | '10%'     | 'C0603'     | 'X7R'     | 'CH4106K1912'(!)   = 'End of Design' | 'Comp-Approve'     | ''       | 'CH4106K1912'    |'C0603'| '(SMC0603AW)'                                                        | '0.1UF'    | '50V'         | '10%'    | 'DISCRETE' | 'CAP CHIP 0.1U 50V(+-10%,X7R,0603)SAM'                         | 'CHIP0603'     | ''          | ''   | '20210812'
 '0.1UF'    | '50V'   | '10%'     | 'C0603'     | 'EMPTY'   | 'CH4106K1912'(!)   = 'End of Design' | 'Comp-Approve'     | ''       | 'CH4106K1912'    |'C0603'| '(SMC0603AW)'                                                        | 'NA'       | '50V'         | '10%'    | 'IO'       | 'CAP CHIP 0.1U 50V(+-10%,X7R,0603)SAM'                         | 'CHIP0603'     | ''          | ''   | '20210812'
 '47PF'     | '50V'   | '1%'      | 'C0402'     | 'NPO'     | 'CH0476F0B00'(!)   = ''              | ''                 | ''       | 'CH0476F0B00'    |'C0402'| '(C0402-0201)'                                                       | '47PF'     | '50V'         | '1%'     | 'DISCRETE' | 'CAP CHIP 47P 50V(+-1%,NPO,0402)'                              | 'CHIP0402'     | ''          | ''   | '20210817'
 '47PF'     | '50V'   | '1%'      | 'C0402'     | 'EMPTY'   | 'CH0476F0B00'(!)   = ''              | ''                 | ''       | 'CH0476F0B00'    |'C0402'| '(C0402-0201)'                                                       | 'NA'       | '50V'         | '1%'     | 'IO'       | 'CAP CHIP 47P 50V(+-1%,NPO,0402)'                              | 'CHIP0402'     | ''          | ''   | '20210817'
 '1000PF'   | '100V'  | '10%'     | 'C0402'     | 'X7R'     | 'CH2108K1B00'(!)   = ''              | ''                 | ''       | 'CH2108K1B00'    |'C0402'| '(C0402-0201)'                                                       | '1000PF'   | '100V'        | '10%'    | 'DISCRETE' | 'CAP CHIP 1000P 100V(+-10%,X7R,0402)'                          | 'CHIP0402'     | ''          | ''   | '20210817'
 '1000PF'   | '100V'  | '10%'     | 'C0402'     | 'EMPTY'   | 'CH2108K1B00'(!)   = ''              | ''                 | ''       | 'CH2108K1B00'    |'C0402'| '(C0402-0201)'                                                       | 'NA'       | '100V'        | '10%'    | 'IO'       | 'CAP CHIP 1000P 100V(+-10%,X7R,0402)'                          | 'CHIP0402'     | ''          | ''   | '20210817'
 '0.1UF'    | '1KV'   | '10%'     | 'C2220'     | 'X7R'     | 'CH410FK1F00'(!)   = ''              | ''                 | ''       | 'CH410FK1F00'    |'C2220XB'| '(SMC2220AW)'                                                        | '0.1UF'    | '1KV'         | '10%'    | 'DISCRETE' | 'CAP CHIP 0.1U 1KV(+-10%,X7R,2220)H2.5'                        | 'CHIP2220'     | ''          | ''   | '20210823'
 '0.1UF'    | '1KV'   | '10%'     | 'C2220'     | 'EMPTY'   | 'CH410FK1F00'(!)   = ''              | ''                 | ''       | 'CH410FK1F00'    |'C2220XB'| '(SMC2220AW)'                                                        | 'NA'       | '1KV'         | '10%'    | 'IO'       | 'CAP CHIP 0.1U 1KV(+-10%,X7R,2220)H2.5'                        | 'CHIP2220'     | ''          | ''   | '20210823'
 '0.033UF'  | '100V'  | '10%'     | 'C0805'     | 'X7R'     | 'CH3338K1A00'(!)   = ''              | ''                 | ''       | 'CH3338K1A00'    |'C0805_H57'| '(SMC0805AW)'                                                        | '0.033UF'  | '100V'        | '10%'    | 'DISCRETE' | 'CAP CHIP 0.033U 100V(+-10%,X7R,0805)'                         | 'CHIP0805'     | ''          | ''   | '20210827'
 '0.033UF'  | '100V'  | '10%'     | 'C0805'     | 'EMPTY'   | 'CH3338K1A00'(!)   = ''              | ''                 | ''       | 'CH3338K1A00'    |'C0805_H57'| '(SMC0805AW)'                                                        | 'NA'       | '100V'        | '10%'    | 'IO'       | 'CAP CHIP 0.033U 100V(+-10%,X7R,0805)'                         | 'CHIP0805'     | ''          | ''   | '20210827'
 '0.022UF'  | '50V'   | '10%'     | 'C0402'     | 'X7R'     | 'CH3226K1B00'(!)   = ''              | ''                 | ''       | 'CH3226K1B00'    |'C0402'| '(C0402-0201)'                                                       | '0.022UF'  | '50V'         | '10%'    | 'DISCRETE' | 'CAP CHIP 0.022U 50V(+-10%,X7R,0402)'                          | 'CHIP0402'     | ''          | ''   | '20210909'
 '0.022UF'  | '50V'   | '10%'     | 'C0402'     | 'EMPTY'   | 'CH3226K1B00'(!)   = ''              | ''                 | ''       | 'CH3226K1B00'    |'C0402'| '(C0402-0201)'                                                       | 'NA'       | '50V'         | '10%'    | 'IO'       | 'CAP CHIP 0.022U 50V(+-10%,X7R,0402)'                          | 'CHIP0402'     | ''          | ''   | '20210909'
 '0.33UF'   | '10V'   | '10%'     | 'C0402'     | 'X5R'     | 'CH4332K9B00'(!)   = ''              | ''                 | ''       | 'CH4332K9B00'    |'C0402'| '(C0402-0201)'                                                       | '0.33UF'   | '10V'         | '10%'    | 'DISCRETE' | 'CAP CHIP 0.33UF 10V(+-10%,X5R,0402)'                          | 'CHIP0402'     | ''          | ''   | '20211018'
 '0.33UF'   | '10V'   | '10%'     | 'C0402'     | 'EMPTY'   | 'CH4332K9B00'(!)   = ''              | ''                 | ''       | 'CH4332K9B00'    |'C0402'| '(C0402-0201)'                                                       | 'NA'       | '10V'         | '10%'    | 'IO'       | 'CAP CHIP 0.33UF 10V(+-10%,X5R,0402)'                          | 'CHIP0402'     | ''          | ''   | '20211018'
 '10UF'     | '10V'   | '10%'     | 'C0805'     | 'X7R'     | 'CH6102K1A05'(!)   = ''              | ''                 | ''       | 'CH6102K1A05'    |'C0805_H57'| '(SMC0805AW)'                                                        | '10UF'     | '10V'         | '10%'    | 'DISCRETE' | 'CAP CHIP 10U 10V(+-10%,X7R,0805)YGO'                          | 'CHIP0805'     | ''          | ''   | '20211115'
 '10UF'     | '10V'   | '10%'     | 'C0805'     | 'EMPTY'   | 'CH6102K1A05'(!)   = ''              | ''                 | ''       | 'CH6102K1A05'    |'C0805_H57'| '(SMC0805AW)'                                                        | 'NA'       | '10V'         | '10%'    | 'IO'       | 'CAP CHIP 10U 10V(+-10%,X7R,0805)YGO'                          | 'CHIP0805'     | ''          | ''   | '20211115'
 '100PF'    | '50V'   | '5%'      | 'C0402'     | 'NPO'     | 'CH1106J0B17'(!)   = ''              | ''                 | ''       | 'CH1106J0B17'    |'C0402'| '(C0402-0201)'                                                       | '100PF'    | '50V'         | '5%'     | 'DISCRETE' | 'CAP CHIP 100P 50V(+-5%,NPO,0402)SAM'                          | 'CHIP0402'     | ''          | ''   | '20211126'
 '100PF'    | '50V'   | '5%'      | 'C0402'     | 'EMPTY'   | 'CH1106J0B17'(!)   = ''              | ''                 | ''       | 'CH1106J0B17'    |'C0402'| '(C0402-0201)'                                                       | 'NA'       | '50V'         | '5%'     | 'IO'       | 'CAP CHIP 100P 50V(+-5%,NPO,0402)SAM'                          | 'CHIP0402'     | ''          | ''   | '20211126'
 '12PF'     | '50V'   | '5%'      | 'C0402'     | 'NP0'     | 'CH0126J0B16'(!)   = ''              | ''                 | ''       | 'CH0126J0B16'    |'C0402'| '(C0402-0201)'                                                       | '12PF'     | '50V'         | '5%'     | 'DISCRETE' | 'CAP CHIP 12P 50V(+-5%,NP0,0402)SAM'                           | 'CHIP0402'     | ''          | ''   | '20211129'
 '12PF'     | '50V'   | '5%'      | 'C0402'     | 'EMPTY'   | 'CH0126J0B16'(!)   = ''              | ''                 | ''       | 'CH0126J0B16'    |'C0402'| '(C0402-0201)'                                                       | 'NA'       | '50V'         | '5%'     | 'IO'       | 'CAP CHIP 12P 50V(+-5%,NP0,0402)SAM'                           | 'CHIP0402'     | ''          | ''   | '20211129'
 '1NF'      | '50V'   | '10%'     | 'C0402'     | 'X7R'     | 'CH2106K1B28'(!)   = ''              | ''                 | ''       | 'CH2106K1B28'    |'C0402'| '(C0402-0201)'                                                       | '1NF'      | '50V'         | '10%'    | 'DISCRETE' | 'CAP CHIP 1N 50V(+-10%,X7R,0402)SAM'                           | 'CHIP0402'     | ''          | ''   | '20211227'
 '1NF'      | '50V'   | '10%'     | 'C0402'     | 'EMPTY'   | 'CH2106K1B28'(!)   = ''              | ''                 | ''       | 'CH2106K1B28'    |'C0402'| '(C0402-0201)'                                                       | 'NA'       | '50V'         | '10%'    | 'IO'       | 'CAP CHIP 1N 50V(+-10%,X7R,0402)SAM'                           | 'CHIP0402'     | ''          | ''   | '20211227'
 '1.5UF'    | '25V'   | '10%'     | 'C0805'     | 'X7R'     | 'CH5154K1A05'(!)   = 'End of Design' | 'Comp-Approve'     | ''       | 'CH5154K1A05'    |'C0805_H57'| '(SMC0805AW)'                                                        | '1.5UF'    | '25V'         | '10%'    | 'DISCRETE' | 'CAP CHIP 1.5U 25V(10%,X7R,0805)H1.25'                         | 'CHIP0805'     | ''          | ''   | '20211227'
 '1.5UF'    | '25V'   | '10%'     | 'C0805'     | 'EMPTY'   | 'CH5154K1A05'(!)   = 'End of Design' | 'Comp-Approve'     | ''       | 'CH5154K1A05'    |'C0805_H57'| '(SMC0805AW)'                                                        | 'NA'       | '25V'         | '10%'    | 'IO'       | 'CAP CHIP 1.5U 25V(10%,X7R,0805)H1.25'                         | 'CHIP0805'     | ''          | ''   | '20211227'
 '0.5PF'    | '250V'  | '0.1PF'   | 'C0603'     | 'C0G'     | 'CH+50CB0900'(!)   = ''              | ''                 | ''       | 'CH+50CB0900'    |'C0603'| '(SMC0603AW)'                                                        | '0.5PF'    | '250V'        | '0.1PF'  | 'DISCRETE' | 'CAP CHIP 0.5P 250V(+-0.1P,C0G,0603)HQ'                        | 'CHIP0603'     | ''          | ''   | '20220106'
 '0.5PF'    | '250V'  | '0.1PF'   | 'C0603'     | 'EMPTY'   | 'CH+50CB0900'(!)   = ''              | ''                 | ''       | 'CH+50CB0900'    |'C0603'| '(SMC0603AW)'                                                        | 'NA'       | '250V'        | '0.1PF'  | 'IO'       | 'CAP CHIP 0.5P 250V(+-0.1P,C0G,0603)HQ'                        | 'CHIP0603'     | ''          | ''   | '20220106'
 '1.2PF'    | '250V'  | '0.1PF'   | 'C0603'     | 'C0G'     | 'CH-12CB0900'(!)   = ''              | ''                 | ''       | 'CH-12CB0900'    |'C0603'| '(SMC0603AW)'                                                        | '1.2PF'    | '250V'        | '0.1PF'  | 'DISCRETE' | 'CAP CHIP 1.2P 250V(+-0.1P,C0G,0603)HQ'                        | 'CHIP0603'     | ''          | ''   | '20220106'
 '1.2PF'    | '250V'  | '0.1PF'   | 'C0603'     | 'EMPTY'   | 'CH-12CB0900'(!)   = ''              | ''                 | ''       | 'CH-12CB0900'    |'C0603'| '(SMC0603AW)'                                                        | 'NA'       | '250V'        | '0.1PF'  | 'IO'       | 'CAP CHIP 1.2P 250V(+-0.1P,C0G,0603)HQ'                        | 'CHIP0603'     | ''          | ''   | '20220106'
 '8.2PF'    | '250V'  | '0.25PF'  | 'C0603'     | 'C0G'     | 'CH-82CC0900'(!)   = ''              | ''                 | ''       | 'CH-82CC0900'    |'C0603'| '(SMC0603AW)'                                                        | '8.2PF'    | '250V'        | '0.25PF' | 'DISCRETE' | 'CAP CHIP 8.2P 250V(+-0.25P,C0G,0603)HQ'                       | 'CHIP0603'     | ''          | ''   | '20220106'
 '8.2PF'    | '250V'  | '0.25PF'  | 'C0603'     | 'EMPTY'   | 'CH-82CC0900'(!)   = ''              | ''                 | ''       | 'CH-82CC0900'    |'C0603'| '(SMC0603AW)'                                                        | 'NA'       | '250V'        | '0.25PF' | 'IO'       | 'CAP CHIP 8.2P 250V(+-0.25P,C0G,0603)HQ'                       | 'CHIP0603'     | ''          | ''   | '20220106'
 '8.2PF'    | '50V'   | '0.25PF'  | 'C0402'     | 'C0G'     | 'CH-826C0B01'(!)   = 'End of Design' | 'Comp-Approve'     | ''       | 'CH-826C0B01'    |'C0402'| '(C0402-0201)'                                                       | '8.2PF'    | '50V'         | '0.25PF' | 'DISCRETE' | 'CAP CHIP 8.2PF,50V(+-0.25PF,C0G,0402)HIQ'                     | 'CHIP0402'     | ''          | ''   | '20220106'
 '8.2PF'    | '50V'   | '0.25PF'  | 'C0402'     | 'EMPTY'   | 'CH-826C0B01'(!)   = 'End of Design' | 'Comp-Approve'     | ''       | 'CH-826C0B01'    |'C0402'| '(C0402-0201)'                                                       | 'NA'       | '50V'         | '0.25PF' | 'IO'       | 'CAP CHIP 8.2PF,50V(+-0.25PF,C0G,0402)HIQ'                     | 'CHIP0402'     | ''          | ''   | '20220106'
 '330PF'    | '50V'   | '5%'      | 'C0402'     | 'X7R'     | 'CH13306JB14'(!)   = ''              | ''                 | ''       | 'CH13306JB14'    |'C0402'| '(C0402-0201)'                                                       | '330PF'    | '50V'         | '5%'     | 'DISCRETE' | 'CAP CHIP 330P 50V (+-5% X7R 0402)'                            | 'CHIP0402'     | ''          | ''   | '20220110'
 '330PF'    | '50V'   | '5%'      | 'C0402'     | 'EMPTY'   | 'CH13306JB14'(!)   = ''              | ''                 | ''       | 'CH13306JB14'    |'C0402'| '(C0402-0201)'                                                       | 'NA'       | '50V'         | '5%'     | 'IO'       | 'CAP CHIP 330P 50V (+-5% X7R 0402)'                            | 'CHIP0402'     | ''          | ''   | '20220110'
 '1PF'      | '250V'  | '0.1PF'   | 'C0603'     | 'C0G'     | 'CH-10CB0900'(!)   = ''              | ''                 | ''       | 'CH-10CB0900'    |'C0603'| '(SMC0603AW)'                                                        | '1PF'      | '250V'        | '0.1PF'  | 'DISCRETE' | 'CAP CHIP 1P 250V(+-0.1P,C0G,0603)HQ'                          | 'CHIP0603'     | ''          | ''   | '20220113'
 '1PF'      | '250V'  | '0.1PF'   | 'C0603'     | 'EMPTY'   | 'CH-10CB0900'(!)   = ''              | ''                 | ''       | 'CH-10CB0900'    |'C0603'| '(SMC0603AW)'                                                        | 'NA'       | '250V'        | '0.1PF'  | 'IO'       | 'CAP CHIP 1P 250V(+-0.1P,C0G,0603)HQ'                          | 'CHIP0603'     | ''          | ''   | '20220113'
 '6.8PF'    | '250V'  | '0.1PF'   | 'C0603'     | 'C0G'     | 'CH-68CB0900'(!)   = ''              | ''                 | ''       | 'CH-68CB0900'    |'C0603'| '(SMC0603AW)'                                                        | '6.8PF'    | '250V'        | '0.1PF'  | 'DISCRETE' | 'CAP CHIP 6.8P 250V(+-0.1P,C0G,0603)HQ'                        | 'CHIP0603'     | ''          | ''   | '20220113'
 '6.8PF'    | '250V'  | '0.1PF'   | 'C0603'     | 'EMPTY'   | 'CH-68CB0900'(!)   = ''              | ''                 | ''       | 'CH-68CB0900'    |'C0603'| '(SMC0603AW)'                                                        | 'NA'       | '250V'        | '0.1PF'  | 'IO'       | 'CAP CHIP 6.8P 250V(+-0.1P,C0G,0603)HQ'                        | 'CHIP0603'     | ''          | ''   | '20220113'
 '22UF'     | '4V'    | '20%'     | 'C0402'     | 'X6S'     | 'CH622KMEB04'(!)   = ''              | ''                 | ''       | 'CH622KMEB04'    |'C0402_H28'| '(C0402-0201_H28)'                                                   | '22UF'     | '4V'          | '20%'    | 'DISCRETE' | 'CAP CHIP 22UF 4V(+-20%,X6S,0402)SAM'                          | 'CHIP0402'     | ''          | ''   | '20220120'
 '22UF'     | '4V'    | '20%'     | 'C0402'     | 'EMPTY'   | 'CH622KMEB04'(!)   = ''              | ''                 | ''       | 'CH622KMEB04'    |'C0402_H28'| '(C0402-0201_H28)'                                                   | 'NA'       | '4V'          | '20%'    | 'IO'       | 'CAP CHIP 22UF 4V(+-20%,X6S,0402)SAM'                          | 'CHIP0402'     | ''          | ''   | '20220120'
 '47UF'     | '2.5V'  | '20%'     | 'C0603'     | 'X6S'     | 'CH647LME902'(!)   = ''              | ''                 | ''       | 'CH647LME902'    |'C0603_H40'| '(SMC0603AW)'                                                        | '47UF'     | '2.5V'        | '20%'    | 'DISCRETE' | 'CAP CHIP 47U 2.5V(+-20%,X6S,0603)SAM'                         | 'CHIP0603'     | ''          | ''   | '20220120'
 '47UF'     | '2.5V'  | '20%'     | 'C0603'     | 'EMPTY'   | 'CH647LME902'(!)   = ''              | ''                 | ''       | 'CH647LME902'    |'C0603_H40'| '(SMC0603AW)'                                                        | 'NA'       | '2.5V'        | '20%'    | 'IO'       | 'CAP CHIP 47U 2.5V(+-20%,X6S,0603)SAM'                         | 'CHIP0603'     | ''          | ''   | '20220120'
 '10UF'     | '16V'   | '10%'     | 'C0805'     | 'X6S'     | 'CH6103KEA03'(!)   = ''              | ''                 | ''       | 'CH6103KEA03'    |'C0805_H57'| '(SMC0805AW)'                                                        | '10UF'     | '16V'         | '10%'    | 'DISCRETE' | 'CAP CHIP 10UF 16V(+-10%,X6S,0805)SAM'                         | 'CHIP0805'     | ''          | ''   | '20220120'
 '10UF'     | '16V'   | '10%'     | 'C0805'     | 'EMPTY'   | 'CH6103KEA03'(!)   = ''              | ''                 | ''       | 'CH6103KEA03'    |'C0805_H57'| '(SMC0805AW)'                                                        | 'NA'       | '16V'         | '10%'    | 'IO'       | 'CAP CHIP 10UF 16V(+-10%,X6S,0805)SAM'                         | 'CHIP0805'     | ''          | ''   | '20220120'
 '0.3PF'    | '250V'  | '0.1PF'   | 'C0603'     | 'C0G'     | 'CH+30CB0900'(!)   = ''              | ''                 | ''       | 'CH+30CB0900'    |'C0603'| '(SMC0603AW)'                                                        | '0.3PF'    | '250V'        | '0.1PF'  | 'DISCRETE' | 'CAP CHIP 0.3P 250V(+-0.1P,C0G,0603)HQ'                        | 'CHIP0603'     | ''          | ''   | '20220120'
 '0.3PF'    | '250V'  | '0.1PF'   | 'C0603'     | 'EMPTY'   | 'CH+30CB0900'(!)   = ''              | ''                 | ''       | 'CH+30CB0900'    |'C0603'| '(SMC0603AW)'                                                        | 'NA'       | '250V'        | '0.1PF'  | 'IO'       | 'CAP CHIP 0.3P 250V(+-0.1P,C0G,0603)HQ'                        | 'CHIP0603'     | ''          | ''   | '20220120'
 '22UF'     | '10V'   | '20%'     | 'C0805'     | 'X6S'     | 'CH6222MEA06'(!)   = 'End of Design' | 'Comp-Approve'     | ''       | 'CH6222MEA06'    |'C0805_H57'| '(SMC0805AW)'                                                        | '22UF'     | '10V'         | '20%'    | 'DISCRETE' | 'CAP CHIP 22U 10V(20%,X6S,0805)SAM'                            | 'CHIP0805'     | ''          | ''   | '20220120'
 '22UF'     | '10V'   | '20%'     | 'C0805'     | 'EMPTY'   | 'CH6222MEA06'(!)   = 'End of Design' | 'Comp-Approve'     | ''       | 'CH6222MEA06'    |'C0805_H57'| '(SMC0805AW)'                                                        | 'NA'       | '10V'         | '20%'    | 'IO'       | 'CAP CHIP 22U 10V(20%,X6S,0805)SAM'                            | 'CHIP0805'     | ''          | ''   | '20220120'
 '2.2UF'    | '25V'   | '20%'     | 'C0402'     | 'X6S'     | 'CH5224MEB04'(!)   = ''              | ''                 | ''       | 'CH5224MEB04'    |'C0402_H28'| '(C0402-0201_H28)'                                                   | '2.2UF'    | '25V'         | '20%'    | 'DISCRETE' | 'CAP CHIP 2.2UF 25V(+-20%,X6S,0402)'                           | 'CHIP0402'     | ''          | ''   | '20220125'
 '2.2UF'    | '25V'   | '20%'     | 'C0402'     | 'EMPTY'   | 'CH5224MEB04'(!)   = ''              | ''                 | ''       | 'CH5224MEB04'    |'C0402_H28'| '(C0402-0201_H28)'                                                   | 'NA'       | '25V'         | '20%'    | 'IO'       | 'CAP CHIP 2.2UF 25V(+-20%,X6S,0402)'                           | 'CHIP0402'     | ''          | ''   | '20220125'
 '1000PF'   | '50V'   | '5%'      | 'C0402'     | 'NPO'     | 'CH2106J0B06'(!)   = ''              | ''                 | ''       | 'CH2106J0B06'    |'C0402'| '(C0402-0201)'                                                       | '1000PF'   | '50V'         | '5%'     | 'DISCRETE' | 'CAP CHIP 1000P,50V(+-5%,NPO,0402)'                            | 'CHIP0402'     | ''          | ''   | '20220221'
 '1000PF'   | '50V'   | '5%'      | 'C0402'     | 'EMPTY'   | 'CH2106J0B06'(!)   = ''              | ''                 | ''       | 'CH2106J0B06'    |'C0402'| '(C0402-0201)'                                                       | 'NA'       | '50V'         | '5%'     | 'IO'       | 'CAP CHIP 1000P,50V(+-5%,NPO,0402)'                            | 'CHIP0402'     | ''          | ''   | '20220221'
 '0.15UF'   | '100V'  | '10%'     | 'C0805'     | 'X7R'     | 'CH4158K1A00'(!)   = ''              | ''                 | ''       | 'CH4158K1A00'    |'C0805_H57'| '(SMC0805AW)'                                                        | '0.15UF'   | '100V'        | '10%'    | 'DISCRETE' | 'CAP CHIP 0.15U 100V(+-10%,X7R,0805)'                          | 'CHIP0805'     | ''          | ''   | '20220301'
 '0.15UF'   | '100V'  | '10%'     | 'C0805'     | 'EMPTY'   | 'CH4158K1A00'(!)   = ''              | ''                 | ''       | 'CH4158K1A00'    |'C0805_H57'| '(SMC0805AW)'                                                        | 'NA'       | '100V'        | '10%'    | 'IO'       | 'CAP CHIP 0.15U 100V(+-10%,X7R,0805)'                          | 'CHIP0805'     | ''          | ''   | '20220301'
 '18PF'     | '50V'   | '2%'      | 'C0201'     | 'C0G'     | 'CH0186G0E00'(!)   = ''              | ''                 | ''       | 'CH0186G0E00'    |'C0201'| '(SMC0201AW)'                                                        | '18PF'     | '50V'         | '2%'     | 'DISCRETE' | 'CAP CHIP 18PF 50V(+-2%,C0G,0201)'                             | 'CHIP0201'     | ''          | ''   | '20220303'
 '18PF'     | '50V'   | '2%'      | 'C0201'     | 'EMPTY'   | 'CH0186G0E00'(!)   = ''              | ''                 | ''       | 'CH0186G0E00'    |'C0201'| '(SMC0201AW)'                                                        | 'NA'       | '50V'         | '2%'     | 'IO'       | 'CAP CHIP 18PF 50V(+-2%,C0G,0201)'                             | 'CHIP0201'     | ''          | ''   | '20220303'
 '22UF'     | '10V'   | '20%'     | 'C0402'     | 'X5R'     | 'CH6222M9B01'(!)   = ''              | ''                 | ''       | 'CH6222M9B01'    |'C0402_H32'| '(C0402-0201_H32)'                                                   | '22UF'     | '10V'         | '20%'    | 'DISCRETE' | 'CAP CHIP 22U 10V(+-20%,X5R,0402)'                             | 'CHIP0402'     | ''          | ''   | '20220307'
 '22UF'     | '10V'   | '20%'     | 'C0402'     | 'EMPTY'   | 'CH6222M9B01'(!)   = ''              | ''                 | ''       | 'CH6222M9B01'    |'C0402_H32'| '(C0402-0201_H32)'                                                   | 'NA'       | '10V'         | '20%'    | 'IO'       | 'CAP CHIP 22U 10V(+-20%,X5R,0402)'                             | 'CHIP0402'     | ''          | ''   | '20220307'
 '1.8PF'    | '50V'   | '0.1PF'   | 'C0402'     | 'NPO'     | 'CH-1826TB06'(!)   = ''              | ''                 | ''       | 'CH-1826TB06'    |'C0402'| '(C0402-0201)'                                                       | '1.8PF'    | '50V'         | '0.1PF'  | 'DISCRETE' | 'CAP CHIP 1.8P 50V(+-0.1P,NPO,0402)'                           | 'CHIP0402'     | ''          | ''   | '20220307'
 '1.8PF'    | '50V'   | '0.1PF'   | 'C0402'     | 'EMPTY'   | 'CH-1826TB06'(!)   = ''              | ''                 | ''       | 'CH-1826TB06'    |'C0402'| '(C0402-0201)'                                                       | 'NA'       | '50V'         | '0.1PF'  | 'IO'       | 'CAP CHIP 1.8P 50V(+-0.1P,NPO,0402)'                           | 'CHIP0402'     | ''          | ''   | '20220307'
 '100PF'    | '50V'   | '5%'      | 'C0201'     | 'NPO'     | 'CH1106J0E00'(!)   = ''              | ''                 | ''       | 'CH1106J0E00'    |'C0201'| '(SMC0201AW)'                                                        | '100PF'    | '50V'         | '5%'     | 'DISCRETE' | 'CAP CHIP 100P 50V(+-5%,NPO,0201)'                             | 'CHIP0201'     | ''          | ''   | '20220307'
 '100PF'    | '50V'   | '5%'      | 'C0201'     | 'EMPTY'   | 'CH1106J0E00'(!)   = ''              | ''                 | ''       | 'CH1106J0E00'    |'C0201'| '(SMC0201AW)'                                                        | 'NA'       | '50V'         | '5%'     | 'IO'       | 'CAP CHIP 100P 50V(+-5%,NPO,0201)'                             | 'CHIP0201'     | ''          | ''   | '20220307'
 '0.22UF'   | '50V'   | '10%'     | 'C0603'     | 'X7R'     | 'CH4226K1902'(!)   = ''              | ''                 | ''       | 'CH4226K1902'    |'C0603'| '(SMC0603AW)'                                                        | '0.22UF'   | '50V'         | '10%'    | 'DISCRETE' | 'CAP CHIP 0.22U 50V(+-10%,X7R,0603)'                           | 'CHIP0603'     | ''          | ''   | '20220321'
 '0.22UF'   | '50V'   | '10%'     | 'C0603'     | 'EMPTY'   | 'CH4226K1902'(!)   = ''              | ''                 | ''       | 'CH4226K1902'    |'C0603'| '(SMC0603AW)'                                                        | 'NA'       | '50V'         | '10%'    | 'IO'       | 'CAP CHIP 0.22U 50V(+-10%,X7R,0603)'                           | 'CHIP0603'     | ''          | ''   | '20220321'
 '330PF'    | '16V'   | '10%'     | 'C0201'     | 'X7R'     | 'CH1333K1E01'(!)   = ''              | ''                 | ''       | 'CH1333K1E01'    |'C0201'| '(SMC0201AW)'                                                        | '330PF'    | '16V'         | '10%'    | 'DISCRETE' | 'CAP CHIP 330PF 16V(+-10%,X7R,0201)'                           | 'CHIP0201'     | ''          | ''   | '20220321'
 '330PF'    | '16V'   | '10%'     | 'C0201'     | 'EMPTY'   | 'CH1333K1E01'(!)   = ''              | ''                 | ''       | 'CH1333K1E01'    |'C0201'| '(SMC0201AW)'                                                        | 'NA'       | '16V'         | '10%'    | 'IO'       | 'CAP CHIP 330PF 16V(+-10%,X7R,0201)'                           | 'CHIP0201'     | ''          | ''   | '20220321'
 '0.022UF'  | '100V'  | '10%'     | 'C0603'     | 'X7R'     | 'CH3228K1900'(!)   = ''              | ''                 | ''       | 'CH3228K1900'    |'C0603'| '(SMC0603AW)'                                                        | '0.022UF'  | '100V'        | '10%'    | 'DISCRETE' | 'CAP CHIP 0.022UF 100V(+-10%,X7R,0603)'                        | 'CHIP0603'     | ''          | ''   | '20220321'
 '0.022UF'  | '100V'  | '10%'     | 'C0603'     | 'EMPTY'   | 'CH3228K1900'(!)   = ''              | ''                 | ''       | 'CH3228K1900'    |'C0603'| '(SMC0603AW)'                                                        | 'NA'       | '100V'        | '10%'    | 'IO'       | 'CAP CHIP 0.022UF 100V(+-10%,X7R,0603)'                        | 'CHIP0603'     | ''          | ''   | '20220321'
 '680PF'    | '50V'   | '10%'     | 'C0402'     | 'X7R'     | 'CH1686K1B09'(!)   = ''              | ''                 | ''       | 'CH1686K1B09'    |'C0402'| '(C0402-0201)'                                                       | '680PF'    | '50V'         | '10%'    | 'DISCRETE' | 'CAP CHIP 680P 50V(+-10%,X7R,0402)MUR'                         | 'CHIP0402'     | ''          | ''   | '20220414'
 '680PF'    | '50V'   | '10%'     | 'C0402'     | 'EMPTY'   | 'CH1686K1B09'(!)   = ''              | ''                 | ''       | 'CH1686K1B09'    |'C0402'| '(C0402-0201)'                                                       | 'NA'       | '50V'         | '10%'    | 'IO'       | 'CAP CHIP 680P 50V(+-10%,X7R,0402)MUR'                         | 'CHIP0402'     | ''          | ''   | '20220414'
 '0.01UF'   | '100V'  | '10%'     | 'C0805'     | 'X7R'     | 'CH3108K1A03'(!)   = ''              | ''                 | ''       | 'CH3108K1A03'    |'C0805_H57'| '(SMC0805AW)'                                                        | '0.01UF'   | '100V'        | '10%'    | 'DISCRETE' | 'CAP CHIP 0.01U 100V(10%,X7R,0805)'                            | 'CHIP0805'     | ''          | ''   | '20220421'
 '0.01UF'   | '100V'  | '10%'     | 'C0805'     | 'EMPTY'   | 'CH3108K1A03'(!)   = ''              | ''                 | ''       | 'CH3108K1A03'    |'C0805_H57'| '(SMC0805AW)'                                                        | 'NA'       | '100V'        | '10%'    | 'IO'       | 'CAP CHIP 0.01U 100V(10%,X7R,0805)'                            | 'CHIP0805'     | ''          | ''   | '20220421'
 '4.7UF'    | '10V'   | '20%'     | 'C0402'     | 'X5R'     | 'CH5472M9B01'(!)   = 'End of Design' | 'Comp-Approve'     | ''       | 'CH5472M9B01'    |'C0402_H28'| '(C0402-0201_H28)'                                                   | '4.7UF'    | '10V'         | '20%'    | 'DISCRETE' | 'CAP CHIP 4.7U 10V(+-20%,X5R,0402)'                            | 'CHIP0402'     | ''          | ''   | '20220422'
 '4.7UF'    | '10V'   | '20%'     | 'C0402'     | 'EMPTY'   | 'CH5472M9B01'(!)   = 'End of Design' | 'Comp-Approve'     | ''       | 'CH5472M9B01'    |'C0402_H28'| '(C0402-0201_H28)'                                                   | 'NA'       | '10V'         | '20%'    | 'IO'       | 'CAP CHIP 4.7U 10V(+-20%,X5R,0402)'                            | 'CHIP0402'     | ''          | ''   | '20220422'
 '330PF'    | '50V'   | '5%'      | 'C0402'     | 'NPO'     | 'CH1336J0B10'(!)   = ''              | ''                 | ''       | 'CH1336J0B10'    |'C0402'| '(C0402-0201)'                                                       | '330PF'    | '50V'         | '5%'     | 'DISCRETE' | 'CAP CHIP 330P 50V(+-5%,NPO,0402)MUR'                          | 'CHIP0402'     | ''          | ''   | '20220422'
 '330PF'    | '50V'   | '5%'      | 'C0402'     | 'EMPTY'   | 'CH1336J0B10'(!)   = ''              | ''                 | ''       | 'CH1336J0B10'    |'C0402'| '(C0402-0201)'                                                       | 'NA'       | '50V'         | '5%'     | 'IO'       | 'CAP CHIP 330P 50V(+-5%,NPO,0402)MUR'                          | 'CHIP0402'     | ''          | ''   | '20220422'
 '680PF'    | '50V'   | '5%'      | 'C0402'     | 'C0G'     | 'CH1686J0B03'(!)   = ''              | ''                 | ''       | 'CH1686J0B03'    |'C0402'| '(C0402-0201)'                                                       | '680PF'    | '50V'         | '5%'     | 'DISCRETE' | 'CAP CHIP 680P 50V(+-5%,C0G,0402)MUR'                          | 'CHIP0402'     | ''          | ''   | '20220422'
 '680PF'    | '50V'   | '5%'      | 'C0402'     | 'EMPTY'   | 'CH1686J0B03'(!)   = ''              | ''                 | ''       | 'CH1686J0B03'    |'C0402'| '(C0402-0201)'                                                       | 'NA'       | '50V'         | '5%'     | 'IO'       | 'CAP CHIP 680P 50V(+-5%,C0G,0402)MUR'                          | 'CHIP0402'     | ''          | ''   | '20220422'
 '0.5PF'    | '250V'  | '0.05PF'  | 'C0603'     | 'C0G'     | 'CH+50CT0900'(!)   = ''              | ''                 | ''       | 'CH+50CT0900'    |'C0603'| '(SMC0603AW)'                                                        | '0.5PF'    | '250V'        | '0.05PF' | 'DISCRETE' | 'CAP CHIP 0.5P 250V(0.05P,C0G,0603)HQ'                         | 'CHIP0603'     | ''          | ''   | '20220504'
 '0.5PF'    | '250V'  | '0.05PF'  | 'C0603'     | 'EMPTY'   | 'CH+50CT0900'(!)   = ''              | ''                 | ''       | 'CH+50CT0900'    |'C0603'| '(SMC0603AW)'                                                        | 'NA'       | '250V'        | '0.05PF' | 'IO'       | 'CAP CHIP 0.5P 250V(0.05P,C0G,0603)HQ'                         | 'CHIP0603'     | ''          | ''   | '20220504'
 '0.2PF'    | '250V'  | '0.05PF'  | 'C0603'     | 'C0G'     | 'CH+20CT0900'(!)   = ''              | ''                 | ''       | 'CH+20CT0900'    |'C0603'| '(SMC0603AW)'                                                        | '0.2PF'    | '250V'        | '0.05PF' | 'DISCRETE' | 'CAP CHIP 0.2P 250V(0.05P,C0G,0603)HQ'                         | 'CHIP0603'     | ''          | ''   | '20220504'
 '0.2PF'    | '250V'  | '0.05PF'  | 'C0603'     | 'EMPTY'   | 'CH+20CT0900'(!)   = ''              | ''                 | ''       | 'CH+20CT0900'    |'C0603'| '(SMC0603AW)'                                                        | 'NA'       | '250V'        | '0.05PF' | 'IO'       | 'CAP CHIP 0.2P 250V(0.05P,C0G,0603)HQ'                         | 'CHIP0603'     | ''          | ''   | '20220504'
 '1000PF'   | '50V'   | '5%'      | 'C0402'     | 'C0G'     | 'CH2106J0B01'(!)   = ''              | ''                 | ''       | 'CH2106J0B01'    |'C0402'| '(C0402-0201)'                                                       | '1000PF'   | '50V'         | '5%'     | 'DISCRETE' | 'CAP CHIP 1000PF 50V( 5%,C0G, 0402)MUR'                        | 'CHIP0402'     | ''          | ''   | '20220506'
 '1000PF'   | '50V'   | '5%'      | 'C0402'     | 'EMPTY'   | 'CH2106J0B01'(!)   = ''              | ''                 | ''       | 'CH2106J0B01'    |'C0402'| '(C0402-0201)'                                                       | 'NA'       | '50V'         | '5%'     | 'IO'       | 'CAP CHIP 1000PF 50V( 5%,C0G, 0402)MUR'                        | 'CHIP0402'     | ''          | ''   | '20220506'
 '0.15UF'   | '50V'   | '10%'     | 'C0603'     | 'X7R'     | 'CH4156K1901'(!)   = ''              | ''                 | ''       | 'CH4156K1901'    |'C0603'| '(SMC0603AW)'                                                        | '0.15UF'   | '50V'         | '10%'    | 'DISCRETE' | 'CAP CHIP 0.15U 50V(10%,X7R,0603)'                             | 'CHIP0603'     | ''          | ''   | '20220512'
 '0.15UF'   | '50V'   | '10%'     | 'C0603'     | 'EMPTY'   | 'CH4156K1901'(!)   = ''              | ''                 | ''       | 'CH4156K1901'    |'C0603'| '(SMC0603AW)'                                                        | 'NA'       | '50V'         | '10%'    | 'IO'       | 'CAP CHIP 0.15U 50V(10%,X7R,0603)'                             | 'CHIP0603'     | ''          | ''   | '20220512'
 '2.2UF'    | '16V'   | '20%'     | 'C0402'     | 'X6S'     | 'CH5223MEB01'(!)   = ''              | ''                 | ''       | 'CH5223MEB01'    |'C0402'| '(C0402-0201)'                                                       | '2.2UF'    | '16V'         | '20%'    | 'DISCRETE' | 'CAP CHIP 2.2U 16V(+-20%,X6S,0402)MUR'                         | 'CHIP0402'     | ''          | ''   | '20220518'
 '2.2UF'    | '16V'   | '20%'     | 'C0402'     | 'EMPTY'   | 'CH5223MEB01'(!)   = ''              | ''                 | ''       | 'CH5223MEB01'    |'C0402'| '(C0402-0201)'                                                       | 'NA'       | '16V'         | '20%'    | 'IO'       | 'CAP CHIP 2.2U 16V(+-20%,X6S,0402)MUR'                         | 'CHIP0402'     | ''          | ''   | '20220518'
 '0.01UF'   | '2KV'   | '10%'     | 'C1812'     | 'X7R'     | 'CH310IK1402'(!)   = ''              | ''                 | ''       | 'CH310IK1402'    |'C1812XC_H111'| '(SMC1812AW)'                                                        | '0.01UF'   | '2KV'         | '10%'    | 'DISCRETE' | 'CAP CHIP 0.01U 2KV(+-10%,X7R,1812)H2.5'                       | 'CHIP1812'     | ''          | ''   | '20220520'
 '0.01UF'   | '2KV'   | '10%'     | 'C1812'     | 'EMPTY'   | 'CH310IK1402'(!)   = ''              | ''                 | ''       | 'CH310IK1402'    |'C1812XC_H111'| '(SMC1812AW)'                                                        | 'NA'       | '2KV'         | '10%'    | 'IO'       | 'CAP CHIP 0.01U 2KV(+-10%,X7R,1812)H2.5'                       | 'CHIP1812'     | ''          | ''   | '20220520'
 '1500PF'   | '50V'   | '2%'      | 'C0402'     | 'C0G'     | 'CH2156G0B01'(!)   = ''              | ''                 | ''       | 'CH2156G0B01'    |'C0402'| '(C0402-0201)'                                                       | '1500PF'   | '50V'         | '2%'     | 'DISCRETE' | 'CAP CHIP 1500PF 50V(+-2%,C0G,0402)MUR'                        | 'CHIP0402'     | ''          | ''   | '20220520'
 '1500PF'   | '50V'   | '2%'      | 'C0402'     | 'EMPTY'   | 'CH2156G0B01'(!)   = ''              | ''                 | ''       | 'CH2156G0B01'    |'C0402'| '(C0402-0201)'                                                       | 'NA'       | '50V'         | '2%'     | 'IO'       | 'CAP CHIP 1500PF 50V(+-2%,C0G,0402)MUR'                        | 'CHIP0402'     | ''          | ''   | '20220520'
 '47UF'     | '4V'    | '20%'     | 'C0603'     | 'X6S'     | 'CH647KME900'(!)   = 'End of Design' | 'Comp-Approve'     | ''       | 'CH647KME900'    |'C0603_H40'| '(C0603_BHS-SP)'                                                     | '47UF'     | '4V'          | '20%'    | 'DISCRETE' | 'CAP CHIP 47U 4V(+-20%,X6S,0603)'                              | 'CHIP0603'     | ''          | ''   | '20220523'
 '47UF'     | '4V'    | '20%'     | 'C0603'     | 'EMPTY'   | 'CH647KME900'(!)   = 'End of Design' | 'Comp-Approve'     | ''       | 'CH647KME900'    |'C0603_H40'| '(C0603_BHS-SP)'                                                     | 'NA'       | '4V'          | '20%'    | 'IO'       | 'CAP CHIP 47U 4V(+-20%,X6S,0603)'                              | 'CHIP0603'     | ''          | ''   | '20220523'
 '15PF'     | '25V'   | '5%'      | 'C0201'     | 'C0G'     | 'CH0154J0E13'(!)   = ''              | ''                 | ''       | 'CH0154J0E13'    |'C0201'| '(SMC0201AW)'                                                        | '15PF'     | '25V'         | '5%'     | 'DISCRETE' | 'CAP CHIP 15P 25V(+-5%,C0G,0201)MUR SELA'                      | 'CHIP0201'     | ''          | ''   | '20220608'
 '15PF'     | '25V'   | '5%'      | 'C0201'     | 'EMPTY'   | 'CH0154J0E13'(!)   = ''              | ''                 | ''       | 'CH0154J0E13'    |'C0201'| '(SMC0201AW)'                                                        | 'NA'       | '25V'         | '5%'     | 'IO'       | 'CAP CHIP 15P 25V(+-5%,C0G,0201)MUR SELA'                      | 'CHIP0201'     | ''          | ''   | '20220608'
 '18PF'     | '50V'   | '2%'      | 'C0201'     | 'C0G'     | 'CH0186G0E01'(!)   = ''              | ''                 | ''       | 'CH0186G0E01'    |'C0201'| '(SMC0201AW)'                                                        | '18PF'     | '50V'         | '2%'     | 'DISCRETE' | 'CAP CHIP 18PF 50V(+-2%,C0G,0201)MUR'                          | 'CHIP0201'     | ''          | ''   | '20220608'
 '18PF'     | '50V'   | '2%'      | 'C0201'     | 'EMPTY'   | 'CH0186G0E01'(!)   = ''              | ''                 | ''       | 'CH0186G0E01'    |'C0201'| '(SMC0201AW)'                                                        | 'NA'       | '50V'         | '2%'     | 'IO'       | 'CAP CHIP 18PF 50V(+-2%,C0G,0201)MUR'                          | 'CHIP0201'     | ''          | ''   | '20220608'
 '100PF'    | '25V'   | '5%'      | 'C0402'     | 'C0G'     | 'CH1104J0B00'(!)   = ''              | ''                 | ''       | 'CH1104J0B00'    |'C0402'| '(C0402-0201)'                                                       | '100PF'    | '25V'         | '5%'     | 'DISCRETE' | 'CAP CHIP 100P 25V(+-5%,C0G,0402)'                             | 'CHIP0402'     | ''          | ''   | '20220608'
 '100PF'    | '25V'   | '5%'      | 'C0402'     | 'EMPTY'   | 'CH1104J0B00'(!)   = ''              | ''                 | ''       | 'CH1104J0B00'    |'C0402'| '(C0402-0201)'                                                       | 'NA'       | '25V'         | '5%'     | 'IO'       | 'CAP CHIP 100P 25V(+-5%,C0G,0402)'                             | 'CHIP0402'     | ''          | ''   | '20220608'
 '0.1UF'    | '16V'   | '10%'     | 'C0402'     | 'X5R'     | 'CH4103K9B06'(!)   = ''              | ''                 | ''       | 'CH4103K9B06'    |'C0402'| '(C0402-0201)'                                                       | '0.1UF'    | '16V'         | '10%'    | 'DISCRETE' | 'CAP CHIP 0.1U 16V(+-10%,X5R,0402)MUR'                         | 'CHIP0402'     | ''          | ''   | '20220608'
 '0.1UF'    | '16V'   | '10%'     | 'C0402'     | 'EMPTY'   | 'CH4103K9B06'(!)   = ''              | ''                 | ''       | 'CH4103K9B06'    |'C0402'| '(C0402-0201)'                                                       | 'NA'       | '16V'         | '10%'    | 'IO'       | 'CAP CHIP 0.1U 16V(+-10%,X5R,0402)MUR'                         | 'CHIP0402'     | ''          | ''   | '20220608'
 '1UF'      | '25V'   | '20%'     | 'C0402'     | 'X5R'     | 'CH5104M9B01'(!)   = ''              | ''                 | ''       | 'CH5104M9B01'    |'C0402'| '(C0402-0201)'                                                       | '1UF'      | '25V'         | '20%'    | 'DISCRETE' | 'CAP CHIP 1UF 25V(+-20%,X5R,0402)MUR'                          | 'CHIP0402'     | ''          | ''   | '20220608'
 '1UF'      | '25V'   | '20%'     | 'C0402'     | 'EMPTY'   | 'CH5104M9B01'(!)   = ''              | ''                 | ''       | 'CH5104M9B01'    |'C0402'| '(C0402-0201)'                                                       | 'NA'       | '25V'         | '20%'    | 'IO'       | 'CAP CHIP 1UF 25V(+-20%,X5R,0402)MUR'                          | 'CHIP0402'     | ''          | ''   | '20220608'
 '0.01UF'   | '10V'   | '10%'     | 'C0402'     | 'X7R'     | 'CH3102K1B00'(!)   = 'End of Design' | 'Comp-Approve'     | ''       | 'CH3102K1B00'    |'C0402'| '(C0402-0201)'                                                       | '0.01UF'   | '10V'         | '10%'    | 'DISCRETE' | 'CAP CHIP 0.01UF 10V(+-10%,X7R,0402)'                          | 'CHIP0402'     | ''          | ''   | '20220609'
 '0.01UF'   | '10V'   | '10%'     | 'C0402'     | 'EMPTY'   | 'CH3102K1B00'(!)   = 'End of Design' | 'Comp-Approve'     | ''       | 'CH3102K1B00'    |'C0402'| '(C0402-0201)'                                                       | 'NA'       | '10V'         | '10%'    | 'IO'       | 'CAP CHIP 0.01UF 10V(+-10%,X7R,0402)'                          | 'CHIP0402'     | ''          | ''   | '20220609'
 '47UF'     | '6.3V'  | '20%'     | 'C0805'     | 'X6S'     | 'CH6471MEA03'(!)   = ''              | ''                 | ''       | 'CH6471MEA03'    |'C0805_H57'| '(SMC0805AW)'                                                        | '47UF'     | '6.3V'        | '20%'    | 'DISCRETE' | 'CAP CHIP 47U 6.3V(+-20%,X6S,0805)MUR'                         | 'CHIP0805'     | ''          | ''   | '20220609'
 '47UF'     | '6.3V'  | '20%'     | 'C0805'     | 'EMPTY'   | 'CH6471MEA03'(!)   = ''              | ''                 | ''       | 'CH6471MEA03'    |'C0805_H57'| '(SMC0805AW)'                                                        | 'NA'       | '6.3V'        | '20%'    | 'IO'       | 'CAP CHIP 47U 6.3V(+-20%,X6S,0805)MUR'                         | 'CHIP0805'     | ''          | ''   | '20220609'
 '100UF'    | '4V'    | '20%'     | 'C0805'     | 'X5R'     | 'CH710KM9A01'(!)   = ''              | ''                 | ''       | 'CH710KM9A01'    |'C0805_H61'| '(SMC0805AW)'                                                        | '100UF'    | '4V'          | '20%'    | 'DISCRETE' | 'CAP CHIP 100U 4V(+-20%,X5R,0805)MUR'                          | 'CHIP0805'     | ''          | ''   | '20220609'
 '100UF'    | '4V'    | '20%'     | 'C0805'     | 'EMPTY'   | 'CH710KM9A01'(!)   = ''              | ''                 | ''       | 'CH710KM9A01'    |'C0805_H61'| '(SMC0805AW)'                                                        | 'NA'       | '4V'          | '20%'    | 'IO'       | 'CAP CHIP 100U 4V(+-20%,X5R,0805)MUR'                          | 'CHIP0805'     | ''          | ''   | '20220609'
 '47UF'     | '10V'   | '20%'     | 'C0805'     | 'X5R'     | 'CH6472M9A02'(!)   = ''              | ''                 | ''       | 'CH6472M9A02'    |'C0805_H61'| '(SMC0805AW)'                                                        | '47UF'     | '10V'         | '20%'    | 'DISCRETE' | 'CAP CHIP 47U 10V(+-20%,X5R,0805)MUR'                          | 'CHIP0805'     | ''          | ''   | '20220609'
 '47UF'     | '10V'   | '20%'     | 'C0805'     | 'EMPTY'   | 'CH6472M9A02'(!)   = ''              | ''                 | ''       | 'CH6472M9A02'    |'C0805_H61'| '(SMC0805AW)'                                                        | 'NA'       | '10V'         | '20%'    | 'IO'       | 'CAP CHIP 47U 10V(+-20%,X5R,0805)MUR'                          | 'CHIP0805'     | ''          | ''   | '20220609'
 '0.1UF'    | '100V'  | '10%'     | 'C0603'     | 'X7R'     | 'CH4108K1909'(!)   = ''              | ''                 | ''       | 'CH4108K1909'    |'C0603'| '(SMC0603AW)'                                                        | '0.1UF'    | '100V'        | '10%'    | 'DISCRETE' | 'CAP CHIP 0.1U 100V(+-10%,X7R,0603)MUR'                        | 'CHIP0603'     | ''          | ''   | '20220609'
 '0.1UF'    | '100V'  | '10%'     | 'C0603'     | 'EMPTY'   | 'CH4108K1909'(!)   = ''              | ''                 | ''       | 'CH4108K1909'    |'C0603'| '(SMC0603AW)'                                                        | 'NA'       | '100V'        | '10%'    | 'IO'       | 'CAP CHIP 0.1U 100V(+-10%,X7R,0603)MUR'                        | 'CHIP0603'     | ''          | ''   | '20220609'
 '15PF'     | '25V'   | '5%'      | 'C0201'     | 'C0G'     | 'CH0154J0E22'(!)   = ''              | ''                 | ''       | 'CH0154J0E22'    |'C0201'| '(SMC0201AW)'                                                        | '15PF'     | '25V'         | '5%'     | 'DISCRETE' | 'CAP CHIP 15P 25V(+-5%,C0G,0201)MUR'                           | 'CHIP0201'     | ''          | ''   | '20220620'
 '15PF'     | '25V'   | '5%'      | 'C0201'     | 'EMPTY'   | 'CH0154J0E22'(!)   = ''              | ''                 | ''       | 'CH0154J0E22'    |'C0201'| '(SMC0201AW)'                                                        | 'NA'       | '25V'         | '5%'     | 'IO'       | 'CAP CHIP 15P 25V(+-5%,C0G,0201)MUR'                           | 'CHIP0201'     | ''          | ''   | '20220620'
 '1UF'      | '25V'   | '10%'     | 'C0402'     | 'X5R'     | 'CH5104K9B15'(!)   = ''              | ''                 | ''       | 'CH5104K9B15'    |'C0402'| '(C0402-0201)'                                                       | '1UF'      | '25V'         | '10%'    | 'DISCRETE' | 'CAP CHIP 1UF 25V(+-10%,X5R,0402)MUR'                          | 'CHIP0402'     | ''          | ''   | '20220620'
 '1UF'      | '25V'   | '10%'     | 'C0402'     | 'EMPTY'   | 'CH5104K9B15'(!)   = ''              | ''                 | ''       | 'CH5104K9B15'    |'C0402'| '(C0402-0201)'                                                       | 'NA'       | '25V'         | '10%'    | 'IO'       | 'CAP CHIP 1UF 25V(+-10%,X5R,0402)MUR'                          | 'CHIP0402'     | ''          | ''   | '20220620'
 '0.1NF'    | '25V'   | '5%'      | 'C0201'     | 'C0G'     | 'CH1104J0E09'(!)   = ''              | ''                 | ''       | 'CH1104J0E09'    |'C0201'| '(SMC0201AW)'                                                        | '0.1NF'    | '25V'         | '5%'     | 'DISCRETE' | 'CAP CHIP 0.1NF 25V(+-5%,C0G,0201)MUR'                         | 'CHIP0201'     | ''          | ''   | '20220621'
 '0.1NF'    | '25V'   | '5%'      | 'C0201'     | 'EMPTY'   | 'CH1104J0E09'(!)   = ''              | ''                 | ''       | 'CH1104J0E09'    |'C0201'| '(SMC0201AW)'                                                        | 'NA'       | '25V'         | '5%'     | 'IO'       | 'CAP CHIP 0.1NF 25V(+-5%,C0G,0201)MUR'                         | 'CHIP0201'     | ''          | ''   | '20220621'
 '1500PF'   | '50V'   | '10%'     | 'C0402'     | 'X7R'     | 'CH2156K1B14'(!)   = ''              | ''                 | ''       | 'CH2156K1B14'    |'C0402'| '(C0402-0201)'                                                       | '1500PF'   | '50V'         | '10%'    | 'DISCRETE' | 'CAP CHIP 1500PF 50V(+-10%,X7R,0402)YGO'                       | 'CHIP0402'     | ''          | ''   | '20220621'
 '1500PF'   | '50V'   | '10%'     | 'C0402'     | 'EMPTY'   | 'CH2156K1B14'(!)   = ''              | ''                 | ''       | 'CH2156K1B14'    |'C0402'| '(C0402-0201)'                                                       | 'NA'       | '50V'         | '10%'    | 'IO'       | 'CAP CHIP 1500PF 50V(+-10%,X7R,0402)YGO'                       | 'CHIP0402'     | ''          | ''   | '20220621'
 '0.01UF'   | '10V'   | '10%'     | 'C0402'     | 'X7R'     | 'CH3102K1B06'(!)   = ''              | ''                 | ''       | 'CH3102K1B06'    |'C0402'| '(C0402_OCTAGONXA,C0402-0201)'                                       | '0.01UF'   | '10V'         | '10%'    | 'DISCRETE' | 'CAP CHIP 0.01UF 10V(+-10%,X7R,0402)YGO'                       | 'CHIP0402'     | ''          | ''   | '20220621'
 '0.01UF'   | '10V'   | '10%'     | 'C0402'     | 'EMPTY'   | 'CH3102K1B06'(!)   = ''              | ''                 | ''       | 'CH3102K1B06'    |'C0402'| '(C0402_OCTAGONXA,C0402-0201)'                                       | 'NA'       | '10V'         | '10%'    | 'IO'       | 'CAP CHIP 0.01UF 10V(+-10%,X7R,0402)YGO'                       | 'CHIP0402'     | ''          | ''   | '20220621'
 '2.2PF'    | '50V'   | '0.1PF'   | 'C0402'     | 'NPO'     | 'CH-226B0B02'(!)   = ''              | ''                 | ''       | 'CH-226B0B02'    |'C0402'| '(C0402-0201)'                                                       | '2.2PF'    | '50V'         | '0.1PF'  | 'DISCRETE' | 'CAP CHIP 2.2P 50V (+-0.1P,NPO,0402)MUR'                       | 'CHIP0402'     | ''          | ''   | '20220621'
 '2.2PF'    | '50V'   | '0.1PF'   | 'C0402'     | 'EMPTY'   | 'CH-226B0B02'(!)   = ''              | ''                 | ''       | 'CH-226B0B02'    |'C0402'| '(C0402-0201)'                                                       | 'NA'       | '50V'         | '0.1PF'  | 'IO'       | 'CAP CHIP 2.2P 50V (+-0.1P,NPO,0402)MUR'                       | 'CHIP0402'     | ''          | ''   | '20220621'
 '3900PF'   | '50V'   | '10%'     | 'C0402'     | 'X7R'     | 'CH2396K1B07'(!)   = ''              | ''                 | ''       | 'CH2396K1B07'    |'C0402'| '(C0402-0201)'                                                       | '3900PF'   | '50V'         | '10%'    | 'DISCRETE' | 'CAP CHIP 3900P 50V(+-10%,X7R,0402)MUR'                        | 'CHIP0402'     | ''          | ''   | '20220622'
 '3900PF'   | '50V'   | '10%'     | 'C0402'     | 'EMPTY'   | 'CH2396K1B07'(!)   = ''              | ''                 | ''       | 'CH2396K1B07'    |'C0402'| '(C0402-0201)'                                                       | 'NA'       | '50V'         | '10%'    | 'IO'       | 'CAP CHIP 3900P 50V(+-10%,X7R,0402)MUR'                        | 'CHIP0402'     | ''          | ''   | '20220622'
 '0.22UF'   | '6.3V'  | '20%'     | 'C0201'     | 'X6S'     | 'CH4221MEE03'(!)   = ''              | ''                 | ''       | 'CH4221MEE03'    |'C0201'| '(SMC0201AW)'                                                        | '0.22UF'   | '6.3V'        | '20%'    | 'DISCRETE' | 'CAP CHIP 0.22UF 6.3V(20%,X6S,0201)MUR'                        | 'CHIP0201'     | ''          | ''   | '20220623'
 '0.22UF'   | '6.3V'  | '20%'     | 'C0201'     | 'EMPTY'   | 'CH4221MEE03'(!)   = ''              | ''                 | ''       | 'CH4221MEE03'    |'C0201'| '(SMC0201AW)'                                                        | 'NA'       | '6.3V'        | '20%'    | 'IO'       | 'CAP CHIP 0.22UF 6.3V(20%,X6S,0201)MUR'                        | 'CHIP0201'     | ''          | ''   | '20220623'
 '0.22UF'   | '6.3V'  | '20%'     | 'C0201'     | 'X6S'     | 'CH4221MEE04'(!)   = ''              | ''                 | ''       | 'CH4221MEE04'    |'C0201'| '(SMC0201AW)'                                                        | '0.22UF'   | '6.3V'        | '20%'    | 'DISCRETE' | 'CAP CHIP 0.22UF 6.3V(20%,X6S,0201)TAY'                        | 'CHIP0201'     | ''          | ''   | '20220623'
 '0.22UF'   | '6.3V'  | '20%'     | 'C0201'     | 'EMPTY'   | 'CH4221MEE04'(!)   = ''              | ''                 | ''       | 'CH4221MEE04'    |'C0201'| '(SMC0201AW)'                                                        | 'NA'       | '6.3V'        | '20%'    | 'IO'       | 'CAP CHIP 0.22UF 6.3V(20%,X6S,0201)TAY'                        | 'CHIP0201'     | ''          | ''   | '20220623'
 '0.015UF'  | '16V'   | '20%'     | 'C0402'     | 'X7R'     | 'CH3153M1B01'(!)   = ''              | ''                 | ''       | 'CH3153M1B01'    |'C0402'| '(C0402-0201)'                                                       | '0.015UF'  | '16V'         | '20%'    | 'DISCRETE' | 'CAP CHIP 0.015U 16V(+-20%,X7R,0402)YGO'                       | 'CHIP0402'     | ''          | ''   | '20220624'
 '0.015UF'  | '16V'   | '20%'     | 'C0402'     | 'EMPTY'   | 'CH3153M1B01'(!)   = ''              | ''                 | ''       | 'CH3153M1B01'    |'C0402'| '(C0402-0201)'                                                       | 'NA'       | '16V'         | '20%'    | 'IO'       | 'CAP CHIP 0.015U 16V(+-20%,X7R,0402)YGO'                       | 'CHIP0402'     | ''          | ''   | '20220624'
 '3300PF'   | '50V'   | '5%'      | 'C0402'     | 'X7R'     | 'CH2336J1B05'(!)   = ''              | ''                 | ''       | 'CH2336J1B05'    |'C0402'| '(C0402-0201)'                                                       | '3300PF'   | '50V'         | '5%'     | 'DISCRETE' | 'CAP CHIP 3300P 50V(+-5%,X7R,0402)MUR'                         | 'CHIP0402'     | ''          | ''   | '20220624'
 '3300PF'   | '50V'   | '5%'      | 'C0402'     | 'EMPTY'   | 'CH2336J1B05'(!)   = ''              | ''                 | ''       | 'CH2336J1B05'    |'C0402'| '(C0402-0201)'                                                       | 'NA'       | '50V'         | '5%'     | 'IO'       | 'CAP CHIP 3300P 50V(+-5%,X7R,0402)MUR'                         | 'CHIP0402'     | ''          | ''   | '20220624'
 '3300PF'   | '50V'   | '5%'      | 'C0402'     | 'X7R'     | 'CH2336J1B07'(!)   = ''              | ''                 | ''       | 'CH2336J1B07'    |'C0402'| '(C0402-0201)'                                                       | '3300PF'   | '50V'         | '5%'     | 'DISCRETE' | 'CAP CHIP 3300P 50V(+-5%,X7R,0402)YGO'                         | 'CHIP0402'     | ''          | ''   | '20220630'
 '3300PF'   | '50V'   | '5%'      | 'C0402'     | 'EMPTY'   | 'CH2336J1B07'(!)   = ''              | ''                 | ''       | 'CH2336J1B07'    |'C0402'| '(C0402-0201)'                                                       | 'NA'       | '50V'         | '5%'     | 'IO'       | 'CAP CHIP 3300P 50V(+-5%,X7R,0402)YGO'                         | 'CHIP0402'     | ''          | ''   | '20220630'
 '2.2UF'    | '25V'   | '10%'     | 'C0402'     | 'X5R'     | 'CH5224K9B06'(!)   = ''              | ''                 | ''       | 'CH5224K9B06'    |'C0402_H28'| '(C0402-0201_H28)'                                                   | '2.2UF'    | '25V'         | '10%'    | 'DISCRETE' | 'CAP CHIP 2.2U 25V(+-10%,X5R,0402)MUR'                         | 'CHIP0402'     | ''          | ''   | '20220704'
 '2.2UF'    | '25V'   | '10%'     | 'C0402'     | 'EMPTY'   | 'CH5224K9B06'(!)   = ''              | ''                 | ''       | 'CH5224K9B06'    |'C0402_H28'| '(C0402-0201_H28)'                                                   | 'NA'       | '25V'         | '10%'    | 'IO'       | 'CAP CHIP 2.2U 25V(+-10%,X5R,0402)MUR'                         | 'CHIP0402'     | ''          | ''   | '20220704'
 '2.2UF'    | '25V'   | '10%'     | 'C0402'     | 'X5R'     | 'CH5224K9B07'(!)   = ''              | ''                 | ''       | 'CH5224K9B07'    |'C0402_H28'| '(C0402-0201_H28)'                                                   | '2.2UF'    | '25V'         | '10%'    | 'DISCRETE' | 'CAP CHIP 2.2U 25V(+-10%,X5R,0402)SAM'                         | 'CHIP0402'     | ''          | ''   | '20220705'
 '2.2UF'    | '25V'   | '10%'     | 'C0402'     | 'EMPTY'   | 'CH5224K9B07'(!)   = ''              | ''                 | ''       | 'CH5224K9B07'    |'C0402_H28'| '(C0402-0201_H28)'                                                   | 'NA'       | '25V'         | '10%'    | 'IO'       | 'CAP CHIP 2.2U 25V(+-10%,X5R,0402)SAM'                         | 'CHIP0402'     | ''          | ''   | '20220705'
 '2.2UF'    | '25V'   | '10%'     | 'C0402'     | 'X5R'     | 'CH5224K9B08'(!)   = ''              | ''                 | ''       | 'CH5224K9B08'    |'C0402_H28'| '(C0402-0201_H28)'                                                   | '2.2UF'    | '25V'         | '10%'    | 'DISCRETE' | 'CAP CHIP 2.2U 25V(+-10%,X5R,0402)WTC'                         | 'CHIP0402'     | ''          | ''   | '20220705'
 '2.2UF'    | '25V'   | '10%'     | 'C0402'     | 'EMPTY'   | 'CH5224K9B08'(!)   = ''              | ''                 | ''       | 'CH5224K9B08'    |'C0402_H28'| '(C0402-0201_H28)'                                                   | 'NA'       | '25V'         | '10%'    | 'IO'       | 'CAP CHIP 2.2U 25V(+-10%,X5R,0402)WTC'                         | 'CHIP0402'     | ''          | ''   | '20220705'
 '2.2UF'    | '6.3V'  | '20%'     | 'C0201'     | 'X6S'     | 'CH5221MEE00'(!)   = ''              | ''                 | ''       | 'CH5221MEE00'    |'C0201_H22'| '(C0201-0402_H22)'                                                   | '2.2UF'    | '6.3V'        | '20%'    | 'DISCRETE' | 'CAP CHIP 2.2UF 6.3V(+-20%,X6S,0201)'                          | 'CHIP0201'     | ''          | ''   | '20220715'
 '2.2UF'    | '6.3V'  | '20%'     | 'C0201'     | 'EMPTY'   | 'CH5221MEE00'(!)   = ''              | ''                 | ''       | 'CH5221MEE00'    |'C0201_H22'| '(C0201-0402_H22)'                                                   | 'NA'       | '6.3V'        | '20%'    | 'IO'       | 'CAP CHIP 2.2UF 6.3V(+-20%,X6S,0201)'                          | 'CHIP0201'     | ''          | ''   | '20220715'
 '820PF'    | '50V'   | '5%'      | 'C0402'     | 'NPO'     | 'CH1826J0B10'(!)   = ''              | ''                 | ''       | 'CH1826J0B10'    |'C0402'| '(C0402-0201)'                                                       | '820PF'    | '50V'         | '5%'     | 'DISCRETE' | 'CAP CHIP 820P 50V(+-5%,NPO,0402)MUR'                          | 'CHIP0402'     | ''          | ''   | '20220722'
 '820PF'    | '50V'   | '5%'      | 'C0402'     | 'EMPTY'   | 'CH1826J0B10'(!)   = ''              | ''                 | ''       | 'CH1826J0B10'    |'C0402'| '(C0402-0201)'                                                       | 'NA'       | '50V'         | '5%'     | 'IO'       | 'CAP CHIP 820P 50V(+-5%,NPO,0402)MUR'                          | 'CHIP0402'     | ''          | ''   | '20220722'
 '0.22UF'   | '10V'   | '10%'     | 'C0201'     | 'X5R'     | 'CH4222K9E00'(!)   = ''              | ''                 | ''       | 'CH4222K9E00'    |'C0201'| '(C0201_HOME-PLATE_H22)'                                             | '0.22UF'   | '10V'         | '10%'    | 'DISCRETE' | 'CAP CHIP 0.22UF 10V(+-10%,X5R,0201)MUR'                       | 'CHIP0201'     | ''          | ''   | '20220725'
 '0.22UF'   | '10V'   | '10%'     | 'C0201'     | 'EMPTY'   | 'CH4222K9E00'(!)   = ''              | ''                 | ''       | 'CH4222K9E00'    |'C0201'| '(C0201_HOME-PLATE_H22)'                                             | 'NA'       | '10V'         | '10%'    | 'IO'       | 'CAP CHIP 0.22UF 10V(+-10%,X5R,0201)MUR'                       | 'CHIP0201'     | ''          | ''   | '20220725'
 '22UF'     | '10V'   | '20%'     | 'C0603'     | 'X5R'     | 'CH6222M9905'(!)   = ''              | ''                 | ''       | 'CH6222M9905'    |'C0603_H40'| '(SMC0603AW)'                                                        | '22UF'     | '10V'         | '20%'    | 'DISCRETE' | 'CAP CHIP 22UF 10V(+-20%,X5R,0603)MUR'                         | 'CHIP0603'     | ''          | ''   | '20220725'
 '22UF'     | '10V'   | '20%'     | 'C0603'     | 'EMPTY'   | 'CH6222M9905'(!)   = ''              | ''                 | ''       | 'CH6222M9905'    |'C0603_H40'| '(SMC0603AW)'                                                        | 'NA'       | '10V'         | '20%'    | 'IO'       | 'CAP CHIP 22UF 10V(+-20%,X5R,0603)MUR'                         | 'CHIP0603'     | ''          | ''   | '20220725'
 '33NF'     | '50V'   | '10%'     | 'C0402'     | 'X7R'     | 'CH3336K1B00'(!)   = ''              | ''                 | ''       | 'CH3336K1B00'    |'C0402'| '(C0402-0201)'                                                       | '33NF'     | '50V'         | '10%'    | 'DISCRETE' | 'CAP CHIP 33NF 50V(+-10%,X7R,0402)'                            | 'CHIP0402'     | ''          | ''   | '20220816'
 '33NF'     | '50V'   | '10%'     | 'C0402'     | 'EMPTY'   | 'CH3336K1B00'(!)   = ''              | ''                 | ''       | 'CH3336K1B00'    |'C0402'| '(C0402-0201)'                                                       | 'NA'       | '50V'         | '10%'    | 'IO'       | 'CAP CHIP 33NF 50V(+-10%,X7R,0402)'                            | 'CHIP0402'     | ''          | ''   | '20220816'
 '0.022UF'  | '50V'   | '10%'     | 'C0402'     | 'X7R'     | 'CH3226K1B08'(!)   = ''              | ''                 | ''       | 'CH3226K1B08'    |'C0402'| '(C0402-0201)'                                                       | '0.022UF'  | '50V'         | '10%'    | 'DISCRETE' | 'CAP CHIP 0.022U 50V(+-10%,X7R,0402)MUR'                       | 'CHIP0402'     | ''          | ''   | '20220816'
 '0.022UF'  | '50V'   | '10%'     | 'C0402'     | 'EMPTY'   | 'CH3226K1B08'(!)   = ''              | ''                 | ''       | 'CH3226K1B08'    |'C0402'| '(C0402-0201)'                                                       | 'NA'       | '50V'         | '10%'    | 'IO'       | 'CAP CHIP 0.022U 50V(+-10%,X7R,0402)MUR'                       | 'CHIP0402'     | ''          | ''   | '20220816'
 '10UF'     | '100V'  | '10%'     | 'C1210'     | 'X7S'     | 'CH6108K6301'(!)   = ''              | ''                 | ''       | 'CH6108K6301'    |'C1210_GRM32E'| '(SMC1210AW)'                                                        | '10UF'     | '100V'        | '10%'    | 'DISCRETE' | 'CAP CHIP 10UF 100V(+-10%,X7S,1210)'                           | 'CHIP1210'     | ''          | ''   | '20220826'
 '10UF'     | '100V'  | '10%'     | 'C1210'     | 'EMPTY'   | 'CH6108K6301'(!)   = ''              | ''                 | ''       | 'CH6108K6301'    |'C1210_GRM32E'| '(SMC1210AW)'                                                        | 'NA'       | '100V'        | '10%'    | 'IO'       | 'CAP CHIP 10UF 100V(+-10%,X7S,1210)'                           | 'CHIP1210'     | ''          | ''   | '20220826'
 '2200PF'   | '50V'   | '5%'      | 'C0603'     | 'C0G'     | 'CH2226J0903'(!)   = ''              | ''                 | ''       | 'CH2226J0903'    |'C0603'| '(SMC0603AW)'                                                        | '2200PF'   | '50V'         | '5%'     | 'DISCRETE' | 'CAP CHIP 2200PF 50V(+-5%,C0G,0603)MUR'                        | 'CHIP0603'     | ''          | ''   | '20220826'
 '2200PF'   | '50V'   | '5%'      | 'C0603'     | 'EMPTY'   | 'CH2226J0903'(!)   = ''              | ''                 | ''       | 'CH2226J0903'    |'C0603'| '(SMC0603AW)'                                                        | 'NA'       | '50V'         | '5%'     | 'IO'       | 'CAP CHIP 2200PF 50V(+-5%,C0G,0603)MUR'                        | 'CHIP0603'     | ''          | ''   | '20220826'
 '1500PF'   | '50V'   | '5%'      | 'C0603'     | 'C0G'     | 'CH2156J0900'(!)   = ''              | ''                 | ''       | 'CH2156J0900'    |'C0603'| '(SMC0603AW)'                                                        | '1500PF'   | '50V'         | '5%'     | 'DISCRETE' | 'CAP CHIP 1500P 50V(+-5%,C0G,0603)MUR'                         | 'CHIP0603'     | ''          | ''   | '20220826'
 '1500PF'   | '50V'   | '5%'      | 'C0603'     | 'EMPTY'   | 'CH2156J0900'(!)   = ''              | ''                 | ''       | 'CH2156J0900'    |'C0603'| '(SMC0603AW)'                                                        | 'NA'       | '50V'         | '5%'     | 'IO'       | 'CAP CHIP 1500P 50V(+-5%,C0G,0603)MUR'                         | 'CHIP0603'     | ''          | ''   | '20220826'
 '4.7UF'    | '10V'   | '20%'     | 'C0402'     | 'X6S'     | 'CH5472MEB00'(!)   = ''              | ''                 | ''       | 'CH5472MEB00'    |'C0402_H28'| '(C0402-0201_H28)'                                                   | '4.7UF'    | '10V'         | '20%'    | 'DISCRETE' | 'CAP CHIP 4.7U 10V(+-20%,X6S,0402)'                            | 'CHIP0402'     | ''          | ''   | '20220826'
 '4.7UF'    | '10V'   | '20%'     | 'C0402'     | 'EMPTY'   | 'CH5472MEB00'(!)   = ''              | ''                 | ''       | 'CH5472MEB00'    |'C0402_H28'| '(C0402-0201_H28)'                                                   | 'NA'       | '10V'         | '20%'    | 'IO'       | 'CAP CHIP 4.7U 10V(+-20%,X6S,0402)'                            | 'CHIP0402'     | ''          | ''   | '20220826'
 '10NF'     | '10V'   | '10%'     | 'C0201'     | 'X7R'     | 'CH3102K1E06'(!)   = ''              | ''                 | ''       | 'CH3102K1E06'    |'C0201'| '(SMC0201AW)'                                                        | '10NF'     | '10V'         | '10%'    | 'DISCRETE' | 'CAP CHIP 10NF 10V(+-10%,X7R,0201)MUR'                         | 'CHIP0201'     | ''          | ''   | '20220901'
 '10NF'     | '10V'   | '10%'     | 'C0201'     | 'EMPTY'   | 'CH3102K1E06'(!)   = ''              | ''                 | ''       | 'CH3102K1E06'    |'C0201'| '(SMC0201AW)'                                                        | 'NA'       | '10V'         | '10%'    | 'IO'       | 'CAP CHIP 10NF 10V(+-10%,X7R,0201)MUR'                         | 'CHIP0201'     | ''          | ''   | '20220901'
 '4700PF'   | '2KV'   | '10%'     | 'C1812'     | 'X7R'     | 'CH247IK1400'(!)   = ''              | ''                 | ''       | 'CH247IK1400'    |'C1812XD'| '(SMC1812AW)'                                                        | '4700PF'   | '2KV'         | '10%'    | 'DISCRETE' | 'CAP CHIP 4700P 2KV(+-10%,X7R,1812)'                           | 'CHIP1812'     | ''          | ''   | '20220905'
 '4700PF'   | '2KV'   | '10%'     | 'C1812'     | 'EMPTY'   | 'CH247IK1400'(!)   = ''              | ''                 | ''       | 'CH247IK1400'    |'C1812XD'| '(SMC1812AW)'                                                        | 'NA'       | '2KV'         | '10%'    | 'IO'       | 'CAP CHIP 4700P 2KV(+-10%,X7R,1812)'                           | 'CHIP1812'     | ''          | ''   | '20220905'
 '0.01UF'   | '25V'   | '10%'     | 'C0402'     | 'X7R'     | 'CH3104K1B12'(!)   = ''              | ''                 | ''       | 'CH3104K1B12'    |'C0402'| '(C0402-0201)'                                                       | '0.01UF'   | '25V'         | '10%'    | 'DISCRETE' | 'CAP CHIP 0.01U 25V(+-10%,X7R,0402)SAM'                        | 'CHIP0402'     | ''          | ''   | '20220926'
 '0.01UF'   | '25V'   | '10%'     | 'C0402'     | 'EMPTY'   | 'CH3104K1B12'(!)   = ''              | ''                 | ''       | 'CH3104K1B12'    |'C0402'| '(C0402-0201)'                                                       | 'NA'       | '25V'         | '10%'    | 'IO'       | 'CAP CHIP 0.01U 25V(+-10%,X7R,0402)SAM'                        | 'CHIP0402'     | ''          | ''   | '20220926'
 '470PF'    | '50V'   | '10%'     | 'C0402'     | 'X7R'     | 'CH1476K1B14'(!)   = ''              | ''                 | ''       | 'CH1476K1B14'    |'C0402'| '(C0402-0201)'                                                       | '470PF'    | '50V'         | '10%'    | 'DISCRETE' | 'CAP CHIP 470P 50V(+-10%,X7R,0402)SAM'                         | 'CHIP0402'     | ''          | ''   | '20220926'
 '470PF'    | '50V'   | '10%'     | 'C0402'     | 'EMPTY'   | 'CH1476K1B14'(!)   = ''              | ''                 | ''       | 'CH1476K1B14'    |'C0402'| '(C0402-0201)'                                                       | 'NA'       | '50V'         | '10%'    | 'IO'       | 'CAP CHIP 470P 50V(+-10%,X7R,0402)SAM'                         | 'CHIP0402'     | ''          | ''   | '20220926'
 '22UF'     | '6.3V'  | '20%'     | 'C0805'     | 'X7T'     | 'CH6221MJA01'(!)   = 'End of Design' | 'Comp-Release Qty' | ''       | 'CH6221MJA01'    |'C0805_H57'| '(SMC0805AW)'                                                        | '22UF'     | '6.3V'        | '20%'    | 'DISCRETE' | 'CAP CHIP 22U 6.3V(+-20%,X7T,0805)'                            | 'CHIP0805'     | ''          | ''   | '20220929'
 '22UF'     | '6.3V'  | '20%'     | 'C0805'     | 'EMPTY'   | 'CH6221MJA01'(!)   = 'End of Design' | 'Comp-Release Qty' | ''       | 'CH6221MJA01'    |'C0805_H57'| '(SMC0805AW)'                                                        | 'NA'       | '6.3V'        | '20%'    | 'IO'       | 'CAP CHIP 22U 6.3V(+-20%,X7T,0805)'                            | 'CHIP0805'     | ''          | ''   | '20220929'
 '0.22UF'   | '6.3V'  | '10%'     | 'C0201'     | 'X6S'     | 'CH4221KEE04'(!)   = ''              | ''                 | ''       | 'CH4221KEE04'    |'C0201'| '(SMC0201AW)'                                                        | '0.22UF'   | '6.3V'        | '10%'    | 'DISCRETE' | 'CAP CHIP 0.22UF 6.3V(+-10%,X6S,0201)SAM'                      | 'CHIP0201'     | ''          | ''   | '20221017'
 '0.22UF'   | '6.3V'  | '10%'     | 'C0201'     | 'EMPTY'   | 'CH4221KEE04'(!)   = ''              | ''                 | ''       | 'CH4221KEE04'    |'C0201'| '(SMC0201AW)'                                                        | 'NA'       | '6.3V'        | '10%'    | 'IO'       | 'CAP CHIP 0.22UF 6.3V(+-10%,X6S,0201)SAM'                      | 'CHIP0201'     | ''          | ''   | '20221017'
 '1UF'      | '25V'   | '10%'     | 'C0603'     | 'X7R'     | 'CH5104K1909'(!)   = ''              | ''                 | ''       | 'CH5104K1909'    |'C0603'| '(SMC0603AW)'                                                        | '1UF'      | '25V'         | '10%'    | 'DISCRETE' | 'CAP CHIP 1U 25V(+-10%,X7R,0603)YGO'                           | 'CHIP0603'     | ''          | ''   | '20221017'
 '1UF'      | '25V'   | '10%'     | 'C0603'     | 'EMPTY'   | 'CH5104K1909'(!)   = ''              | ''                 | ''       | 'CH5104K1909'    |'C0603'| '(SMC0603AW)'                                                        | 'NA'       | '25V'         | '10%'    | 'IO'       | 'CAP CHIP 1U 25V(+-10%,X7R,0603)YGO'                           | 'CHIP0603'     | ''          | ''   | '20221017'
 '10PF'     | '50V'   | '2%'      | 'C0402'     | 'NPO'     | 'CH0106G0B07'(!)   = ''              | ''                 | ''       | 'CH0106G0B07'    |'C0402'| '(C0402-0201)'                                                       | '10PF'     | '50V'         | '2%'     | 'DISCRETE' | 'CAP CHIP 10P 50V(+-2%,NPO,0402)YGO'                           | 'CHIP0402'     | ''          | ''   | '20221017'
 '10PF'     | '50V'   | '2%'      | 'C0402'     | 'EMPTY'   | 'CH0106G0B07'(!)   = ''              | ''                 | ''       | 'CH0106G0B07'    |'C0402'| '(C0402-0201)'                                                       | 'NA'       | '50V'         | '2%'     | 'IO'       | 'CAP CHIP 10P 50V(+-2%,NPO,0402)YGO'                           | 'CHIP0402'     | ''          | ''   | '20221017'
 '10UF'     | '25V'   | '10%'     | 'C0805'     | 'X6S'     | 'CH6104KEA08'(!)   = ''              | ''                 | ''       | 'CH6104KEA08'    |'C0805_H57'| '(SMC0805AW)'                                                        | '10UF'     | '25V'         | '10%'    | 'DISCRETE' | 'CAP CHIP 10U 25V(+-10%,X6S,0805)TAY'                          | 'CHIP0805'     | ''          | ''   | '20221017'
 '10UF'     | '25V'   | '10%'     | 'C0805'     | 'EMPTY'   | 'CH6104KEA08'(!)   = ''              | ''                 | ''       | 'CH6104KEA08'    |'C0805_H57'| '(SMC0805AW)'                                                        | 'NA'       | '25V'         | '10%'    | 'IO'       | 'CAP CHIP 10U 25V(+-10%,X6S,0805)TAY'                          | 'CHIP0805'     | ''          | ''   | '20221017'
 '0.1UF'    | '10V'   | '10%'     | 'C0201'     | 'X7S'     | 'CH4102K6E00'(!)   = 'End of Design' | 'Comp-Approve'     | ''       | 'CH4102K6E00'    |'C0201'| '(SMC0201AW)'                                                        | '0.1UF'    | '10V'         | '10%'    | 'DISCRETE' | 'CAP CHIP 0.1U 10V(+-10%,X7S,0201)'                            | 'CHIP0201'     | ''          | ''   | '20221017'
 '0.1UF'    | '10V'   | '10%'     | 'C0201'     | 'EMPTY'   | 'CH4102K6E00'(!)   = 'End of Design' | 'Comp-Approve'     | ''       | 'CH4102K6E00'    |'C0201'| '(SMC0201AW)'                                                        | 'NA'       | '10V'         | '10%'    | 'IO'       | 'CAP CHIP 0.1U 10V(+-10%,X7S,0201)'                            | 'CHIP0201'     | ''          | ''   | '20221017'
 '12PF'     | '50V'   | '5%'      | 'C0402'     | 'C0G'     | 'CH0126J0B13'(!)   = ''              | ''                 | ''       | 'CH0126J0B13'    |'C0402'| '(C0402-0201)'                                                       | '12PF'     | '50V'         | '5%'     | 'DISCRETE' | 'CAP CHIP 12P 50V(+-5%,C0G,0402)MUR'                           | 'CHIP0402'     | ''          | ''   | '20221019'
 '12PF'     | '50V'   | '5%'      | 'C0402'     | 'EMPTY'   | 'CH0126J0B13'(!)   = ''              | ''                 | ''       | 'CH0126J0B13'    |'C0402'| '(C0402-0201)'                                                       | 'NA'       | '50V'         | '5%'     | 'IO'       | 'CAP CHIP 12P 50V(+-5%,C0G,0402)MUR'                           | 'CHIP0402'     | ''          | ''   | '20221019'
 '1NF'      | '25V'   | '10%'     | 'C0201'     | 'X7R'     | 'CH2104K1E04'(!)   = ''              | ''                 | ''       | 'CH2104K1E04'    |'C0201'| '(SMC0201AW)'                                                        | '1NF'      | '25V'         | '10%'    | 'DISCRETE' | 'CAP CHIP 1NF 25V(+-10%,X7R,0201)MUR'                          | 'CHIP0201'     | ''          | ''   | '20221019'
 '1NF'      | '25V'   | '10%'     | 'C0201'     | 'EMPTY'   | 'CH2104K1E04'(!)   = ''              | ''                 | ''       | 'CH2104K1E04'    |'C0201'| '(SMC0201AW)'                                                        | 'NA'       | '25V'         | '10%'    | 'IO'       | 'CAP CHIP 1NF 25V(+-10%,X7R,0201)MUR'                          | 'CHIP0201'     | ''          | ''   | '20221019'
 '1.8PF'    | '50V'   | '0.1PF'   | 'C0402'     | 'NPO'     | 'CH-186B0B03'(!)   = ''              | ''                 | ''       | 'CH-186B0B03'    |'C0402'| '(C0402-0201)'                                                       | '1.8PF'    | '50V'         | '0.1PF'  | 'DISCRETE' | 'CAP CHIP 1.8P 50V(+-0.1P,NPO,0402)MUR'                        | 'CHIP0402'     | ''          | ''   | '20221101'
 '1.8PF'    | '50V'   | '0.1PF'   | 'C0402'     | 'EMPTY'   | 'CH-186B0B03'(!)   = ''              | ''                 | ''       | 'CH-186B0B03'    |'C0402'| '(C0402-0201)'                                                       | 'NA'       | '50V'         | '0.1PF'  | 'IO'       | 'CAP CHIP 1.8P 50V(+-0.1P,NPO,0402)MUR'                        | 'CHIP0402'     | ''          | ''   | '20221101'
 '0.33UF'   | '6.3V'  | '10%'     | 'C0402'     | 'X6S'     | 'CH4331KEB02'(!)   = ''              | ''                 | ''       | 'CH4331KEB02'    |'C0402'| '(C0402-0201)'                                                       | '0.33UF'   | '6.3V'        | '10%'    | 'DISCRETE' | 'CAP CHIP 0.33UF 6.3V(10%,X6S,0402)MUR'                        | 'CHIP0402'     | ''          | ''   | '20221101'
 '0.33UF'   | '6.3V'  | '10%'     | 'C0402'     | 'EMPTY'   | 'CH4331KEB02'(!)   = ''              | ''                 | ''       | 'CH4331KEB02'    |'C0402'| '(C0402-0201)'                                                       | 'NA'       | '6.3V'        | '10%'    | 'IO'       | 'CAP CHIP 0.33UF 6.3V(10%,X6S,0402)MUR'                        | 'CHIP0402'     | ''          | ''   | '20221101'
 '10PF'     | '50V'   | '1%'      | 'C0402'     | 'NPO'     | 'CH0106F0B07'(!)   = ''              | ''                 | ''       | 'CH0106F0B07'    |'C0402'| '(C0402-0201)'                                                       | '10PF'     | '50V'         | '1%'     | 'DISCRETE' | 'CAP CHIP 10PF 50V(+-1%,NPO,0402)MUR'                          | 'CHIP0402'     | ''          | ''   | '20221101'
 '10PF'     | '50V'   | '1%'      | 'C0402'     | 'EMPTY'   | 'CH0106F0B07'(!)   = ''              | ''                 | ''       | 'CH0106F0B07'    |'C0402'| '(C0402-0201)'                                                       | 'NA'       | '50V'         | '1%'     | 'IO'       | 'CAP CHIP 10PF 50V(+-1%,NPO,0402)MUR'                          | 'CHIP0402'     | ''          | ''   | '20221101'
 '120PF'    | '50V'   | '5%'      | 'C0402'     | 'NPO'     | 'CH1126J0B14'(!)   = ''              | ''                 | ''       | 'CH1126J0B14'    |'C0402'| '(C0402-0201)'                                                       | '120PF'    | '50V'         | '5%'     | 'DISCRETE' | 'CAP CHIP 120P 50V(+-5%,NPO,0402)MUR'                          | 'CHIP0402'     | ''          | ''   | '20221101'
 '120PF'    | '50V'   | '5%'      | 'C0402'     | 'EMPTY'   | 'CH1126J0B14'(!)   = ''              | ''                 | ''       | 'CH1126J0B14'    |'C0402'| '(C0402-0201)'                                                       | 'NA'       | '50V'         | '5%'     | 'IO'       | 'CAP CHIP 120P 50V(+-5%,NPO,0402)MUR'                          | 'CHIP0402'     | ''          | ''   | '20221101'
 '2.2UF'    | '16V'   | '10%'     | 'C0402'     | 'X6S'     | 'CH5223KEB03'(!)   = ''              | ''                 | ''       | 'CH5223KEB03'    |'C0402_H28'| '(C0402-0201_H28)'                                                   | '2.2UF'    | '16V'         | '10%'    | 'DISCRETE' | 'CAP CHIP 2.2U 16V(+-10%,X6S,0402)MUR'                         | 'CHIP0402'     | ''          | ''   | '20221101'
 '2.2UF'    | '16V'   | '10%'     | 'C0402'     | 'EMPTY'   | 'CH5223KEB03'(!)   = ''              | ''                 | ''       | 'CH5223KEB03'    |'C0402_H28'| '(C0402-0201_H28)'                                                   | 'NA'       | '16V'         | '10%'    | 'IO'       | 'CAP CHIP 2.2U 16V(+-10%,X6S,0402)MUR'                         | 'CHIP0402'     | ''          | ''   | '20221101'
 '22UF'     | '16V'   | '20%'     | 'C0805'     | 'X6S'     | 'CH6223MEA05'(!)   = ''              | ''                 | ''       | 'CH6223MEA05'    |'C0805_H57'| '(SMC0805AW)'                                                        | '22UF'     | '16V'         | '20%'    | 'DISCRETE' | 'CAP CHIP 22U 16V(+-20%,X6S,0805)TAY'                          | 'CHIP0805'     | ''          | ''   | '20221130'
 '22UF'     | '16V'   | '20%'     | 'C0805'     | 'EMPTY'   | 'CH6223MEA05'(!)   = ''              | ''                 | ''       | 'CH6223MEA05'    |'C0805_H57'| '(SMC0805AW)'                                                        | 'NA'       | '16V'         | '20%'    | 'IO'       | 'CAP CHIP 22U 16V(+-20%,X6S,0805)TAY'                          | 'CHIP0805'     | ''          | ''   | '20221130'
 '22UF'     | '4V'    | '20%'     | 'C0805'     | 'X6S'     | 'CH622KMEA05'(!)   = ''              | ''                 | ''       | 'CH622KMEA05'    |'C0805_H57'| '(SMC0805AW)'                                                        | '22UF'     | '4V'          | '20%'    | 'DISCRETE' | 'CAP CHIP 22U 4V(+-20%,X6S,0805)TAY'                           | 'CHIP0805'     | ''          | ''   | '20221130'
 '22UF'     | '4V'    | '20%'     | 'C0805'     | 'EMPTY'   | 'CH622KMEA05'(!)   = ''              | ''                 | ''       | 'CH622KMEA05'    |'C0805_H57'| '(SMC0805AW)'                                                        | 'NA'       | '4V'          | '20%'    | 'IO'       | 'CAP CHIP 22U 4V(+-20%,X6S,0805)TAY'                           | 'CHIP0805'     | ''          | ''   | '20221130'
 '10UF'     | '25V'   | '10%'     | 'C0805'     | 'X6S'     | 'CH6104KEA04'(!)   = ''              | ''                 | ''       | 'CH6104KEA04'    |'C0805_H57'| '(SMC0805AW)'                                                        | '10UF'     | '25V'         | '10%'    | 'DISCRETE' | 'CAP CHIP 10U 25V(10%,X6S,0805,H1.25)SAM'                      | 'CHIP0805'     | ''          | ''   | '20221208'
 '10UF'     | '25V'   | '10%'     | 'C0805'     | 'EMPTY'   | 'CH6104KEA04'(!)   = ''              | ''                 | ''       | 'CH6104KEA04'    |'C0805_H57'| '(SMC0805AW)'                                                        | 'NA'       | '25V'         | '10%'    | 'IO'       | 'CAP CHIP 10U 25V(10%,X6S,0805,H1.25)SAM'                      | 'CHIP0805'     | ''          | ''   | '20221208'
 '1PF'      | '50V'   | '0.05PF'  | 'C0402'     | 'C0G'     | 'CH-106T0B04'(!)   = ''              | ''                 | ''       | 'CH-106T0B04'    |'C0402'| '(C0402-0201)'                                                       | '1PF'      | '50V'         | '0.05PF' | 'DISCRETE' | 'CAP CHIP 1P 50V(+-0.05P,C0G,0402)WTC'                         | 'CHIP0402'     | ''          | ''   | '20221223'
 '1PF'      | '50V'   | '0.05PF'  | 'C0402'     | 'EMPTY'   | 'CH-106T0B04'(!)   = ''              | ''                 | ''       | 'CH-106T0B04'    |'C0402'| '(C0402-0201)'                                                       | 'NA'       | '50V'         | '0.05PF' | 'IO'       | 'CAP CHIP 1P 50V(+-0.05P,C0G,0402)WTC'                         | 'CHIP0402'     | ''          | ''   | '20221223'
 '150PF'    | '50V'   | '5%'      | 'C0402'     | 'NPO'     | 'CH1156J0B07'(!)   = ''              | ''                 | ''       | 'CH1156J0B07'    |'C0402'| '(C0402-0201)'                                                       | '150PF'    | '50V'         | '5%'     | 'DISCRETE' | 'CAP CHIP 150P 50V(+-5%,NPO,0402)WTC'                          | 'CHIP0402'     | ''          | ''   | '20221223'
 '150PF'    | '50V'   | '5%'      | 'C0402'     | 'EMPTY'   | 'CH1156J0B07'(!)   = ''              | ''                 | ''       | 'CH1156J0B07'    |'C0402'| '(C0402-0201)'                                                       | 'NA'       | '50V'         | '5%'     | 'IO'       | 'CAP CHIP 150P 50V(+-5%,NPO,0402)WTC'                          | 'CHIP0402'     | ''          | ''   | '20221223'
 '10UF'     | '10V'   | '20%'     | 'C0402'     | 'X5R'     | 'CH6102M9B09'(!)   = ''              | ''                 | ''       | 'CH6102M9B09'    |'C0402_H28'| '(C0402-0201_H28)'                                                   | '10UF'     | '10V'         | '20%'    | 'DISCRETE' | 'CAP CHIP 10U 10V(+-20%, X5R,0402)MUR'                         | 'CHIP0402'     | ''          | ''   | '20221223'
 '10UF'     | '10V'   | '20%'     | 'C0402'     | 'EMPTY'   | 'CH6102M9B09'(!)   = ''              | ''                 | ''       | 'CH6102M9B09'    |'C0402_H28'| '(C0402-0201_H28)'                                                   | 'NA'       | '10V'         | '20%'    | 'IO'       | 'CAP CHIP 10U 10V(+-20%, X5R,0402)MUR'                         | 'CHIP0402'     | ''          | ''   | '20221223'
 '2.2UF'    | '25V'   | '10%'     | 'C0402'     | 'X6S'     | 'CH5224KEB00'(!)   = ''              | ''                 | ''       | 'CH5224KEB00'    |'C0402_H28'| '(C0402-0201_H28)'                                                   | '2.2UF'    | '25V'         | '10%'    | 'DISCRETE' | 'CAP CHIP 2.2U 25V(+-10%,X6S,0402)MUR'                         | 'CHIP0402'     | ''          | ''   | '20221226'
 '2.2UF'    | '25V'   | '10%'     | 'C0402'     | 'EMPTY'   | 'CH5224KEB00'(!)   = ''              | ''                 | ''       | 'CH5224KEB00'    |'C0402_H28'| '(C0402-0201_H28)'                                                   | 'NA'       | '25V'         | '10%'    | 'IO'       | 'CAP CHIP 2.2U 25V(+-10%,X6S,0402)MUR'                         | 'CHIP0402'     | ''          | ''   | '20221226'
 '3.9PF'    | '50V'   | '0.1PF'   | 'C0402'     | 'NP0'     | 'CH-396B0B01'(!)   = ''              | ''                 | ''       | 'CH-396B0B01'    |'C0402'| '(C0402-0201)'                                                       | '3.9PF'    | '50V'         | '0.1PF'  | 'DISCRETE' | 'CAP CHIP 3.9P 50V(+-0.1P,NP0,0402)WTC'                        | 'CHIP0402'     | ''          | ''   | '20221227'
 '3.9PF'    | '50V'   | '0.1PF'   | 'C0402'     | 'EMPTY'   | 'CH-396B0B01'(!)   = ''              | ''                 | ''       | 'CH-396B0B01'    |'C0402'| '(C0402-0201)'                                                       | 'NA'       | '50V'         | '0.1PF'  | 'IO'       | 'CAP CHIP 3.9P 50V(+-0.1P,NP0,0402)WTC'                        | 'CHIP0402'     | ''          | ''   | '20221227'
 '10PF'     | '50V'   | '1%'      | 'C0402'     | 'NPO'     | 'CH0106F0B08'(!)   = ''              | ''                 | ''       | 'CH0106F0B08'    |'C0402'| '(C0402-0201)'                                                       | '10PF'     | '50V'         | '1%'     | 'DISCRETE' | 'CAP CHIP 10PF 50V(+-1%,NPO,0402)WTC'                          | 'CHIP0402'     | ''          | ''   | '20230104'
 '10PF'     | '50V'   | '1%'      | 'C0402'     | 'EMPTY'   | 'CH0106F0B08'(!)   = ''              | ''                 | ''       | 'CH0106F0B08'    |'C0402'| '(C0402-0201)'                                                       | 'NA'       | '50V'         | '1%'     | 'IO'       | 'CAP CHIP 10PF 50V(+-1%,NPO,0402)WTC'                          | 'CHIP0402'     | ''          | ''   | '20230104'
 '1.8PF'    | '50V'   | '0.1PF'   | 'C0402'     | 'NPO'     | 'CH-186B0B05'(!)   = ''              | ''                 | ''       | 'CH-186B0B05'    |'C0402'| '(C0402-0201)'                                                       | '1.8PF'    | '50V'         | '0.1PF'  | 'DISCRETE' | 'CAP CHIP 1.8P 50V(+-0.1P,NPO,0402)WTC'                        | 'CHIP0402'     | ''          | ''   | '20230104'
 '1.8PF'    | '50V'   | '0.1PF'   | 'C0402'     | 'EMPTY'   | 'CH-186B0B05'(!)   = ''              | ''                 | ''       | 'CH-186B0B05'    |'C0402'| '(C0402-0201)'                                                       | 'NA'       | '50V'         | '0.1PF'  | 'IO'       | 'CAP CHIP 1.8P 50V(+-0.1P,NPO,0402)WTC'                        | 'CHIP0402'     | ''          | ''   | '20230104'
 '120PF'    | '50V'   | '5%'      | 'C0402'     | 'NPO'     | 'CH1126J0B09'(!)   = ''              | ''                 | ''       | 'CH1126J0B09'    |'C0402'| '(C0402-0201)'                                                       | '120PF'    | '50V'         | '5%'     | 'DISCRETE' | 'CAP CHIP 120P 50V(+-5%,NPO,0402)WTC'                          | 'CHIP0402'     | ''          | ''   | '20230104'
 '120PF'    | '50V'   | '5%'      | 'C0402'     | 'EMPTY'   | 'CH1126J0B09'(!)   = ''              | ''                 | ''       | 'CH1126J0B09'    |'C0402'| '(C0402-0201)'                                                       | 'NA'       | '50V'         | '5%'     | 'IO'       | 'CAP CHIP 120P 50V(+-5%,NPO,0402)WTC'                          | 'CHIP0402'     | ''          | ''   | '20230104'
 '0.33UF'   | '6.3V'  | '10%'     | 'C0402'     | 'X6S'     | 'CH4331KEB03'(!)   = ''              | ''                 | ''       | 'CH4331KEB03'    |'C0402'| '(C0402-0201)'                                                       | '0.33UF'   | '6.3V'        | '10%'    | 'DISCRETE' | 'CAP CHIP 0.33U 6.3V(+-10%,X6S,0402)API'                       | 'CHIP0402'     | ''          | ''   | '20230106'
 '0.33UF'   | '6.3V'  | '10%'     | 'C0402'     | 'EMPTY'   | 'CH4331KEB03'(!)   = ''              | ''                 | ''       | 'CH4331KEB03'    |'C0402'| '(C0402-0201)'                                                       | 'NA'       | '6.3V'        | '10%'    | 'IO'       | 'CAP CHIP 0.33U 6.3V(+-10%,X6S,0402)API'                       | 'CHIP0402'     | ''          | ''   | '20230106'
 '1000PF'   | '100V'  | '10%'     | 'C0402'     | 'X7R'     | 'CH2108K1B03'(!)   = ''              | ''                 | ''       | 'CH2108K1B03'    |'C0402_OCTAGONXA_BOUND22'| '(SMC0402AW)'                                                        | '1000PF'   | '100V'        | '10%'    | 'DISCRETE' | 'CAP CHIP 1000P 100V(+-10%,X7R,0402)MUR_OCTAGON'               | 'CHIP0402'     | ''          | ''   | '20230221'
 '1000PF'   | '100V'  | '10%'     | 'C0402'     | 'EMPTY'   | 'CH2108K1B03'(!)   = ''              | ''                 | ''       | 'CH2108K1B03'    |'C0402_OCTAGONXA_BOUND22'| '(SMC0402AW)'                                                        | 'NA'       | '100V'        | '10%'    | 'IO'       | 'CAP CHIP 1000P 100V(+-10%,X7R,0402)MUR_OCTAGON'               | 'CHIP0402'     | ''          | ''   | '20230221'
 '2.7PF'    | '50V'   | '0.1PF'   | 'C0402'     | 'NPO'     | 'CH-276B0B00'(!)   = ''              | ''                 | ''       | 'CH-276B0B00'    |'C0402'| '(C0402-0201)'                                                       | '2.7PF'    | '50V'         | '0.1PF'  | 'DISCRETE' | 'CAP CHIP 2.7P 50V(+-0.1P,NPO,0402)'                           | 'CHIP0402'     | ''          | ''   | '20230316'
 '2.7PF'    | '50V'   | '0.1PF'   | 'C0402'     | 'EMPTY'   | 'CH-276B0B00'(!)   = ''              | ''                 | ''       | 'CH-276B0B00'    |'C0402'| '(C0402-0201)'                                                       | 'NA'       | '50V'         | '0.1PF'  | 'IO'       | 'CAP CHIP 2.7P 50V(+-0.1P,NPO,0402)'                           | 'CHIP0402'     | ''          | ''   | '20230316'

END_PART

END.

